FILE_TYPE = LIBRARY_PARTS;
{ Packager-XL run on 14-Sep-2023 AT 16:11:04 }
primitive '74CBTLV3126PW-74CBTLV3126PW,SMLF,IC,AL003126K08';
  pin
    '2A':
      PIN_NUMBER='(5)';
      BIDIRECTIONAL='TRUE';
      INPUT_LOAD='(-0.01,0.01)';
      OUTPUT_LOAD='(1.0,-1.0)';
      PINUSE='BI';
    '3B':
      PIN_NUMBER='(8)';
      BIDIRECTIONAL='TRUE';
      INPUT_LOAD='(-0.01,0.01)';
      OUTPUT_LOAD='(1.0,-1.0)';
      PINUSE='BI';
    '1OE':
      PIN_NUMBER='(1)';
      INPUT_LOAD='(-0.01,0.01)';
      PINUSE='IN';
    '2OE':
      PIN_NUMBER='(4)';
      OUTPUT_LOAD='(1.0,-1.0)';
      PINUSE='OUT';
    '1B':
      PIN_NUMBER='(3)';
      BIDIRECTIONAL='TRUE';
      INPUT_LOAD='(-0.01,0.01)';
      OUTPUT_LOAD='(1.0,-1.0)';
      PINUSE='BI';
    '2B':
      PIN_NUMBER='(6)';
      BIDIRECTIONAL='TRUE';
      INPUT_LOAD='(-0.01,0.01)';
      OUTPUT_LOAD='(1.0,-1.0)';
      PINUSE='BI';
    '1A':
      PIN_NUMBER='(2)';
      PINUSE='POWER';
      NO_LOAD_CHECK='Both';
      NO_IO_CHECK='Both';
      NO_ASSERT_CHECK='TRUE';
      NO_DIR_CHECK='TRUE';
      ALLOW_CONNECT='TRUE';
    'GND':
      PIN_NUMBER='(7)';
      PINUSE='POWER';
      NO_LOAD_CHECK='Both';
      NO_IO_CHECK='Both';
      NO_ASSERT_CHECK='TRUE';
      NO_DIR_CHECK='TRUE';
      ALLOW_CONNECT='TRUE';
    '3A':
      PIN_NUMBER='(9)';
      BIDIRECTIONAL='TRUE';
      INPUT_LOAD='(-0.01,0.01)';
      OUTPUT_LOAD='(1.0,-1.0)';
      PINUSE='BI';
    '3OE':
      PIN_NUMBER='(10)';
      BIDIRECTIONAL='TRUE';
      INPUT_LOAD='(-0.01,0.01)';
      OUTPUT_LOAD='(1.0,-1.0)';
      PINUSE='BI';
    '4B':
      PIN_NUMBER='(11)';
      BIDIRECTIONAL='TRUE';
      INPUT_LOAD='(-0.01,0.01)';
      OUTPUT_LOAD='(1.0,-1.0)';
      PINUSE='BI';
    '4A':
      PIN_NUMBER='(12)';
      BIDIRECTIONAL='TRUE';
      INPUT_LOAD='(-0.01,0.01)';
      OUTPUT_LOAD='(1.0,-1.0)';
      PINUSE='BI';
    '4OE':
      PIN_NUMBER='(13)';
      BIDIRECTIONAL='TRUE';
      INPUT_LOAD='(-0.01,0.01)';
      OUTPUT_LOAD='(1.0,-1.0)';
      PINUSE='BI';
    'VCC':
      PIN_NUMBER='(14)';
      BIDIRECTIONAL='TRUE';
      INPUT_LOAD='(-0.01,0.01)';
      OUTPUT_LOAD='(1.0,-1.0)';
      PINUSE='BI';
  end_pin;
  body
      PART_NAME='74CBTLV3126PW';
      BODY_NAME='74CBTLV3126PW';
      JEDEC_TYPE='TSSOP14';
      PHYS_DES_PREFIX='U';
      CLASS='IC';
      STANDARD='';
      LIFECYCLE='';
      PART_NUMBER='AL003126K08';
      DESCRIPTION='IC OTHER(14P) 74CBTLV3126PW(TSSOP)';
      MANUFTR='NXP';
      MANUF_PN='74CBTLV3126PW';
      RD_CMPLS_LVL='EU(V1)';
      CMPLS_LVL='';
      FROM_PJ='S4L-CHARLES';
      DIP_SMD='';
      DATA='NXP_74CBTLV3126.pdf';
      EE_CHECK_LIST='';
      FP_ECN='';
      PSL='';
      CREATOR='';
      STATUS='';
      CREATEDAY='20130102';
      PARENT_PART_TYPE='74CBTLV3126PW';
      PARENT_PPT='74CBTLV3126PW';
      PARENT_PPT_PART='74CBTLV3126PW-74CBTLV3126PW,SMLF,IC,AL003126K08';
  end_body;
end_primitive;
primitive '74LV4052PW-74LV4052PW,SMLF,IC,ALLV4052K19';
  pin
    '2Y0':
      PIN_NUMBER='(1)';
      BIDIRECTIONAL='TRUE';
      INPUT_LOAD='(-0.01,0.01)';
      OUTPUT_LOAD='(1.0,-1.0)';
      PINUSE='BI';
    '2Y2':
      PIN_NUMBER='(2)';
      BIDIRECTIONAL='TRUE';
      INPUT_LOAD='(-0.01,0.01)';
      OUTPUT_LOAD='(1.0,-1.0)';
      PINUSE='BI';
    '2Z':
      PIN_NUMBER='(3)';
      BIDIRECTIONAL='TRUE';
      INPUT_LOAD='(-0.01,0.01)';
      OUTPUT_LOAD='(1.0,-1.0)';
      PINUSE='BI';
    '2Y3':
      PIN_NUMBER='(4)';
      BIDIRECTIONAL='TRUE';
      INPUT_LOAD='(-0.01,0.01)';
      OUTPUT_LOAD='(1.0,-1.0)';
      PINUSE='BI';
    '2Y1':
      PIN_NUMBER='(5)';
      BIDIRECTIONAL='TRUE';
      INPUT_LOAD='(-0.01,0.01)';
      OUTPUT_LOAD='(1.0,-1.0)';
      PINUSE='BI';
    'E_N':
      PIN_NUMBER='(6)';
      BIDIRECTIONAL='TRUE';
      INPUT_LOAD='(-0.01,0.01)';
      OUTPUT_LOAD='(1.0,-1.0)';
      PINUSE='BI';
    'VEE':
      PIN_NUMBER='(7)';
      PINUSE='POWER';
      NO_LOAD_CHECK='Both';
      NO_IO_CHECK='Both';
      NO_ASSERT_CHECK='TRUE';
      NO_DIR_CHECK='TRUE';
      ALLOW_CONNECT='TRUE';
    'GND':
      PIN_NUMBER='(8)';
      PINUSE='POWER';
      NO_LOAD_CHECK='Both';
      NO_IO_CHECK='Both';
      NO_ASSERT_CHECK='TRUE';
      NO_DIR_CHECK='TRUE';
      ALLOW_CONNECT='TRUE';
    'S1':
      PIN_NUMBER='(9)';
      BIDIRECTIONAL='TRUE';
      INPUT_LOAD='(-0.01,0.01)';
      OUTPUT_LOAD='(1.0,-1.0)';
      PINUSE='BI';
    'S0':
      PIN_NUMBER='(10)';
      BIDIRECTIONAL='TRUE';
      INPUT_LOAD='(-0.01,0.01)';
      OUTPUT_LOAD='(1.0,-1.0)';
      PINUSE='BI';
    '1Y3':
      PIN_NUMBER='(11)';
      BIDIRECTIONAL='TRUE';
      INPUT_LOAD='(-0.01,0.01)';
      OUTPUT_LOAD='(1.0,-1.0)';
      PINUSE='BI';
    '1Y0':
      PIN_NUMBER='(12)';
      BIDIRECTIONAL='TRUE';
      INPUT_LOAD='(-0.01,0.01)';
      OUTPUT_LOAD='(1.0,-1.0)';
      PINUSE='BI';
    '1Z':
      PIN_NUMBER='(13)';
      BIDIRECTIONAL='TRUE';
      INPUT_LOAD='(-0.01,0.01)';
      OUTPUT_LOAD='(1.0,-1.0)';
      PINUSE='BI';
    '1Y1':
      PIN_NUMBER='(14)';
      BIDIRECTIONAL='TRUE';
      INPUT_LOAD='(-0.01,0.01)';
      OUTPUT_LOAD='(1.0,-1.0)';
      PINUSE='BI';
    '1Y2':
      PIN_NUMBER='(15)';
      BIDIRECTIONAL='TRUE';
      INPUT_LOAD='(-0.01,0.01)';
      OUTPUT_LOAD='(1.0,-1.0)';
      PINUSE='BI';
    'VCC':
      PIN_NUMBER='(16)';
      PINUSE='POWER';
      NO_LOAD_CHECK='Both';
      NO_IO_CHECK='Both';
      NO_ASSERT_CHECK='TRUE';
      NO_DIR_CHECK='TRUE';
      ALLOW_CONNECT='TRUE';
  end_pin;
  body
      PART_NAME='74LV4052PW';
      BODY_NAME='74LV4052PW';
      PHYS_DES_PREFIX='U';
      CLASS='IC';
      STANDARD='';
      LIFECYCLE='';
      PART_NUMBER='ALLV4052K19';
      JEDEC_TYPE='TSSOP16_0-65_5X4-4XH';
      DESCRIPTION='IC OTHERS(16P)74LV4052PW(TSSOP)';
      MANUFTR='PHI';
      MANUF_PN='74LV4052PW';
      RD_CMPLS_LVL='EP';
      CMPLS_LVL='EP';
      FROM_PJ='A5W-JANE';
      DIP_SMD='';
      DATA='PHI_74LV4052PW.pdf';
      EE_CHECK_LIST='';
      FP_ECN='';
      PSL='';
      CREATOR='';
      STATUS='';
      MSD='NA';
      ESD_CDM='NA';
      ESD_HBM='NA';
      ESD_MM='NA';
      PIN_LENGTH_SHORT_PIN='0 MILS';
      PIN_LENGTH_LONG_PIN='0 MILS';
      CREATEDAY='20190711';
      PARENT_PART_TYPE='74LV4052PW';
      PARENT_PPT='74LV4052PW';
      PARENT_PPT_PART='74LV4052PW-74LV4052PW,SMLF,IC,ALLV4052K19';
  end_body;
end_primitive;
primitive '74LVC1G07GV-74LVC1G07GV,SMLF,IC,AL1G0007001';
  pin
    'VCC':
      PIN_NUMBER='(5)';
      PINUSE='POWER';
      NO_LOAD_CHECK='Both';
      NO_IO_CHECK='Both';
      NO_ASSERT_CHECK='TRUE';
      NO_DIR_CHECK='TRUE';
      ALLOW_CONNECT='TRUE';
    'A':
      PIN_NUMBER='(2)';
      INPUT_LOAD='(-0.01,0.01)';
      PINUSE='IN';
    'GND':
      PIN_NUMBER='(3)';
      PINUSE='POWER';
      NO_LOAD_CHECK='Both';
      NO_IO_CHECK='Both';
      NO_ASSERT_CHECK='TRUE';
      NO_DIR_CHECK='TRUE';
      ALLOW_CONNECT='TRUE';
    'Y':
      PIN_NUMBER='(4)';
      OUTPUT_TYPE='(OC,AND)';
      OUTPUT_LOAD='(1.0,*)';
      PINUSE='OCA';
    'NC1':
      PIN_NUMBER='(1)';
      OUTPUT_TYPE='(TS,TS)';
      INPUT_LOAD='(-0.01,0.01)';
      OUTPUT_LOAD='(1.0,-1.0)';
      PINUSE='TRI';
  end_pin;
  body
      PART_NAME='74LVC1G07GV';
      BODY_NAME='74LVC1G07GV';
      PHYS_DES_PREFIX='U';
      CLASS='IC';
      STANDARD='';
      LIFECYCLE='';
      PART_NUMBER='AL1G0007001';
      JEDEC_TYPE='SC-74A_2-9X1-5';
      DESCRIPTION='IC OTHER(5P) 74LVC1G07GV(SOT753)';
      MANUFTR='NXP';
      MANUF_PN='74LVC1G07GV';
      RD_CMPLS_LVL='EP(V1)';
      CMPLS_LVL='EP(V1)';
      FROM_PJ='S3D-ALAN';
      DIP_SMD='';
      DATA='NXP_74LVC1G07GV.pdf';
      EE_CHECK_LIST='';
      FP_ECN='74LVC1G07GV.msg';
      PSL='';
      CREATOR='';
      STATUS='';
      MSD='Level-1';
      ESD_CDM='NA';
      ESD_HBM='2000V';
      ESD_MM='200V';
      PIN_LENGTH_SHORT_PIN='0 MILS';
      PIN_LENGTH_LONG_PIN='0 MILS';
      CREATEDAY='20191122';
      PARENT_PART_TYPE='74LVC1G07GV';
      PARENT_PPT='74LVC1G07GV';
      PARENT_PPT_PART='74LVC1G07GV-74LVC1G07GV,SMLF,IC,AL1G0007001';
  end_body;
end_primitive;
primitive '74LVC1G08W57-74LVC1G08W5-7,SMLF,IC,AL1G0008020';
  pin
    'A':
      PIN_NUMBER='(1)';
      INPUT_LOAD='(-0.01,0.01)';
      PINUSE='IN';
    'B':
      PIN_NUMBER='(2)';
      INPUT_LOAD='(-0.01,0.01)';
      PINUSE='IN';
    'GND':
      PIN_NUMBER='(3)';
      PINUSE='POWER';
      NO_LOAD_CHECK='Both';
      NO_IO_CHECK='Both';
      NO_ASSERT_CHECK='TRUE';
      NO_DIR_CHECK='TRUE';
      ALLOW_CONNECT='TRUE';
    'Y':
      PIN_NUMBER='(4)';
      OUTPUT_LOAD='(1.0,-1.0)';
      PINUSE='OUT';
    'VCC':
      PIN_NUMBER='(5)';
      PINUSE='POWER';
      NO_LOAD_CHECK='Both';
      NO_IO_CHECK='Both';
      NO_ASSERT_CHECK='TRUE';
      NO_DIR_CHECK='TRUE';
      ALLOW_CONNECT='TRUE';
  end_pin;
  body
      PART_NAME='74LVC1G08W57';
      BODY_NAME='74LVC1G08W57';
      PHYS_DES_PREFIX='U';
      CLASS='IC';
      STANDARD='';
      LIFECYCLE='';
      PART_NUMBER='AL1G0008020';
      JEDEC_TYPE='SOT25-5_0-95_3X1-6';
      DESCRIPTION='IC OTHER(5P) 74LVC1G08W5-7(SOT25)';
      MANUFTR='DDS';
      MANUF_PN='74LVC1G08W5-7';
      RD_CMPLS_LVL='EP(V1)';
      CMPLS_LVL='EP(V1)';
      FROM_PJ='S6S-KYLE';
      DIP_SMD='';
      DATA='DDS_74LVC1G08W5-7.pdf';
      EE_CHECK_LIST='';
      FP_ECN='';
      PSL='';
      CREATOR='';
      STATUS='';
      MSD='';
      ESD_CDM='';
      ESD_HBM='';
      ESD_MM='';
      PIN_LENGTH_SHORT_PIN='0 MILS';
      PIN_LENGTH_LONG_PIN='0 MILS';
      CREATEDAY='20210604';
      PARENT_PART_TYPE='74LVC1G08W57';
      PARENT_PPT='74LVC1G08W57';
      PARENT_PPT_PART='74LVC1G08W57-74LVC1G08W5-7,SMLF,IC,AL1G0008020';
  end_body;
end_primitive;
primitive '74LVC1G126SE7-74LVC1G126SE-7,SMLF,IC,AL1G0126009';
  pin
    'A':
      PIN_NUMBER='(2)';
      INPUT_LOAD='(-0.01,0.01)';
      PINUSE='IN';
    'Y':
      PIN_NUMBER='(4)';
      OUTPUT_LOAD='(1.0,-1.0)';
      PINUSE='OUT';
    'VCC':
      PIN_NUMBER='(5)';
      PINUSE='POWER';
      NO_LOAD_CHECK='Both';
      NO_IO_CHECK='Both';
      NO_ASSERT_CHECK='TRUE';
      NO_DIR_CHECK='TRUE';
      ALLOW_CONNECT='TRUE';
    'GND':
      PIN_NUMBER='(3)';
      PINUSE='POWER';
      NO_LOAD_CHECK='Both';
      NO_IO_CHECK='Both';
      NO_ASSERT_CHECK='TRUE';
      NO_DIR_CHECK='TRUE';
      ALLOW_CONNECT='TRUE';
    'OE':
      PIN_NUMBER='(1)';
      INPUT_LOAD='(-0.01,0.01)';
      PINUSE='IN';
  end_pin;
  body
      PART_NAME='74LVC1G126SE7';
      BODY_NAME='74LVC1G126SE7';
      PHYS_DES_PREFIX='U';
      CLASS='IC';
      STANDARD='';
      LIFECYCLE='';
      PART_NUMBER='AL1G0126009';
      JEDEC_TYPE='SOT353_0-65_2X1-25';
      DESCRIPTION='IC OTHER(5P) 74LVC1G126SE-7 (SOT353)';
      MANUFTR='DDS';
      MANUF_PN='74LVC1G126SE-7';
      RD_CMPLS_LVL='EP(V1)';
      CMPLS_LVL='EP(V1)';
      FROM_PJ='F0C-IVES';
      DIP_SMD='';
      DATA='DDS_74LVC1G126SE-7.pdf';
      EE_CHECK_LIST='';
      FP_ECN='';
      PSL='';
      CREATOR='';
      STATUS='';
      MSD='';
      ESD_CDM='';
      ESD_HBM='';
      ESD_MM='';
      PIN_LENGTH_SHORT_PIN='0 MILS';
      PIN_LENGTH_LONG_PIN='0 MILS';
      CREATEDAY='20210615';
      PARENT_PART_TYPE='74LVC1G126SE7';
      PARENT_PPT='74LVC1G126SE7';
      PARENT_PPT_PART='74LVC1G126SE7-74LVC1G126SE-7,SMLF,IC,AL1G0126009';
  end_body;
end_primitive;
primitive '74LVC1G17GW-74LVC1G17GW,SMLF,IC,AL1G0017K01';
  pin
    'VCC':
      PIN_NUMBER='(5)';
      PINUSE='POWER';
      NO_LOAD_CHECK='Both';
      NO_IO_CHECK='Both';
      NO_ASSERT_CHECK='TRUE';
      NO_DIR_CHECK='TRUE';
      ALLOW_CONNECT='TRUE';
    'A':
      PIN_NUMBER='(2)';
      INPUT_LOAD='(-0.01,0.01)';
      PINUSE='IN';
    'GND':
      PIN_NUMBER='(3)';
      PINUSE='POWER';
      NO_LOAD_CHECK='Both';
      NO_IO_CHECK='Both';
      NO_ASSERT_CHECK='TRUE';
      NO_DIR_CHECK='TRUE';
      ALLOW_CONNECT='TRUE';
    'Y':
      PIN_NUMBER='(4)';
      OUTPUT_TYPE='(OC,AND)';
      OUTPUT_LOAD='(1.0,*)';
      PINUSE='OCA';
    'NC':
      PIN_NUMBER='(1)';
      OUTPUT_TYPE='(TS,TS)';
      INPUT_LOAD='(-0.01,0.01)';
      OUTPUT_LOAD='(1.0,-1.0)';
      PINUSE='TRI';
  end_pin;
  body
      PART_NAME='74LVC1G17GW';
      BODY_NAME='74LVC1G17GW';
      PHYS_DES_PREFIX='U';
      CLASS='IC';
      STANDARD='';
      LIFECYCLE='';
      PART_NUMBER='AL1G0017K01';
      JEDEC_TYPE='TSSOP5';
      DESCRIPTION='IC OTHER(5P) 74LVC1G17GW(TSSOP)';
      MANUFTR='NXP';
      MANUF_PN='74LVC1G17GW';
      RD_CMPLS_LVL='EP(V1)';
      CMPLS_LVL='EP(V1)';
      FROM_PJ='MF1-EUPHIE';
      DIP_SMD='';
      DATA='NXP_74LVC1G17.pdf';
      EE_CHECK_LIST='';
      FP_ECN='';
      PSL='';
      CREATOR='';
      STATUS='';
      CREATEDAY='20140828';
      PARENT_PART_TYPE='74LVC1G17GW';
      PARENT_PPT='74LVC1G17GW';
      PARENT_PPT_PART='74LVC1G17GW-74LVC1G17GW,SMLF,IC,AL1G0017K01';
  end_body;
end_primitive;
primitive '74LVC1G32GW_SMLF-74LVC1G32GW,IC,ALVC1G32007';
  pin
    'I0':
      PIN_NUMBER='(1)';
      INPUT_LOAD='(-0.01,0.01)';
      PINUSE='IN';
    'I1':
      PIN_NUMBER='(2)';
      INPUT_LOAD='(-0.01,0.01)';
      PINUSE='IN';
    'O':
      PIN_NUMBER='(4)';
      OUTPUT_LOAD='(1.0,-1.0)';
      PINUSE='OUT';
    'VCC':
      PIN_NUMBER='(5)';
      PINUSE='POWER';
    'GND':
      PIN_NUMBER='(3)';
      PINUSE='POWER';
  end_pin;
  body
      CLASS='IC';
      PART_NAME='74LVC1G32GW';
      PHYS_DES_PREFIX='U';
      STANDARD='';
      LIFECYCLE='';
      PART_NUMBER='ALVC1G32007';
      JEDEC_TYPE='SOT353_Q';
      DESCRIPTION='IC(5P)74LVC1G32GW (SC70-5)';
      HEIGHT='.044IN';
      COMPONENT_TYPE='SMALLSMT';
      LEAD_LENGTH='';
      DFM_EXCLUSION='';
      DAY='20101005';
      PARENT_PART_TYPE='74LVC1G32GW';
      PARENT_PPT='74LVC1G32GW';
      PARENT_PPT_PART='74LVC1G32GW_SMLF-74LVC1G32GW,IC,ALVC1G32007';
  end_body;
end_primitive;
primitive '74LVC1G66GV-74LVC1G66GV,SMLF,IC,AL001G66000';
  pin
    'Y':
      PIN_NUMBER='(1)';
      BIDIRECTIONAL='TRUE';
      INPUT_LOAD='(-0.01,0.01)';
      OUTPUT_LOAD='(1.0,-1.0)';
      PINUSE='BI';
    'Z':
      PIN_NUMBER='(2)';
      BIDIRECTIONAL='TRUE';
      INPUT_LOAD='(-0.01,0.01)';
      OUTPUT_LOAD='(1.0,-1.0)';
      PINUSE='BI';
    'GND':
      PIN_NUMBER='(3)';
      PINUSE='POWER';
      NO_LOAD_CHECK='Both';
      NO_IO_CHECK='Both';
      NO_ASSERT_CHECK='TRUE';
      NO_DIR_CHECK='TRUE';
      ALLOW_CONNECT='TRUE';
    'E':
      PIN_NUMBER='(4)';
      INPUT_LOAD='(-0.01,0.01)';
      PINUSE='IN';
    'VCC':
      PIN_NUMBER='(5)';
      PINUSE='POWER';
      NO_LOAD_CHECK='Both';
      NO_IO_CHECK='Both';
      NO_ASSERT_CHECK='TRUE';
      NO_DIR_CHECK='TRUE';
      ALLOW_CONNECT='TRUE';
  end_pin;
  body
      PART_NAME='74LVC1G66GV';
      BODY_NAME='74LVC1G66GV';
      PHYS_DES_PREFIX='U';
      CLASS='IC';
      STANDARD='';
      LIFECYCLE='';
      PART_NUMBER='AL001G66000';
      JEDEC_TYPE='SC74AXA';
      DESCRIPTION='IC(5P) 74LVC1G66GV(SOT753)';
      MANUFTR='PHI';
      MANUF_PN='74LVC1G66GV';
      RD_CMPLS_LVL='';
      CMPLS_LVL='EP';
      FROM_PJ='S4P-FRANK';
      DIP_SMD='';
      DATA='PHI_74LVC1G66.pdf';
      EE_CHECK_LIST='SC74AXA.xls';
      FP_ECN='';
      PSL='';
      CREATOR='';
      STATUS='';
      CREATEDAY='20140912';
      PARENT_PART_TYPE='74LVC1G66GV';
      PARENT_PPT='74LVC1G66GV';
      PARENT_PPT_PART='74LVC1G66GV-74LVC1G66GV,SMLF,IC,AL001G66000';
  end_body;
end_primitive;
primitive '74LVC2G07DW7-74LVC2G07DW-7,SMLF,EMPTY,AL002G07003';
  pin
    '1A':
      PIN_NUMBER='(1)';
      INPUT_LOAD='(-0.01,0.01)';
      PINUSE='IN';
    '2A':
      PIN_NUMBER='(3)';
      INPUT_LOAD='(-0.01,0.01)';
      PINUSE='IN';
    '1Y':
      PIN_NUMBER='(6)';
      OUTPUT_LOAD='(1.0,-1.0)';
      PINUSE='OUT';
    '2Y':
      PIN_NUMBER='(4)';
      OUTPUT_LOAD='(1.0,-1.0)';
      PINUSE='OUT';
    'GND':
      PIN_NUMBER='(2)';
      PINUSE='POWER';
      NO_LOAD_CHECK='Both';
      NO_IO_CHECK='Both';
      NO_ASSERT_CHECK='TRUE';
      NO_DIR_CHECK='TRUE';
      ALLOW_CONNECT='TRUE';
    'VCC':
      PIN_NUMBER='(5)';
      PINUSE='POWER';
      NO_LOAD_CHECK='Both';
      NO_IO_CHECK='Both';
      NO_ASSERT_CHECK='TRUE';
      NO_DIR_CHECK='TRUE';
      ALLOW_CONNECT='TRUE';
  end_pin;
  body
      PART_NAME='74LVC2G07DW7';
      BODY_NAME='74LVC2G07DW7';
      PHYS_DES_PREFIX='U';
      CLASS='IC';
      STANDARD='';
      LIFECYCLE='';
      PART_NUMBER='AL002G07003';
      JEDEC_TYPE='SOT363_0-65_2X1-25XC';
      DESCRIPTION='IC OTHER(6P)74LVC2G07DW-7(SOT-363)';
      MANUFTR='DDS';
      MANUF_PN='74LVC2G07DW-7';
      RD_CMPLS_LVL='EP(V1)';
      CMPLS_LVL='EP(V1)';
      FROM_PJ='F0C-IVES';
      DIP_SMD='';
      DATA='DDS_74LVC2G07DW-7.pdf';
      EE_CHECK_LIST='';
      FP_ECN='';
      PSL='';
      CREATOR='';
      STATUS='';
      MSD='';
      ESD_CDM='';
      ESD_HBM='';
      ESD_MM='';
      PIN_LENGTH_SHORT_PIN='0 MILS';
      PIN_LENGTH_LONG_PIN='0 MILS';
      CREATEDAY='20210611';
      PARENT_PART_TYPE='74LVC2G07DW7';
      PARENT_PPT='74LVC2G07DW7';
      PARENT_PPT_PART='74LVC2G07DW7-74LVC2G07DW-7,SMLF,EMPTY,AL002G07003';
  end_body;
end_primitive;
primitive '74LVC2G07DW7-74LVC2G07DW-7,SMLF,IC,AL002G07003';
  pin
    '1A':
      PIN_NUMBER='(1)';
      INPUT_LOAD='(-0.01,0.01)';
      PINUSE='IN';
    '2A':
      PIN_NUMBER='(3)';
      INPUT_LOAD='(-0.01,0.01)';
      PINUSE='IN';
    '1Y':
      PIN_NUMBER='(6)';
      OUTPUT_LOAD='(1.0,-1.0)';
      PINUSE='OUT';
    '2Y':
      PIN_NUMBER='(4)';
      OUTPUT_LOAD='(1.0,-1.0)';
      PINUSE='OUT';
    'GND':
      PIN_NUMBER='(2)';
      PINUSE='POWER';
      NO_LOAD_CHECK='Both';
      NO_IO_CHECK='Both';
      NO_ASSERT_CHECK='TRUE';
      NO_DIR_CHECK='TRUE';
      ALLOW_CONNECT='TRUE';
    'VCC':
      PIN_NUMBER='(5)';
      PINUSE='POWER';
      NO_LOAD_CHECK='Both';
      NO_IO_CHECK='Both';
      NO_ASSERT_CHECK='TRUE';
      NO_DIR_CHECK='TRUE';
      ALLOW_CONNECT='TRUE';
  end_pin;
  body
      PART_NAME='74LVC2G07DW7';
      BODY_NAME='74LVC2G07DW7';
      PHYS_DES_PREFIX='U';
      CLASS='IC';
      STANDARD='';
      LIFECYCLE='';
      PART_NUMBER='AL002G07003';
      JEDEC_TYPE='SOT363_0-65_2X1-25XC';
      DESCRIPTION='IC OTHER(6P)74LVC2G07DW-7(SOT-363)';
      MANUFTR='DDS';
      MANUF_PN='74LVC2G07DW-7';
      RD_CMPLS_LVL='EP(V1)';
      CMPLS_LVL='EP(V1)';
      FROM_PJ='F0C-IVES';
      DIP_SMD='';
      DATA='DDS_74LVC2G07DW-7.pdf';
      EE_CHECK_LIST='';
      FP_ECN='';
      PSL='';
      CREATOR='';
      STATUS='';
      MSD='';
      ESD_CDM='';
      ESD_HBM='';
      ESD_MM='';
      PIN_LENGTH_SHORT_PIN='0 MILS';
      PIN_LENGTH_LONG_PIN='0 MILS';
      CREATEDAY='20210611';
      PARENT_PART_TYPE='74LVC2G07DW7';
      PARENT_PPT='74LVC2G07DW7';
      PARENT_PPT_PART='74LVC2G07DW7-74LVC2G07DW-7,SMLF,IC,AL002G07003';
  end_body;
end_primitive;
primitive '74LVC2G08DP-74LVC2G08DP,SMLF,EMPTY,ALVC2G08K01';
  pin
    'VCC':
      PIN_NUMBER='(8,0)';
      PINUSE='POWER';
      NO_LOAD_CHECK='Both';
      NO_IO_CHECK='Both';
      NO_ASSERT_CHECK='TRUE';
      NO_DIR_CHECK='TRUE';
      ALLOW_CONNECT='TRUE';
    'GND':
      PIN_NUMBER='(4,0)';
      PINUSE='POWER';
      NO_LOAD_CHECK='Both';
      NO_IO_CHECK='Both';
      NO_ASSERT_CHECK='TRUE';
      NO_DIR_CHECK='TRUE';
      ALLOW_CONNECT='TRUE';
    '1A':
      PIN_NUMBER='(1,0)';
      INPUT_LOAD='(-0.01,0.01)';
      PINUSE='IN';
    '1B':
      PIN_NUMBER='(2,0)';
      INPUT_LOAD='(-0.01,0.01)';
      PINUSE='IN';
    '1Y':
      PIN_NUMBER='(7,0)';
      OUTPUT_LOAD='(1.0,-1.0)';
      PINUSE='OUT';
    '2A':
      PIN_NUMBER='(0,5)';
      INPUT_LOAD='(-0.01,0.01)';
      PINUSE='IN';
    '2B':
      PIN_NUMBER='(0,6)';
      INPUT_LOAD='(-0.01,0.01)';
      PINUSE='IN';
    '2Y':
      PIN_NUMBER='(0,3)';
      OUTPUT_LOAD='(1.0,-1.0)';
      PINUSE='OUT';
  end_pin;
  body
      PART_NAME='74LVC2G08DP';
      BODY_NAME='74LVC2G08DP';
      PHYS_DES_PREFIX='U';
      CLASS='IC';
      STANDARD='';
      LIFECYCLE='';
      PART_NUMBER='ALVC2G08K01';
      JEDEC_TYPE='TSSOP8_0-65_3X3';
      DESCRIPTION='IC OTHER(8P) 74LVC2G08DP(TSSOP)';
      MANUFTR='NXP';
      MANUF_PN='74LVC2G08DP';
      RD_CMPLS_LVL='EP(V1)';
      CMPLS_LVL='EP(V1)';
      FROM_PJ='F08-OWEN';
      DIP_SMD='';
      DATA='NXP_74LVC2G08DP.pdf';
      EE_CHECK_LIST='';
      FP_ECN='';
      PSL='';
      CREATOR='';
      STATUS='';
      MSD='';
      ESD_CDM='';
      ESD_HBM='';
      ESD_MM='';
      PIN_LENGTH_SHORT_PIN='';
      PIN_LENGTH_LONG_PIN='';
      CREATEDAY='20160122';
      PARENT_PART_TYPE='74LVC2G08DP';
      PARENT_PPT='74LVC2G08DP';
      PARENT_PPT_PART='74LVC2G08DP-74LVC2G08DP,SMLF,EMPTY,ALVC2G08K01';
  end_body;
end_primitive;
primitive '74LVC2G17GW-74LVC2G17GW,SMLF,IC,AL2G0017005';
  pin
    'VCC':
      PIN_NUMBER='(5)';
      PINUSE='POWER';
      NO_LOAD_CHECK='Both';
      NO_IO_CHECK='Both';
      NO_ASSERT_CHECK='TRUE';
      NO_DIR_CHECK='TRUE';
      ALLOW_CONNECT='TRUE';
    'B1':
      PIN_NUMBER='(4)';
      OUTPUT_LOAD='(1.0,-1.0)';
      PINUSE='OUT';
    'GND':
      PIN_NUMBER='(2)';
      PINUSE='POWER';
      NO_LOAD_CHECK='Both';
      NO_IO_CHECK='Both';
      NO_ASSERT_CHECK='TRUE';
      NO_DIR_CHECK='TRUE';
      ALLOW_CONNECT='TRUE';
    'A0':
      PIN_NUMBER='(1)';
      INPUT_LOAD='(-0.01,0.01)';
      PINUSE='IN';
    'A1':
      PIN_NUMBER='(3)';
      INPUT_LOAD='(-0.01,0.01)';
      PINUSE='IN';
    'B0':
      PIN_NUMBER='(6)';
      OUTPUT_LOAD='(1.0,-1.0)';
      PINUSE='OUT';
  end_pin;
  body
      PART_NAME='74LVC2G17GW';
      BODY_NAME='74LVC2G17GW';
      PHYS_DES_PREFIX='U';
      CLASS='IC';
      STANDARD='';
      LIFECYCLE='';
      PART_NUMBER='AL2G0017005';
      JEDEC_TYPE='SOT363';
      DESCRIPTION='IC(6P) 74LVC2G17GW (SC-88)';
      MANUFTR='PHI';
      MANUF_PN='74LVC2G17GW';
      RD_CMPLS_LVL='EP';
      CMPLS_LVL='EP';
      FROM_PJ='T6S-LOUISE';
      DIP_SMD='';
      DATA='74LVC2G17.pdf';
      EE_CHECK_LIST='';
      FP_ECN='';
      PSL='';
      CREATOR='';
      STATUS='';
      CREATEDAY='20121122';
      PARENT_PART_TYPE='74LVC2G17GW';
      PARENT_PPT='74LVC2G17GW';
      PARENT_PPT_PART='74LVC2G17GW-74LVC2G17GW,SMLF,IC,AL2G0017005';
  end_body;
end_primitive;
primitive '9FGL0251DKILFT-9FGL0251DKILFT,SMLF,IC,AL000251002';
  pin
    'XIN||CLKIN_25':
      PIN_NUMBER='(1)';
      INPUT_LOAD='(-0.01,0.01)';
      PINUSE='IN';
    'X2':
      PIN_NUMBER='(2)';
      OUTPUT_LOAD='(1.0,-1.0)';
      PINUSE='OUT';
    'VDDXTAL3.3':
      PIN_NUMBER='(3)';
      PINUSE='POWER';
      NO_LOAD_CHECK='Both';
      NO_IO_CHECK='Both';
      NO_ASSERT_CHECK='TRUE';
      NO_DIR_CHECK='TRUE';
      ALLOW_CONNECT='TRUE';
    'VSADR||REF3.3':
      PIN_NUMBER='(4)';
      BIDIRECTIONAL='TRUE';
      INPUT_LOAD='(-0.01,0.01)';
      OUTPUT_LOAD='(1.0,-1.0)';
      PINUSE='BI';
    'GNDREF':
      PIN_NUMBER='(5)';
      PINUSE='POWER';
      NO_LOAD_CHECK='Both';
      NO_IO_CHECK='Both';
      NO_ASSERT_CHECK='TRUE';
      NO_DIR_CHECK='TRUE';
      ALLOW_CONNECT='TRUE';
    'GNDDIG':
      PIN_NUMBER='(6)';
      PINUSE='POWER';
      NO_LOAD_CHECK='Both';
      NO_IO_CHECK='Both';
      NO_ASSERT_CHECK='TRUE';
      NO_DIR_CHECK='TRUE';
      ALLOW_CONNECT='TRUE';
    'VDDDIG3.3':
      PIN_NUMBER='(7)';
      PINUSE='POWER';
      NO_LOAD_CHECK='Both';
      NO_IO_CHECK='Both';
      NO_ASSERT_CHECK='TRUE';
      NO_DIR_CHECK='TRUE';
      ALLOW_CONNECT='TRUE';
    'SCLK_3.3':
      PIN_NUMBER='(8)';
      INPUT_LOAD='(-0.01,0.01)';
      PINUSE='IN';
    'SDATA_3.3':
      PIN_NUMBER='(9)';
      BIDIRECTIONAL='TRUE';
      INPUT_LOAD='(-0.01,0.01)';
      OUTPUT_LOAD='(1.0,-1.0)';
      PINUSE='BI';
    'GND_10':
      PIN_NUMBER='(10)';
      PINUSE='POWER';
      NO_LOAD_CHECK='Both';
      NO_IO_CHECK='Both';
      NO_ASSERT_CHECK='TRUE';
      NO_DIR_CHECK='TRUE';
      ALLOW_CONNECT='TRUE';
    'VDD3.3_11':
      PIN_NUMBER='(11)';
      PINUSE='POWER';
      NO_LOAD_CHECK='Both';
      NO_IO_CHECK='Both';
      NO_ASSERT_CHECK='TRUE';
      NO_DIR_CHECK='TRUE';
      ALLOW_CONNECT='TRUE';
    'VOE0#':
      PIN_NUMBER='(12)';
      INPUT_LOAD='(-0.01,0.01)';
      PINUSE='IN';
    'DIF0':
      PIN_NUMBER='(13)';
      OUTPUT_LOAD='(1.0,-1.0)';
      PINUSE='OUT';
    'DIF0#':
      PIN_NUMBER='(14)';
      OUTPUT_LOAD='(1.0,-1.0)';
      PINUSE='OUT';
    'GNDA':
      PIN_NUMBER='(15)';
      PINUSE='POWER';
      NO_LOAD_CHECK='Both';
      NO_IO_CHECK='Both';
      NO_ASSERT_CHECK='TRUE';
      NO_DIR_CHECK='TRUE';
      ALLOW_CONNECT='TRUE';
    'VDDA3.3':
      PIN_NUMBER='(16)';
      PINUSE='POWER';
      NO_LOAD_CHECK='Both';
      NO_IO_CHECK='Both';
      NO_ASSERT_CHECK='TRUE';
      NO_DIR_CHECK='TRUE';
      ALLOW_CONNECT='TRUE';
    'DIF1':
      PIN_NUMBER='(17)';
      OUTPUT_LOAD='(1.0,-1.0)';
      PINUSE='OUT';
    'DIF1#':
      PIN_NUMBER='(18)';
      OUTPUT_LOAD='(1.0,-1.0)';
      PINUSE='OUT';
    'VOE1#':
      PIN_NUMBER='(19)';
      INPUT_LOAD='(-0.01,0.01)';
      PINUSE='IN';
    'VDD3.3_20':
      PIN_NUMBER='(20)';
      PINUSE='POWER';
      NO_LOAD_CHECK='Both';
      NO_IO_CHECK='Both';
      NO_ASSERT_CHECK='TRUE';
      NO_DIR_CHECK='TRUE';
      ALLOW_CONNECT='TRUE';
    'GND_21':
      PIN_NUMBER='(21)';
      PINUSE='POWER';
      NO_LOAD_CHECK='Both';
      NO_IO_CHECK='Both';
      NO_ASSERT_CHECK='TRUE';
      NO_DIR_CHECK='TRUE';
      ALLOW_CONNECT='TRUE';
    '^CKPWRGD_PD#':
      PIN_NUMBER='(22)';
      INPUT_LOAD='(-0.01,0.01)';
      PINUSE='IN';
    '^VSS_EN_TRI':
      PIN_NUMBER='(23)';
      INPUT_LOAD='(-0.01,0.01)';
      PINUSE='IN';
    'GNDXTAL':
      PIN_NUMBER='(24)';
      PINUSE='POWER';
      NO_LOAD_CHECK='Both';
      NO_IO_CHECK='Both';
      NO_ASSERT_CHECK='TRUE';
      NO_DIR_CHECK='TRUE';
      ALLOW_CONNECT='TRUE';
    'TH_GND':
      PIN_NUMBER='(25)';
      PINUSE='POWER';
      NO_LOAD_CHECK='Both';
      NO_IO_CHECK='Both';
      NO_ASSERT_CHECK='TRUE';
      NO_DIR_CHECK='TRUE';
      ALLOW_CONNECT='TRUE';
  end_pin;
  body
      PART_NAME='9FGL0251DKILFT';
      BODY_NAME='9FGL0251DKILFT';
      PHYS_DES_PREFIX='U';
      CLASS='IC';
      STANDARD='';
      LIFECYCLE='';
      PART_NUMBER='AL000251002';
      JEDEC_TYPE='VFQFPN24_TH_0-5_4X4XI';
      DESCRIPTION='IC(24P)9FGL0251DKILFT(VFQFPN)';
      MANUFTR='RTT';
      MANUF_PN='9FGL0251DKILFT';
      RD_CMPLS_LVL='EP(V1)';
      CMPLS_LVL='';
      FROM_PJ='S7G-DAVID';
      DIP_SMD='';
      DATA='RTT_9FGL0251DKILFT.pdf';
      EE_CHECK_LIST='';
      FP_ECN='';
      PSL='';
      CREATOR='';
      STATUS='';
      MSD='';
      ESD_CDM='';
      ESD_HBM='';
      ESD_MM='';
      PIN_LENGTH_SHORT_PIN='0 MILS';
      PIN_LENGTH_LONG_PIN='0 MILS';
      CREATEDAY='20221223';
      PARENT_PART_TYPE='9FGL0251DKILFT';
      PARENT_PPT='9FGL0251DKILFT';
      PARENT_PPT_PART='9FGL0251DKILFT-9FGL0251DKILFT,SMLF,IC,AL000251002';
  end_body;
end_primitive;
primitive '9ZXL0451EKILFT-9ZXL0451EKILFT,SMLF,IC,AL000451003';
  pin
    'DIF_IN':
      PIN_NUMBER='(3)';
      INPUT_LOAD='(-0.01,0.01)';
      PINUSE='IN';
    'DIF_IN#':
      PIN_NUMBER='(4)';
      INPUT_LOAD='(-0.01,0.01)';
      PINUSE='IN';
    'VDDR':
      PIN_NUMBER='(2)';
      PINUSE='POWER';
      NO_LOAD_CHECK='Both';
      NO_IO_CHECK='Both';
      NO_ASSERT_CHECK='TRUE';
      NO_DIR_CHECK='TRUE';
      ALLOW_CONNECT='TRUE';
    'VDD3':
      PIN_NUMBER='(25)';
      PINUSE='POWER';
      NO_LOAD_CHECK='Both';
      NO_IO_CHECK='Both';
      NO_ASSERT_CHECK='TRUE';
      NO_DIR_CHECK='TRUE';
      ALLOW_CONNECT='TRUE';
    'VDD4':
      PIN_NUMBER='(29)';
      PINUSE='POWER';
      NO_LOAD_CHECK='Both';
      NO_IO_CHECK='Both';
      NO_ASSERT_CHECK='TRUE';
      NO_DIR_CHECK='TRUE';
      ALLOW_CONNECT='TRUE';
    'FBOUT_NC':
      PIN_NUMBER='(9)';
      OUTPUT_LOAD='(1.0,-1.0)';
      PINUSE='OUT';
    'VOE0#':
      PIN_NUMBER='(15)';
      INPUT_LOAD='(-0.01,0.01)';
      PINUSE='IN';
    'VOE3#':
      PIN_NUMBER='(26)';
      INPUT_LOAD='(-0.01,0.01)';
      PINUSE='IN';
    'SMBDAT':
      PIN_NUMBER='(6)';
      BIDIRECTIONAL='TRUE';
      INPUT_LOAD='(-0.01,0.01)';
      OUTPUT_LOAD='(1.0,-1.0)';
      PINUSE='BI';
    'NC1':
      PIN_NUMBER='(11)';
      OUTPUT_TYPE='(TS,TS)';
      INPUT_LOAD='(-0.01,0.01)';
      OUTPUT_LOAD='(1.0,-1.0)';
      PINUSE='TRI';
    'FBOUT_NC#':
      PIN_NUMBER='(8)';
      OUTPUT_LOAD='(1.0,-1.0)';
      PINUSE='OUT';
    'SMBCLK':
      PIN_NUMBER='(7)';
      INPUT_LOAD='(-0.01,0.01)';
      PINUSE='IN';
    'VDD2':
      PIN_NUMBER='(21)';
      PINUSE='POWER';
      NO_LOAD_CHECK='Both';
      NO_IO_CHECK='Both';
      NO_ASSERT_CHECK='TRUE';
      NO_DIR_CHECK='TRUE';
      ALLOW_CONNECT='TRUE';
    '^CKPWRGD_PD#':
      PIN_NUMBER='(1)';
      INPUT_LOAD='(-0.01,0.01)';
      PINUSE='IN';
    'DIF0#':
      PIN_NUMBER='(14)';
      OUTPUT_LOAD='(1.0,-1.0)';
      PINUSE='OUT';
    'DIF0':
      PIN_NUMBER='(13)';
      OUTPUT_LOAD='(1.0,-1.0)';
      PINUSE='OUT';
    'VOE1#':
      PIN_NUMBER='(18)';
      INPUT_LOAD='(-0.01,0.01)';
      PINUSE='IN';
    'DIF1#':
      PIN_NUMBER='(20)';
      OUTPUT_LOAD='(1.0,-1.0)';
      PINUSE='OUT';
    'DIF2':
      PIN_NUMBER='(22)';
      OUTPUT_LOAD='(1.0,-1.0)';
      PINUSE='OUT';
    'VOE2#':
      PIN_NUMBER='(24)';
      INPUT_LOAD='(-0.01,0.01)';
      PINUSE='IN';
    'DIF2#':
      PIN_NUMBER='(23)';
      OUTPUT_LOAD='(1.0,-1.0)';
      PINUSE='OUT';
    'DIF3#':
      PIN_NUMBER='(28)';
      OUTPUT_LOAD='(1.0,-1.0)';
      PINUSE='OUT';
    'NC0':
      PIN_NUMBER='(10)';
      OUTPUT_TYPE='(TS,TS)';
      INPUT_LOAD='(-0.01,0.01)';
      OUTPUT_LOAD='(1.0,-1.0)';
      PINUSE='TRI';
    'VDDA':
      PIN_NUMBER='(31)';
      PINUSE='POWER';
      NO_LOAD_CHECK='Both';
      NO_IO_CHECK='Both';
      NO_ASSERT_CHECK='TRUE';
      NO_DIR_CHECK='TRUE';
      ALLOW_CONNECT='TRUE';
    'VDD1':
      PIN_NUMBER='(16)';
      PINUSE='POWER';
      NO_LOAD_CHECK='Both';
      NO_IO_CHECK='Both';
      NO_ASSERT_CHECK='TRUE';
      NO_DIR_CHECK='TRUE';
      ALLOW_CONNECT='TRUE';
    '^HIBW_BYPM_LOBW#':
      PIN_NUMBER='(32)';
      INPUT_LOAD='(-0.01,0.01)';
      PINUSE='IN';
    'EPAD_GND':
      PIN_NUMBER='(33)';
      PINUSE='POWER';
      NO_LOAD_CHECK='Both';
      NO_IO_CHECK='Both';
      NO_ASSERT_CHECK='TRUE';
      NO_DIR_CHECK='TRUE';
      ALLOW_CONNECT='TRUE';
    'DIF1':
      PIN_NUMBER='(19)';
      OUTPUT_LOAD='(1.0,-1.0)';
      PINUSE='OUT';
    'DIF3':
      PIN_NUMBER='(27)';
      OUTPUT_LOAD='(1.0,-1.0)';
      PINUSE='OUT';
    'VDD0':
      PIN_NUMBER='(12)';
      PINUSE='POWER';
      NO_LOAD_CHECK='Both';
      NO_IO_CHECK='Both';
      NO_ASSERT_CHECK='TRUE';
      NO_DIR_CHECK='TRUE';
      ALLOW_CONNECT='TRUE';
    'NC3':
      PIN_NUMBER='(30)';
      OUTPUT_TYPE='(TS,TS)';
      INPUT_LOAD='(-0.01,0.01)';
      OUTPUT_LOAD='(1.0,-1.0)';
      PINUSE='TRI';
    'NC2':
      PIN_NUMBER='(17)';
      OUTPUT_TYPE='(TS,TS)';
      INPUT_LOAD='(-0.01,0.01)';
      OUTPUT_LOAD='(1.0,-1.0)';
      PINUSE='TRI';
    'VSADR0_TRI':
      PIN_NUMBER='(5)';
      INPUT_LOAD='(-0.01,0.01)';
      PINUSE='IN';
  end_pin;
  body
      PART_NAME='9ZXL0451EKILFT';
      BODY_NAME='9ZXL0451EKILFT';
      PHYS_DES_PREFIX='U';
      CLASS='IC';
      STANDARD='';
      LIFECYCLE='';
      PART_NUMBER='AL000451003';
      JEDEC_TYPE='VFQFPN32_TH_0-5_5X5XD';
      DESCRIPTION='IC OTHER(32P) 9ZXL0451EKILFT(VFQFPN)';
      MANUFTR='IDT';
      MANUF_PN='9ZXL0451EKILFT';
      RD_CMPLS_LVL='EP(V1)';
      CMPLS_LVL='EP(V1)';
      FROM_PJ='S69-JEFF';
      DIP_SMD='';
      DATA='IDT_9ZXL0451EKILFT.pdf';
      EE_CHECK_LIST='';
      FP_ECN='';
      PSL='';
      CREATOR='';
      STATUS='';
      MSD='NA';
      ESD_CDM='NA';
      ESD_HBM='NA';
      ESD_MM='NA';
      PIN_LENGTH_SHORT_PIN='0 MILS';
      PIN_LENGTH_LONG_PIN='0 MILS';
      CREATEDAY='20190416';
      PARENT_PART_TYPE='9ZXL0451EKILFT';
      PARENT_PPT='9ZXL0451EKILFT';
      PARENT_PPT_PART='9ZXL0451EKILFT-9ZXL0451EKILFT,SMLF,IC,AL000451003';
  end_body;
end_primitive;
primitive 'ADC128D818CIMTXNOPB-ADC128D818CIMTX/NOPB,SMLF,IC,AA';
  pin
    'VREF':
      PIN_NUMBER='(1)';
      INPUT_LOAD='(-0.01,0.01)';
      PINUSE='IN';
    'V+':
      PIN_NUMBER='(5)';
      PINUSE='POWER';
      NO_LOAD_CHECK='Both';
      NO_IO_CHECK='Both';
      NO_ASSERT_CHECK='TRUE';
      NO_DIR_CHECK='TRUE';
      ALLOW_CONNECT='TRUE';
    'A0':
      PIN_NUMBER='(7)';
      INPUT_LOAD='(-0.01,0.01)';
      PINUSE='IN';
    'A1':
      PIN_NUMBER='(8)';
      INPUT_LOAD='(-0.01,0.01)';
      PINUSE='IN';
    'IN7':
      PIN_NUMBER='(9)';
      INPUT_LOAD='(-0.01,0.01)';
      PINUSE='IN';
    'IN6':
      PIN_NUMBER='(10)';
      INPUT_LOAD='(-0.01,0.01)';
      PINUSE='IN';
    'IN5':
      PIN_NUMBER='(11)';
      INPUT_LOAD='(-0.01,0.01)';
      PINUSE='IN';
    'IN4':
      PIN_NUMBER='(12)';
      INPUT_LOAD='(-0.01,0.01)';
      PINUSE='IN';
    'IN3':
      PIN_NUMBER='(13)';
      INPUT_LOAD='(-0.01,0.01)';
      PINUSE='IN';
    'IN2':
      PIN_NUMBER='(14)';
      INPUT_LOAD='(-0.01,0.01)';
      PINUSE='IN';
    'IN1':
      PIN_NUMBER='(15)';
      INPUT_LOAD='(-0.01,0.01)';
      PINUSE='IN';
    'IN0':
      PIN_NUMBER='(16)';
      INPUT_LOAD='(-0.01,0.01)';
      PINUSE='IN';
    'SDA':
      PIN_NUMBER='(2)';
      BIDIRECTIONAL='TRUE';
      INPUT_LOAD='(-0.01,0.01)';
      OUTPUT_LOAD='(1.0,-1.0)';
      PINUSE='BI';
    'SCL':
      PIN_NUMBER='(3)';
      INPUT_LOAD='(-0.01,0.01)';
      PINUSE='IN';
    'GND':
      PIN_NUMBER='(4)';
      PINUSE='POWER';
      NO_LOAD_CHECK='Both';
      NO_IO_CHECK='Both';
      NO_ASSERT_CHECK='TRUE';
      NO_DIR_CHECK='TRUE';
      ALLOW_CONNECT='TRUE';
    'INT#':
      PIN_NUMBER='(6)';
      OUTPUT_LOAD='(1.0,-1.0)';
      PINUSE='OUT';
  end_pin;
  body
      PART_NAME='ADC128D818CIMTXNOPB';
      BODY_NAME='ADC128D818CIMTXNOPB';
      PHYS_DES_PREFIX='U';
      CLASS='IC';
      STANDARD='';
      LIFECYCLE='';
      PART_NUMBER='AL000128K00';
      JEDEC_TYPE='TSSOP16XC';
      DESCRIPTION='IC OTHER(16P)ADC128D818CIMTX/NOPB(TSSOP)';
      MANUFTR='TIC';
      MANUF_PN='ADC128D818CIMTX/NOPB';
      RD_CMPLS_LVL='EP(V1)';
      CMPLS_LVL='';
      FROM_PJ='S1U-OWEN';
      DIP_SMD='';
      DATA='TIC_ADC128D818CIMTXNOPB.pdf';
      EE_CHECK_LIST='';
      FP_ECN='';
      PSL='';
      CREATOR='';
      STATUS='';
      CREATEDAY='20150604';
      PARENT_PART_TYPE='ADC128D818CIMTXNOPB';
      PARENT_PPT='ADC128D818CIMTXNOPB';
      PARENT_PPT_PART='ADC128D818CIMTXNOPB-ADC128D818CIMTX/NOPB,SMLF,IC,AL000128K00';
  end_body;
end_primitive;
primitive 'AP331AWG7-AP331AWG-7,SMLF,EMPTY,AL000331011';
  pin
    'IN+':
      PIN_NUMBER='(3)';
      INPUT_LOAD='(-0.01,0.01)';
      PINUSE='IN';
    'IN-':
      PIN_NUMBER='(1)';
      INPUT_LOAD='(-0.01,0.01)';
      PINUSE='IN';
    'OUTPUT':
      PIN_NUMBER='(4)';
      OUTPUT_LOAD='(1.0,-1.0)';
      PINUSE='OUT';
    'VCC':
      PIN_NUMBER='(5)';
      PINUSE='POWER';
      NO_LOAD_CHECK='Both';
      NO_IO_CHECK='Both';
      NO_ASSERT_CHECK='TRUE';
      NO_DIR_CHECK='TRUE';
      ALLOW_CONNECT='TRUE';
    'GND':
      PIN_NUMBER='(2)';
      PINUSE='POWER';
      NO_LOAD_CHECK='Both';
      NO_IO_CHECK='Both';
      NO_ASSERT_CHECK='TRUE';
      NO_DIR_CHECK='TRUE';
      ALLOW_CONNECT='TRUE';
  end_pin;
  body
      PART_NAME='AP331AWG7';
      BODY_NAME='AP331AWG7';
      PHYS_DES_PREFIX='U';
      CLASS='IC';
      STANDARD='';
      LIFECYCLE='';
      PART_NUMBER='AL000331011';
      JEDEC_TYPE='SOT25';
      DESCRIPTION='IC OTHER(5P) AP331AWG-7 (SOT25)';
      MANUFTR='DDS';
      MANUF_PN='AP331AWG-7';
      RD_CMPLS_LVL='EP(V1)';
      CMPLS_LVL='EP(V1)';
      FROM_PJ='T6G-ALLEN';
      DIP_SMD='';
      DATA='DDS_AP331AWG-7.pdf';
      EE_CHECK_LIST='';
      FP_ECN='';
      PSL='';
      CREATOR='';
      STATUS='';
      MSD='';
      ESD_CDM='';
      ESD_HBM='';
      ESD_MM='';
      PIN_LENGTH_SHORT_PIN='0 MILS';
      PIN_LENGTH_LONG_PIN='0 MILS';
      CREATEDAY='20210812';
      PARENT_PART_TYPE='AP331AWG7';
      PARENT_PPT='AP331AWG7';
      PARENT_PPT_PART='AP331AWG7-AP331AWG-7,SMLF,EMPTY,AL000331011';
  end_body;
end_primitive;
primitive 'AP331AWG7-AP331AWG-7,SMLF,IC,AL000331011';
  pin
    'IN+':
      PIN_NUMBER='(3)';
      INPUT_LOAD='(-0.01,0.01)';
      PINUSE='IN';
    'IN-':
      PIN_NUMBER='(1)';
      INPUT_LOAD='(-0.01,0.01)';
      PINUSE='IN';
    'OUTPUT':
      PIN_NUMBER='(4)';
      OUTPUT_LOAD='(1.0,-1.0)';
      PINUSE='OUT';
    'VCC':
      PIN_NUMBER='(5)';
      PINUSE='POWER';
      NO_LOAD_CHECK='Both';
      NO_IO_CHECK='Both';
      NO_ASSERT_CHECK='TRUE';
      NO_DIR_CHECK='TRUE';
      ALLOW_CONNECT='TRUE';
    'GND':
      PIN_NUMBER='(2)';
      PINUSE='POWER';
      NO_LOAD_CHECK='Both';
      NO_IO_CHECK='Both';
      NO_ASSERT_CHECK='TRUE';
      NO_DIR_CHECK='TRUE';
      ALLOW_CONNECT='TRUE';
  end_pin;
  body
      PART_NAME='AP331AWG7';
      BODY_NAME='AP331AWG7';
      PHYS_DES_PREFIX='U';
      CLASS='IC';
      STANDARD='';
      LIFECYCLE='';
      PART_NUMBER='AL000331011';
      JEDEC_TYPE='SOT25';
      DESCRIPTION='IC OTHER(5P) AP331AWG-7 (SOT25)';
      MANUFTR='DDS';
      MANUF_PN='AP331AWG-7';
      RD_CMPLS_LVL='EP(V1)';
      CMPLS_LVL='EP(V1)';
      FROM_PJ='T6G-ALLEN';
      DIP_SMD='';
      DATA='DDS_AP331AWG-7.pdf';
      EE_CHECK_LIST='';
      FP_ECN='';
      PSL='';
      CREATOR='';
      STATUS='';
      MSD='';
      ESD_CDM='';
      ESD_HBM='';
      ESD_MM='';
      PIN_LENGTH_SHORT_PIN='0 MILS';
      PIN_LENGTH_LONG_PIN='0 MILS';
      CREATEDAY='20210812';
      PARENT_PART_TYPE='AP331AWG7';
      PARENT_PPT='AP331AWG7';
      PARENT_PPT_PART='AP331AWG7-AP331AWG-7,SMLF,IC,AL000331011';
  end_body;
end_primitive;
primitive 'APX80929SAG7-APX809-29SAG-7,SMLF,IC,AL080929000';
  pin
    'VCC':
      PIN_NUMBER='(3)';
      PINUSE='POWER';
      NO_LOAD_CHECK='Both';
      NO_IO_CHECK='Both';
      NO_ASSERT_CHECK='TRUE';
      NO_DIR_CHECK='TRUE';
      ALLOW_CONNECT='TRUE';
    'RESET_L':
      PIN_NUMBER='(2)';
      OUTPUT_LOAD='(1.0,-1.0)';
      PINUSE='OUT';
    'GND':
      PIN_NUMBER='(1)';
      PINUSE='POWER';
      NO_LOAD_CHECK='Both';
      NO_IO_CHECK='Both';
      NO_ASSERT_CHECK='TRUE';
      NO_DIR_CHECK='TRUE';
      ALLOW_CONNECT='TRUE';
  end_pin;
  body
      PART_NAME='APX80929SAG7';
      BODY_NAME='APX80929SAG7';
      PHYS_DES_PREFIX='U';
      CLASS='IC';
      STANDARD='';
      LIFECYCLE='';
      PART_NUMBER='AL080929000';
      JEDEC_TYPE='SOT23_123XI';
      DESCRIPTION='IC OTHER(3P) APX809-29SAG-7(SOT23)';
      MANUFTR='DDS';
      MANUF_PN='APX809-29SAG-7';
      RD_CMPLS_LVL='EP(V1)';
      CMPLS_LVL='EP(V1)';
      FROM_PJ='S2VA-JOSEPH';
      DIP_SMD='';
      DATA='DDS_APX809-810_rev4.pdf';
      EE_CHECK_LIST='';
      FP_ECN='';
      PSL='';
      CREATOR='';
      STATUS='';
      CREATEDAY='20130717';
      PARENT_PART_TYPE='APX80929SAG7';
      PARENT_PPT='APX80929SAG7';
      PARENT_PPT_PART='APX80929SAG7-APX809-29SAG-7,SMLF,IC,AL080929000';
  end_body;
end_primitive;
primitive 'BAT547F-BAT547F,SMLF,IC,BC0BAT54Z53';
  pin
    '1':
      PIN_NUMBER='(1)';
      BIDIRECTIONAL='TRUE';
      INPUT_LOAD='(-0.01,0.01)';
      OUTPUT_LOAD='(1.0,-1.0)';
      PINUSE='BI';
    '3':
      PIN_NUMBER='(3)';
      BIDIRECTIONAL='TRUE';
      INPUT_LOAD='(-0.01,0.01)';
      OUTPUT_LOAD='(1.0,-1.0)';
      PINUSE='BI';
  end_pin;
  body
      PART_NAME='BAT547F';
      BODY_NAME='BAT547F';
      PHYS_DES_PREFIX='D';
      CLASS='IC';
      NC_PINS='(2)';
      STANDARD='';
      LIFECYCLE='';
      PART_NUMBER='BC0BAT54Z53';
      JEDEC_TYPE='SOT23_123XB';
      DESCRIPTION='DIODE BAT54-7-F(30V.200MA SCHOTTKY)';
      MANUFTR='DDS';
      MANUF_PN='BAT54-7-F';
      RD_CMPLS_LVL='';
      CMPLS_LVL='EU';
      DIP_SMD='';
      FP_ECN='';
      FROM_PJ='S50-STEVE';
      DATA='DDS_BAT54-7-F(A.C.S-7-F).pdf';
      EE_CHECK_LIST='';
      STATUS='';
      PSL='';
      PREFERENCE='';
      CREATOR='';
      CREATEDAY='20130912';
      PARENT_PART_TYPE='BAT547F';
      PARENT_PPT='BAT547F';
      PARENT_PPT_PART='BAT547F-BAT547F,SMLF,IC,BC0BAT54Z53';
  end_body;
end_primitive;
primitive 'BSS138DW7F-BSS138DW-7-F,SMLF,IC,BAM01380032';
  pin
    'G1':
      PIN_NUMBER='(2)';
      INPUT_LOAD='(-0.01,0.01)';
      OUTPUT_LOAD='(1.0,-1.0)';
      BIDIRECTIONAL='TRUE';
      PINUSE='BI';
    'G2':
      PIN_NUMBER='(5)';
      INPUT_LOAD='(-0.01,0.01)';
      OUTPUT_LOAD='(1.0,-1.0)';
      BIDIRECTIONAL='TRUE';
      PINUSE='BI';
    'S1':
      PIN_NUMBER='(1)';
      INPUT_LOAD='(-0.01,0.01)';
      OUTPUT_LOAD='(1.0,-1.0)';
      BIDIRECTIONAL='TRUE';
      PINUSE='BI';
    'S2':
      PIN_NUMBER='(4)';
      INPUT_LOAD='(-0.01,0.01)';
      OUTPUT_LOAD='(1.0,-1.0)';
      BIDIRECTIONAL='TRUE';
      PINUSE='BI';
    'D1':
      PIN_NUMBER='(6)';
      INPUT_LOAD='(-0.01,0.01)';
      OUTPUT_LOAD='(1.0,-1.0)';
      BIDIRECTIONAL='TRUE';
      PINUSE='BI';
    'D2':
      PIN_NUMBER='(3)';
      INPUT_LOAD='(-0.01,0.01)';
      OUTPUT_LOAD='(1.0,-1.0)';
      BIDIRECTIONAL='TRUE';
      PINUSE='BI';
  end_pin;
  body
      CLASS='IC';
      PART_NAME='BSS138DW7F';
      PHYS_DES_PREFIX='Q';
      STANDARD='';
      LIFECYCLE='';
      PART_NUMBER='BAM01380032';
      JEDEC_TYPE='SOT363A';
      DESCRIPTION='TRANS MOSFET BSS138DW-7-F(50V,200MA)';
      MANUFTR='DDS';
      MANUF_PN='BSS138DW-7-F';
      RD_CMPLS_LVL='EP(V1)';
      CMPLS_LVL='';
      DIP_SMD='';
      FROM_PJ='S2N-JUMP';
      DATA='BSS138DW-7-F.pdf';
      FP_ECN='';
      EE_CHECK_LIST='';
      STATUS='';
      PREFERENCE='';
      NOT_INSERT='';
      PARENT_PART_TYPE='BSS138DW7F';
      PARENT_PPT='BSS138DW7F';
      PARENT_PPT_PART='BSS138DW7F-BSS138DW-7-F,SMLF,IC,BAM01380032';
  end_body;
end_primitive;
primitive 'CONN10_HBC1051L300D8H-CONN10_HBC1051-L300D-8H,THLFA';
  pin
    '1':
      PIN_NUMBER='(1)';
      BIDIRECTIONAL='TRUE';
      INPUT_LOAD='(-0.01,0.01)';
      OUTPUT_LOAD='(1.0,-1.0)';
      PINUSE='BI';
    '2':
      PIN_NUMBER='(2)';
      BIDIRECTIONAL='TRUE';
      INPUT_LOAD='(-0.01,0.01)';
      OUTPUT_LOAD='(1.0,-1.0)';
      PINUSE='BI';
    '3':
      PIN_NUMBER='(3)';
      BIDIRECTIONAL='TRUE';
      INPUT_LOAD='(-0.01,0.01)';
      OUTPUT_LOAD='(1.0,-1.0)';
      PINUSE='BI';
    '4':
      PIN_NUMBER='(4)';
      BIDIRECTIONAL='TRUE';
      INPUT_LOAD='(-0.01,0.01)';
      OUTPUT_LOAD='(1.0,-1.0)';
      PINUSE='BI';
    '5':
      PIN_NUMBER='(5)';
      BIDIRECTIONAL='TRUE';
      INPUT_LOAD='(-0.01,0.01)';
      OUTPUT_LOAD='(1.0,-1.0)';
      PINUSE='BI';
    '6':
      PIN_NUMBER='(6)';
      BIDIRECTIONAL='TRUE';
      INPUT_LOAD='(-0.01,0.01)';
      OUTPUT_LOAD='(1.0,-1.0)';
      PINUSE='BI';
    '7':
      PIN_NUMBER='(7)';
      BIDIRECTIONAL='TRUE';
      INPUT_LOAD='(-0.01,0.01)';
      OUTPUT_LOAD='(1.0,-1.0)';
      PINUSE='BI';
    '9':
      PIN_NUMBER='(9)';
      BIDIRECTIONAL='TRUE';
      INPUT_LOAD='(-0.01,0.01)';
      OUTPUT_LOAD='(1.0,-1.0)';
      PINUSE='BI';
    '8':
      PIN_NUMBER='(8)';
      BIDIRECTIONAL='TRUE';
      INPUT_LOAD='(-0.01,0.01)';
      OUTPUT_LOAD='(1.0,-1.0)';
      PINUSE='BI';
    '10':
      PIN_NUMBER='(10)';
      BIDIRECTIONAL='TRUE';
      INPUT_LOAD='(-0.01,0.01)';
      OUTPUT_LOAD='(1.0,-1.0)';
      PINUSE='BI';
  end_pin;
  body
      PART_NAME='CONN10_HBC1051L300D8H';
      BODY_NAME='CONN10_HBC1051L300D8H';
      PHYS_DES_PREFIX='J';
      CLASS='IO';
      STANDARD='';
      LIFECYCLE='';
      PART_NUMBER='DFHD10MS117';
      JEDEC_TYPE='HEADER2X5XJ';
      DESCRIPTION='CONN DIP HEADER 10P 2R MS(P2.54, H8.38)';
      MANUFTR='FOX';
      MANUF_PN='HBC1051-L300D-8H';
      RD_CMPLS_LVL='EP(V1)';
      CMPLS_LVL='EP(V1)';
      DIP_SMD='DIP';
      FROM_PJ='S3IS-MARK';
      DATA='FOX_HBC1051-L300D-8H.pdf';
      FP_ECN='';
      EE_CHECK_LIST='';
      CREATOR='';
      CREATEDAY='20210203';
      PSL='';
      STATUS='';
      ESD_CDM='0';
      ESD_HBM='0';
      ESD_MM='0';
      MSD='NA';
      PIN_LENGTH_LONG_PIN='126 MILS';
      PIN_LENGTH_SHORT_PIN='126 MILS';
      PARENT_PART_TYPE='CONN10_HBC1051L300D8H';
      PARENT_PPT='CONN10_HBC1051L300D8H';
      PARENT_PPT_PART='CONN10_HBC1051L300D8H-CONN10_HBC1051-L300D-8H,THLF,IO,DFHD10MS117';
  end_body;
end_primitive;
primitive 'CONN112_10137002101LF-CONN112_10137002-101LF,THLF,A';
  pin
    'A8':
      PIN_NUMBER='(A8,0)';
      BIDIRECTIONAL='TRUE';
      INPUT_LOAD='(-0.01,0.01)';
      OUTPUT_LOAD='(1.0,-1.0)';
      PINUSE='BI';
    'A7':
      PIN_NUMBER='(A7,0)';
      BIDIRECTIONAL='TRUE';
      INPUT_LOAD='(-0.01,0.01)';
      OUTPUT_LOAD='(1.0,-1.0)';
      PINUSE='BI';
    'A6':
      PIN_NUMBER='(A6,0)';
      BIDIRECTIONAL='TRUE';
      INPUT_LOAD='(-0.01,0.01)';
      OUTPUT_LOAD='(1.0,-1.0)';
      PINUSE='BI';
    'A5':
      PIN_NUMBER='(A5,0)';
      BIDIRECTIONAL='TRUE';
      INPUT_LOAD='(-0.01,0.01)';
      OUTPUT_LOAD='(1.0,-1.0)';
      PINUSE='BI';
    'B8':
      PIN_NUMBER='(B8,0)';
      BIDIRECTIONAL='TRUE';
      INPUT_LOAD='(-0.01,0.01)';
      OUTPUT_LOAD='(1.0,-1.0)';
      PINUSE='BI';
    'B7':
      PIN_NUMBER='(B7,0)';
      BIDIRECTIONAL='TRUE';
      INPUT_LOAD='(-0.01,0.01)';
      OUTPUT_LOAD='(1.0,-1.0)';
      PINUSE='BI';
    'B6':
      PIN_NUMBER='(B6,0)';
      BIDIRECTIONAL='TRUE';
      INPUT_LOAD='(-0.01,0.01)';
      OUTPUT_LOAD='(1.0,-1.0)';
      PINUSE='BI';
    'B5':
      PIN_NUMBER='(B5,0)';
      BIDIRECTIONAL='TRUE';
      INPUT_LOAD='(-0.01,0.01)';
      OUTPUT_LOAD='(1.0,-1.0)';
      PINUSE='BI';
    'C8':
      PIN_NUMBER='(C8,0)';
      BIDIRECTIONAL='TRUE';
      INPUT_LOAD='(-0.01,0.01)';
      OUTPUT_LOAD='(1.0,-1.0)';
      PINUSE='BI';
    'C7':
      PIN_NUMBER='(C7,0)';
      BIDIRECTIONAL='TRUE';
      INPUT_LOAD='(-0.01,0.01)';
      OUTPUT_LOAD='(1.0,-1.0)';
      PINUSE='BI';
    'C6':
      PIN_NUMBER='(C6,0)';
      BIDIRECTIONAL='TRUE';
      INPUT_LOAD='(-0.01,0.01)';
      OUTPUT_LOAD='(1.0,-1.0)';
      PINUSE='BI';
    'C5':
      PIN_NUMBER='(C5,0)';
      BIDIRECTIONAL='TRUE';
      INPUT_LOAD='(-0.01,0.01)';
      OUTPUT_LOAD='(1.0,-1.0)';
      PINUSE='BI';
    'D8':
      PIN_NUMBER='(D8,0)';
      BIDIRECTIONAL='TRUE';
      INPUT_LOAD='(-0.01,0.01)';
      OUTPUT_LOAD='(1.0,-1.0)';
      PINUSE='BI';
    'D7':
      PIN_NUMBER='(D7,0)';
      BIDIRECTIONAL='TRUE';
      INPUT_LOAD='(-0.01,0.01)';
      OUTPUT_LOAD='(1.0,-1.0)';
      PINUSE='BI';
    'D6':
      PIN_NUMBER='(D6,0)';
      BIDIRECTIONAL='TRUE';
      INPUT_LOAD='(-0.01,0.01)';
      OUTPUT_LOAD='(1.0,-1.0)';
      PINUSE='BI';
    'D5':
      PIN_NUMBER='(D5,0)';
      BIDIRECTIONAL='TRUE';
      INPUT_LOAD='(-0.01,0.01)';
      OUTPUT_LOAD='(1.0,-1.0)';
      PINUSE='BI';
    'E8':
      PIN_NUMBER='(E8,0)';
      BIDIRECTIONAL='TRUE';
      INPUT_LOAD='(-0.01,0.01)';
      OUTPUT_LOAD='(1.0,-1.0)';
      PINUSE='BI';
    'E7':
      PIN_NUMBER='(E7,0)';
      BIDIRECTIONAL='TRUE';
      INPUT_LOAD='(-0.01,0.01)';
      OUTPUT_LOAD='(1.0,-1.0)';
      PINUSE='BI';
    'E6':
      PIN_NUMBER='(E6,0)';
      BIDIRECTIONAL='TRUE';
      INPUT_LOAD='(-0.01,0.01)';
      OUTPUT_LOAD='(1.0,-1.0)';
      PINUSE='BI';
    'E5':
      PIN_NUMBER='(E5,0)';
      BIDIRECTIONAL='TRUE';
      INPUT_LOAD='(-0.01,0.01)';
      OUTPUT_LOAD='(1.0,-1.0)';
      PINUSE='BI';
    'F8':
      PIN_NUMBER='(F8,0)';
      BIDIRECTIONAL='TRUE';
      INPUT_LOAD='(-0.01,0.01)';
      OUTPUT_LOAD='(1.0,-1.0)';
      PINUSE='BI';
    'F7':
      PIN_NUMBER='(F7,0)';
      BIDIRECTIONAL='TRUE';
      INPUT_LOAD='(-0.01,0.01)';
      OUTPUT_LOAD='(1.0,-1.0)';
      PINUSE='BI';
    'F6':
      PIN_NUMBER='(F6,0)';
      BIDIRECTIONAL='TRUE';
      INPUT_LOAD='(-0.01,0.01)';
      OUTPUT_LOAD='(1.0,-1.0)';
      PINUSE='BI';
    'F5':
      PIN_NUMBER='(F5,0)';
      BIDIRECTIONAL='TRUE';
      INPUT_LOAD='(-0.01,0.01)';
      OUTPUT_LOAD='(1.0,-1.0)';
      PINUSE='BI';
    'G8':
      PIN_NUMBER='(G8,0)';
      BIDIRECTIONAL='TRUE';
      INPUT_LOAD='(-0.01,0.01)';
      OUTPUT_LOAD='(1.0,-1.0)';
      PINUSE='BI';
    'G7':
      PIN_NUMBER='(G7,0)';
      BIDIRECTIONAL='TRUE';
      INPUT_LOAD='(-0.01,0.01)';
      OUTPUT_LOAD='(1.0,-1.0)';
      PINUSE='BI';
    'G6':
      PIN_NUMBER='(G6,0)';
      BIDIRECTIONAL='TRUE';
      INPUT_LOAD='(-0.01,0.01)';
      OUTPUT_LOAD='(1.0,-1.0)';
      PINUSE='BI';
    'G5':
      PIN_NUMBER='(G5,0)';
      BIDIRECTIONAL='TRUE';
      INPUT_LOAD='(-0.01,0.01)';
      OUTPUT_LOAD='(1.0,-1.0)';
      PINUSE='BI';
    'H8':
      PIN_NUMBER='(H8,0)';
      BIDIRECTIONAL='TRUE';
      INPUT_LOAD='(-0.01,0.01)';
      OUTPUT_LOAD='(1.0,-1.0)';
      PINUSE='BI';
    'H7':
      PIN_NUMBER='(H7,0)';
      BIDIRECTIONAL='TRUE';
      INPUT_LOAD='(-0.01,0.01)';
      OUTPUT_LOAD='(1.0,-1.0)';
      PINUSE='BI';
    'H6':
      PIN_NUMBER='(H6,0)';
      BIDIRECTIONAL='TRUE';
      INPUT_LOAD='(-0.01,0.01)';
      OUTPUT_LOAD='(1.0,-1.0)';
      PINUSE='BI';
    'H5':
      PIN_NUMBER='(H5,0)';
      BIDIRECTIONAL='TRUE';
      INPUT_LOAD='(-0.01,0.01)';
      OUTPUT_LOAD='(1.0,-1.0)';
      PINUSE='BI';
    'I8':
      PIN_NUMBER='(I8,0)';
      BIDIRECTIONAL='TRUE';
      INPUT_LOAD='(-0.01,0.01)';
      OUTPUT_LOAD='(1.0,-1.0)';
      PINUSE='BI';
    'I7':
      PIN_NUMBER='(I7,0)';
      BIDIRECTIONAL='TRUE';
      INPUT_LOAD='(-0.01,0.01)';
      OUTPUT_LOAD='(1.0,-1.0)';
      PINUSE='BI';
    'I6':
      PIN_NUMBER='(I6,0)';
      BIDIRECTIONAL='TRUE';
      INPUT_LOAD='(-0.01,0.01)';
      OUTPUT_LOAD='(1.0,-1.0)';
      PINUSE='BI';
    'I5':
      PIN_NUMBER='(I5,0)';
      BIDIRECTIONAL='TRUE';
      INPUT_LOAD='(-0.01,0.01)';
      OUTPUT_LOAD='(1.0,-1.0)';
      PINUSE='BI';
    'J8':
      PIN_NUMBER='(J8,0)';
      BIDIRECTIONAL='TRUE';
      INPUT_LOAD='(-0.01,0.01)';
      OUTPUT_LOAD='(1.0,-1.0)';
      PINUSE='BI';
    'J7':
      PIN_NUMBER='(J7,0)';
      BIDIRECTIONAL='TRUE';
      INPUT_LOAD='(-0.01,0.01)';
      OUTPUT_LOAD='(1.0,-1.0)';
      PINUSE='BI';
    'J6':
      PIN_NUMBER='(J6,0)';
      BIDIRECTIONAL='TRUE';
      INPUT_LOAD='(-0.01,0.01)';
      OUTPUT_LOAD='(1.0,-1.0)';
      PINUSE='BI';
    'J5':
      PIN_NUMBER='(J5,0)';
      BIDIRECTIONAL='TRUE';
      INPUT_LOAD='(-0.01,0.01)';
      OUTPUT_LOAD='(1.0,-1.0)';
      PINUSE='BI';
    'K8':
      PIN_NUMBER='(K8,0)';
      BIDIRECTIONAL='TRUE';
      INPUT_LOAD='(-0.01,0.01)';
      OUTPUT_LOAD='(1.0,-1.0)';
      PINUSE='BI';
    'K7':
      PIN_NUMBER='(K7,0)';
      BIDIRECTIONAL='TRUE';
      INPUT_LOAD='(-0.01,0.01)';
      OUTPUT_LOAD='(1.0,-1.0)';
      PINUSE='BI';
    'K6':
      PIN_NUMBER='(K6,0)';
      BIDIRECTIONAL='TRUE';
      INPUT_LOAD='(-0.01,0.01)';
      OUTPUT_LOAD='(1.0,-1.0)';
      PINUSE='BI';
    'K5':
      PIN_NUMBER='(K5,0)';
      BIDIRECTIONAL='TRUE';
      INPUT_LOAD='(-0.01,0.01)';
      OUTPUT_LOAD='(1.0,-1.0)';
      PINUSE='BI';
    'L8':
      PIN_NUMBER='(L8,0)';
      BIDIRECTIONAL='TRUE';
      INPUT_LOAD='(-0.01,0.01)';
      OUTPUT_LOAD='(1.0,-1.0)';
      PINUSE='BI';
    'L7':
      PIN_NUMBER='(L7,0)';
      BIDIRECTIONAL='TRUE';
      INPUT_LOAD='(-0.01,0.01)';
      OUTPUT_LOAD='(1.0,-1.0)';
      PINUSE='BI';
    'L6':
      PIN_NUMBER='(L6,0)';
      BIDIRECTIONAL='TRUE';
      INPUT_LOAD='(-0.01,0.01)';
      OUTPUT_LOAD='(1.0,-1.0)';
      PINUSE='BI';
    'L5':
      PIN_NUMBER='(L5,0)';
      BIDIRECTIONAL='TRUE';
      INPUT_LOAD='(-0.01,0.01)';
      OUTPUT_LOAD='(1.0,-1.0)';
      PINUSE='BI';
    'M5':
      PIN_NUMBER='(M5,0)';
      BIDIRECTIONAL='TRUE';
      INPUT_LOAD='(-0.01,0.01)';
      OUTPUT_LOAD='(1.0,-1.0)';
      PINUSE='BI';
    'N5':
      PIN_NUMBER='(N5,0)';
      BIDIRECTIONAL='TRUE';
      INPUT_LOAD='(-0.01,0.01)';
      OUTPUT_LOAD='(1.0,-1.0)';
      PINUSE='BI';
    'M6':
      PIN_NUMBER='(M6,0)';
      BIDIRECTIONAL='TRUE';
      INPUT_LOAD='(-0.01,0.01)';
      OUTPUT_LOAD='(1.0,-1.0)';
      PINUSE='BI';
    'N6':
      PIN_NUMBER='(N6,0)';
      BIDIRECTIONAL='TRUE';
      INPUT_LOAD='(-0.01,0.01)';
      OUTPUT_LOAD='(1.0,-1.0)';
      PINUSE='BI';
    'M7':
      PIN_NUMBER='(M7,0)';
      BIDIRECTIONAL='TRUE';
      INPUT_LOAD='(-0.01,0.01)';
      OUTPUT_LOAD='(1.0,-1.0)';
      PINUSE='BI';
    'N7':
      PIN_NUMBER='(N7,0)';
      BIDIRECTIONAL='TRUE';
      INPUT_LOAD='(-0.01,0.01)';
      OUTPUT_LOAD='(1.0,-1.0)';
      PINUSE='BI';
    'M8':
      PIN_NUMBER='(M8,0)';
      BIDIRECTIONAL='TRUE';
      INPUT_LOAD='(-0.01,0.01)';
      OUTPUT_LOAD='(1.0,-1.0)';
      PINUSE='BI';
    'N8':
      PIN_NUMBER='(N8,0)';
      BIDIRECTIONAL='TRUE';
      INPUT_LOAD='(-0.01,0.01)';
      OUTPUT_LOAD='(1.0,-1.0)';
      PINUSE='BI';
    'A4':
      PIN_NUMBER='(0,A4)';
      BIDIRECTIONAL='TRUE';
      INPUT_LOAD='(-0.01,0.01)';
      OUTPUT_LOAD='(1.0,-1.0)';
      PINUSE='BI';
    'A3':
      PIN_NUMBER='(0,A3)';
      BIDIRECTIONAL='TRUE';
      INPUT_LOAD='(-0.01,0.01)';
      OUTPUT_LOAD='(1.0,-1.0)';
      PINUSE='BI';
    'A2':
      PIN_NUMBER='(0,A2)';
      BIDIRECTIONAL='TRUE';
      INPUT_LOAD='(-0.01,0.01)';
      OUTPUT_LOAD='(1.0,-1.0)';
      PINUSE='BI';
    'A1':
      PIN_NUMBER='(0,A1)';
      BIDIRECTIONAL='TRUE';
      INPUT_LOAD='(-0.01,0.01)';
      OUTPUT_LOAD='(1.0,-1.0)';
      PINUSE='BI';
    'B4':
      PIN_NUMBER='(0,B4)';
      BIDIRECTIONAL='TRUE';
      INPUT_LOAD='(-0.01,0.01)';
      OUTPUT_LOAD='(1.0,-1.0)';
      PINUSE='BI';
    'B3':
      PIN_NUMBER='(0,B3)';
      BIDIRECTIONAL='TRUE';
      INPUT_LOAD='(-0.01,0.01)';
      OUTPUT_LOAD='(1.0,-1.0)';
      PINUSE='BI';
    'B2':
      PIN_NUMBER='(0,B2)';
      BIDIRECTIONAL='TRUE';
      INPUT_LOAD='(-0.01,0.01)';
      OUTPUT_LOAD='(1.0,-1.0)';
      PINUSE='BI';
    'B1':
      PIN_NUMBER='(0,B1)';
      BIDIRECTIONAL='TRUE';
      INPUT_LOAD='(-0.01,0.01)';
      OUTPUT_LOAD='(1.0,-1.0)';
      PINUSE='BI';
    'C4':
      PIN_NUMBER='(0,C4)';
      BIDIRECTIONAL='TRUE';
      INPUT_LOAD='(-0.01,0.01)';
      OUTPUT_LOAD='(1.0,-1.0)';
      PINUSE='BI';
    'C3':
      PIN_NUMBER='(0,C3)';
      BIDIRECTIONAL='TRUE';
      INPUT_LOAD='(-0.01,0.01)';
      OUTPUT_LOAD='(1.0,-1.0)';
      PINUSE='BI';
    'C2':
      PIN_NUMBER='(0,C2)';
      BIDIRECTIONAL='TRUE';
      INPUT_LOAD='(-0.01,0.01)';
      OUTPUT_LOAD='(1.0,-1.0)';
      PINUSE='BI';
    'C1':
      PIN_NUMBER='(0,C1)';
      BIDIRECTIONAL='TRUE';
      INPUT_LOAD='(-0.01,0.01)';
      OUTPUT_LOAD='(1.0,-1.0)';
      PINUSE='BI';
    'D4':
      PIN_NUMBER='(0,D4)';
      BIDIRECTIONAL='TRUE';
      INPUT_LOAD='(-0.01,0.01)';
      OUTPUT_LOAD='(1.0,-1.0)';
      PINUSE='BI';
    'D3':
      PIN_NUMBER='(0,D3)';
      BIDIRECTIONAL='TRUE';
      INPUT_LOAD='(-0.01,0.01)';
      OUTPUT_LOAD='(1.0,-1.0)';
      PINUSE='BI';
    'D2':
      PIN_NUMBER='(0,D2)';
      BIDIRECTIONAL='TRUE';
      INPUT_LOAD='(-0.01,0.01)';
      OUTPUT_LOAD='(1.0,-1.0)';
      PINUSE='BI';
    'D1':
      PIN_NUMBER='(0,D1)';
      BIDIRECTIONAL='TRUE';
      INPUT_LOAD='(-0.01,0.01)';
      OUTPUT_LOAD='(1.0,-1.0)';
      PINUSE='BI';
    'E4':
      PIN_NUMBER='(0,E4)';
      BIDIRECTIONAL='TRUE';
      INPUT_LOAD='(-0.01,0.01)';
      OUTPUT_LOAD='(1.0,-1.0)';
      PINUSE='BI';
    'E3':
      PIN_NUMBER='(0,E3)';
      BIDIRECTIONAL='TRUE';
      INPUT_LOAD='(-0.01,0.01)';
      OUTPUT_LOAD='(1.0,-1.0)';
      PINUSE='BI';
    'E2':
      PIN_NUMBER='(0,E2)';
      BIDIRECTIONAL='TRUE';
      INPUT_LOAD='(-0.01,0.01)';
      OUTPUT_LOAD='(1.0,-1.0)';
      PINUSE='BI';
    'E1':
      PIN_NUMBER='(0,E1)';
      BIDIRECTIONAL='TRUE';
      INPUT_LOAD='(-0.01,0.01)';
      OUTPUT_LOAD='(1.0,-1.0)';
      PINUSE='BI';
    'F4':
      PIN_NUMBER='(0,F4)';
      BIDIRECTIONAL='TRUE';
      INPUT_LOAD='(-0.01,0.01)';
      OUTPUT_LOAD='(1.0,-1.0)';
      PINUSE='BI';
    'F3':
      PIN_NUMBER='(0,F3)';
      BIDIRECTIONAL='TRUE';
      INPUT_LOAD='(-0.01,0.01)';
      OUTPUT_LOAD='(1.0,-1.0)';
      PINUSE='BI';
    'F2':
      PIN_NUMBER='(0,F2)';
      BIDIRECTIONAL='TRUE';
      INPUT_LOAD='(-0.01,0.01)';
      OUTPUT_LOAD='(1.0,-1.0)';
      PINUSE='BI';
    'F1':
      PIN_NUMBER='(0,F1)';
      BIDIRECTIONAL='TRUE';
      INPUT_LOAD='(-0.01,0.01)';
      OUTPUT_LOAD='(1.0,-1.0)';
      PINUSE='BI';
    'G4':
      PIN_NUMBER='(0,G4)';
      BIDIRECTIONAL='TRUE';
      INPUT_LOAD='(-0.01,0.01)';
      OUTPUT_LOAD='(1.0,-1.0)';
      PINUSE='BI';
    'G3':
      PIN_NUMBER='(0,G3)';
      BIDIRECTIONAL='TRUE';
      INPUT_LOAD='(-0.01,0.01)';
      OUTPUT_LOAD='(1.0,-1.0)';
      PINUSE='BI';
    'G2':
      PIN_NUMBER='(0,G2)';
      BIDIRECTIONAL='TRUE';
      INPUT_LOAD='(-0.01,0.01)';
      OUTPUT_LOAD='(1.0,-1.0)';
      PINUSE='BI';
    'G1':
      PIN_NUMBER='(0,G1)';
      BIDIRECTIONAL='TRUE';
      INPUT_LOAD='(-0.01,0.01)';
      OUTPUT_LOAD='(1.0,-1.0)';
      PINUSE='BI';
    'H4':
      PIN_NUMBER='(0,H4)';
      BIDIRECTIONAL='TRUE';
      INPUT_LOAD='(-0.01,0.01)';
      OUTPUT_LOAD='(1.0,-1.0)';
      PINUSE='BI';
    'H3':
      PIN_NUMBER='(0,H3)';
      BIDIRECTIONAL='TRUE';
      INPUT_LOAD='(-0.01,0.01)';
      OUTPUT_LOAD='(1.0,-1.0)';
      PINUSE='BI';
    'H2':
      PIN_NUMBER='(0,H2)';
      BIDIRECTIONAL='TRUE';
      INPUT_LOAD='(-0.01,0.01)';
      OUTPUT_LOAD='(1.0,-1.0)';
      PINUSE='BI';
    'H1':
      PIN_NUMBER='(0,H1)';
      BIDIRECTIONAL='TRUE';
      INPUT_LOAD='(-0.01,0.01)';
      OUTPUT_LOAD='(1.0,-1.0)';
      PINUSE='BI';
    'I4':
      PIN_NUMBER='(0,I4)';
      BIDIRECTIONAL='TRUE';
      INPUT_LOAD='(-0.01,0.01)';
      OUTPUT_LOAD='(1.0,-1.0)';
      PINUSE='BI';
    'I3':
      PIN_NUMBER='(0,I3)';
      BIDIRECTIONAL='TRUE';
      INPUT_LOAD='(-0.01,0.01)';
      OUTPUT_LOAD='(1.0,-1.0)';
      PINUSE='BI';
    'I2':
      PIN_NUMBER='(0,I2)';
      BIDIRECTIONAL='TRUE';
      INPUT_LOAD='(-0.01,0.01)';
      OUTPUT_LOAD='(1.0,-1.0)';
      PINUSE='BI';
    'I1':
      PIN_NUMBER='(0,I1)';
      BIDIRECTIONAL='TRUE';
      INPUT_LOAD='(-0.01,0.01)';
      OUTPUT_LOAD='(1.0,-1.0)';
      PINUSE='BI';
    'J4':
      PIN_NUMBER='(0,J4)';
      BIDIRECTIONAL='TRUE';
      INPUT_LOAD='(-0.01,0.01)';
      OUTPUT_LOAD='(1.0,-1.0)';
      PINUSE='BI';
    'J3':
      PIN_NUMBER='(0,J3)';
      BIDIRECTIONAL='TRUE';
      INPUT_LOAD='(-0.01,0.01)';
      OUTPUT_LOAD='(1.0,-1.0)';
      PINUSE='BI';
    'J2':
      PIN_NUMBER='(0,J2)';
      BIDIRECTIONAL='TRUE';
      INPUT_LOAD='(-0.01,0.01)';
      OUTPUT_LOAD='(1.0,-1.0)';
      PINUSE='BI';
    'J1':
      PIN_NUMBER='(0,J1)';
      BIDIRECTIONAL='TRUE';
      INPUT_LOAD='(-0.01,0.01)';
      OUTPUT_LOAD='(1.0,-1.0)';
      PINUSE='BI';
    'K4':
      PIN_NUMBER='(0,K4)';
      BIDIRECTIONAL='TRUE';
      INPUT_LOAD='(-0.01,0.01)';
      OUTPUT_LOAD='(1.0,-1.0)';
      PINUSE='BI';
    'K3':
      PIN_NUMBER='(0,K3)';
      BIDIRECTIONAL='TRUE';
      INPUT_LOAD='(-0.01,0.01)';
      OUTPUT_LOAD='(1.0,-1.0)';
      PINUSE='BI';
    'K2':
      PIN_NUMBER='(0,K2)';
      BIDIRECTIONAL='TRUE';
      INPUT_LOAD='(-0.01,0.01)';
      OUTPUT_LOAD='(1.0,-1.0)';
      PINUSE='BI';
    'K1':
      PIN_NUMBER='(0,K1)';
      BIDIRECTIONAL='TRUE';
      INPUT_LOAD='(-0.01,0.01)';
      OUTPUT_LOAD='(1.0,-1.0)';
      PINUSE='BI';
    'L4':
      PIN_NUMBER='(0,L4)';
      BIDIRECTIONAL='TRUE';
      INPUT_LOAD='(-0.01,0.01)';
      OUTPUT_LOAD='(1.0,-1.0)';
      PINUSE='BI';
    'L3':
      PIN_NUMBER='(0,L3)';
      BIDIRECTIONAL='TRUE';
      INPUT_LOAD='(-0.01,0.01)';
      OUTPUT_LOAD='(1.0,-1.0)';
      PINUSE='BI';
    'L2':
      PIN_NUMBER='(0,L2)';
      BIDIRECTIONAL='TRUE';
      INPUT_LOAD='(-0.01,0.01)';
      OUTPUT_LOAD='(1.0,-1.0)';
      PINUSE='BI';
    'L1':
      PIN_NUMBER='(0,L1)';
      BIDIRECTIONAL='TRUE';
      INPUT_LOAD='(-0.01,0.01)';
      OUTPUT_LOAD='(1.0,-1.0)';
      PINUSE='BI';
    'M1':
      PIN_NUMBER='(0,M1)';
      BIDIRECTIONAL='TRUE';
      INPUT_LOAD='(-0.01,0.01)';
      OUTPUT_LOAD='(1.0,-1.0)';
      PINUSE='BI';
    'N1':
      PIN_NUMBER='(0,N1)';
      BIDIRECTIONAL='TRUE';
      INPUT_LOAD='(-0.01,0.01)';
      OUTPUT_LOAD='(1.0,-1.0)';
      PINUSE='BI';
    'M2':
      PIN_NUMBER='(0,M2)';
      BIDIRECTIONAL='TRUE';
      INPUT_LOAD='(-0.01,0.01)';
      OUTPUT_LOAD='(1.0,-1.0)';
      PINUSE='BI';
    'N2':
      PIN_NUMBER='(0,N2)';
      BIDIRECTIONAL='TRUE';
      INPUT_LOAD='(-0.01,0.01)';
      OUTPUT_LOAD='(1.0,-1.0)';
      PINUSE='BI';
    'M3':
      PIN_NUMBER='(0,M3)';
      BIDIRECTIONAL='TRUE';
      INPUT_LOAD='(-0.01,0.01)';
      OUTPUT_LOAD='(1.0,-1.0)';
      PINUSE='BI';
    'N3':
      PIN_NUMBER='(0,N3)';
      BIDIRECTIONAL='TRUE';
      INPUT_LOAD='(-0.01,0.01)';
      OUTPUT_LOAD='(1.0,-1.0)';
      PINUSE='BI';
    'M4':
      PIN_NUMBER='(0,M4)';
      BIDIRECTIONAL='TRUE';
      INPUT_LOAD='(-0.01,0.01)';
      OUTPUT_LOAD='(1.0,-1.0)';
      PINUSE='BI';
    'N4':
      PIN_NUMBER='(0,N4)';
      BIDIRECTIONAL='TRUE';
      INPUT_LOAD='(-0.01,0.01)';
      OUTPUT_LOAD='(1.0,-1.0)';
      PINUSE='BI';
  end_pin;
  body
      PART_NAME='CONN112_10137002101LF';
      BODY_NAME='CONN112_10137002101LF';
      PHYS_DES_PREFIX='J';
      CLASS='IO';
      STANDARD='';
      LIFECYCLE='';
      PART_NUMBER='DFHSB2FR012';
      JEDEC_TYPE='HSD_F112D8_P2W1-2_RDH';
      DESCRIPTION='CONN DIP HOUSING 112P 8R FR(P1.2,H17.9)';
      MANUFTR='BER';
      MANUF_PN='10137002-101LF';
      RD_CMPLS_LVL='EP(V1)';
      CMPLS_LVL='';
      DIP_SMD='DIP';
      FROM_PJ='JG5-ALBERT';
      DATA='BER_10137002-101LF';
      FP_ECN='';
      EE_CHECK_LIST='';
      CREATOR='';
      CREATEDAY='20180413';
      PSL='';
      STATUS='';
      ESD_CDM='NA';
      ESD_HBM='NA';
      ESD_MM='NA';
      MSD='NA';
      PIN_LENGTH_LONG_PIN='71 MILS';
      PIN_LENGTH_SHORT_PIN='63 MILS';
      PARENT_PART_TYPE='CONN112_10137002101LF';
      PARENT_PPT='CONN112_10137002101LF';
      PARENT_PPT_PART='CONN112_10137002101LF-CONN112_10137002-101LF,THLF,IO,DFHSB2FR012';
  end_body;
end_primitive;
primitive 'CONN160_10131762101LF-CONN160_10131762-101LF,THLF,A';
  pin
    'A8':
      PIN_NUMBER='(A8,0)';
      BIDIRECTIONAL='TRUE';
      INPUT_LOAD='(-0.01,0.01)';
      OUTPUT_LOAD='(1.0,-1.0)';
      PINUSE='BI';
    'A7':
      PIN_NUMBER='(A7,0)';
      BIDIRECTIONAL='TRUE';
      INPUT_LOAD='(-0.01,0.01)';
      OUTPUT_LOAD='(1.0,-1.0)';
      PINUSE='BI';
    'A6':
      PIN_NUMBER='(A6,0)';
      BIDIRECTIONAL='TRUE';
      INPUT_LOAD='(-0.01,0.01)';
      OUTPUT_LOAD='(1.0,-1.0)';
      PINUSE='BI';
    'A5':
      PIN_NUMBER='(A5,0)';
      BIDIRECTIONAL='TRUE';
      INPUT_LOAD='(-0.01,0.01)';
      OUTPUT_LOAD='(1.0,-1.0)';
      PINUSE='BI';
    'B8':
      PIN_NUMBER='(B8,0)';
      BIDIRECTIONAL='TRUE';
      INPUT_LOAD='(-0.01,0.01)';
      OUTPUT_LOAD='(1.0,-1.0)';
      PINUSE='BI';
    'B7':
      PIN_NUMBER='(B7,0)';
      BIDIRECTIONAL='TRUE';
      INPUT_LOAD='(-0.01,0.01)';
      OUTPUT_LOAD='(1.0,-1.0)';
      PINUSE='BI';
    'B6':
      PIN_NUMBER='(B6,0)';
      BIDIRECTIONAL='TRUE';
      INPUT_LOAD='(-0.01,0.01)';
      OUTPUT_LOAD='(1.0,-1.0)';
      PINUSE='BI';
    'B5':
      PIN_NUMBER='(B5,0)';
      BIDIRECTIONAL='TRUE';
      INPUT_LOAD='(-0.01,0.01)';
      OUTPUT_LOAD='(1.0,-1.0)';
      PINUSE='BI';
    'C8':
      PIN_NUMBER='(C8,0)';
      BIDIRECTIONAL='TRUE';
      INPUT_LOAD='(-0.01,0.01)';
      OUTPUT_LOAD='(1.0,-1.0)';
      PINUSE='BI';
    'C7':
      PIN_NUMBER='(C7,0)';
      BIDIRECTIONAL='TRUE';
      INPUT_LOAD='(-0.01,0.01)';
      OUTPUT_LOAD='(1.0,-1.0)';
      PINUSE='BI';
    'C6':
      PIN_NUMBER='(C6,0)';
      BIDIRECTIONAL='TRUE';
      INPUT_LOAD='(-0.01,0.01)';
      OUTPUT_LOAD='(1.0,-1.0)';
      PINUSE='BI';
    'C5':
      PIN_NUMBER='(C5,0)';
      BIDIRECTIONAL='TRUE';
      INPUT_LOAD='(-0.01,0.01)';
      OUTPUT_LOAD='(1.0,-1.0)';
      PINUSE='BI';
    'D8':
      PIN_NUMBER='(D8,0)';
      BIDIRECTIONAL='TRUE';
      INPUT_LOAD='(-0.01,0.01)';
      OUTPUT_LOAD='(1.0,-1.0)';
      PINUSE='BI';
    'D7':
      PIN_NUMBER='(D7,0)';
      BIDIRECTIONAL='TRUE';
      INPUT_LOAD='(-0.01,0.01)';
      OUTPUT_LOAD='(1.0,-1.0)';
      PINUSE='BI';
    'D6':
      PIN_NUMBER='(D6,0)';
      BIDIRECTIONAL='TRUE';
      INPUT_LOAD='(-0.01,0.01)';
      OUTPUT_LOAD='(1.0,-1.0)';
      PINUSE='BI';
    'D5':
      PIN_NUMBER='(D5,0)';
      BIDIRECTIONAL='TRUE';
      INPUT_LOAD='(-0.01,0.01)';
      OUTPUT_LOAD='(1.0,-1.0)';
      PINUSE='BI';
    'E8':
      PIN_NUMBER='(E8,0)';
      BIDIRECTIONAL='TRUE';
      INPUT_LOAD='(-0.01,0.01)';
      OUTPUT_LOAD='(1.0,-1.0)';
      PINUSE='BI';
    'E7':
      PIN_NUMBER='(E7,0)';
      BIDIRECTIONAL='TRUE';
      INPUT_LOAD='(-0.01,0.01)';
      OUTPUT_LOAD='(1.0,-1.0)';
      PINUSE='BI';
    'E6':
      PIN_NUMBER='(E6,0)';
      BIDIRECTIONAL='TRUE';
      INPUT_LOAD='(-0.01,0.01)';
      OUTPUT_LOAD='(1.0,-1.0)';
      PINUSE='BI';
    'E5':
      PIN_NUMBER='(E5,0)';
      BIDIRECTIONAL='TRUE';
      INPUT_LOAD='(-0.01,0.01)';
      OUTPUT_LOAD='(1.0,-1.0)';
      PINUSE='BI';
    'F8':
      PIN_NUMBER='(F8,0)';
      BIDIRECTIONAL='TRUE';
      INPUT_LOAD='(-0.01,0.01)';
      OUTPUT_LOAD='(1.0,-1.0)';
      PINUSE='BI';
    'F7':
      PIN_NUMBER='(F7,0)';
      BIDIRECTIONAL='TRUE';
      INPUT_LOAD='(-0.01,0.01)';
      OUTPUT_LOAD='(1.0,-1.0)';
      PINUSE='BI';
    'F6':
      PIN_NUMBER='(F6,0)';
      BIDIRECTIONAL='TRUE';
      INPUT_LOAD='(-0.01,0.01)';
      OUTPUT_LOAD='(1.0,-1.0)';
      PINUSE='BI';
    'F5':
      PIN_NUMBER='(F5,0)';
      BIDIRECTIONAL='TRUE';
      INPUT_LOAD='(-0.01,0.01)';
      OUTPUT_LOAD='(1.0,-1.0)';
      PINUSE='BI';
    'G8':
      PIN_NUMBER='(G8,0)';
      BIDIRECTIONAL='TRUE';
      INPUT_LOAD='(-0.01,0.01)';
      OUTPUT_LOAD='(1.0,-1.0)';
      PINUSE='BI';
    'G7':
      PIN_NUMBER='(G7,0)';
      BIDIRECTIONAL='TRUE';
      INPUT_LOAD='(-0.01,0.01)';
      OUTPUT_LOAD='(1.0,-1.0)';
      PINUSE='BI';
    'G6':
      PIN_NUMBER='(G6,0)';
      BIDIRECTIONAL='TRUE';
      INPUT_LOAD='(-0.01,0.01)';
      OUTPUT_LOAD='(1.0,-1.0)';
      PINUSE='BI';
    'G5':
      PIN_NUMBER='(G5,0)';
      BIDIRECTIONAL='TRUE';
      INPUT_LOAD='(-0.01,0.01)';
      OUTPUT_LOAD='(1.0,-1.0)';
      PINUSE='BI';
    'H8':
      PIN_NUMBER='(H8,0)';
      BIDIRECTIONAL='TRUE';
      INPUT_LOAD='(-0.01,0.01)';
      OUTPUT_LOAD='(1.0,-1.0)';
      PINUSE='BI';
    'H7':
      PIN_NUMBER='(H7,0)';
      BIDIRECTIONAL='TRUE';
      INPUT_LOAD='(-0.01,0.01)';
      OUTPUT_LOAD='(1.0,-1.0)';
      PINUSE='BI';
    'H6':
      PIN_NUMBER='(H6,0)';
      BIDIRECTIONAL='TRUE';
      INPUT_LOAD='(-0.01,0.01)';
      OUTPUT_LOAD='(1.0,-1.0)';
      PINUSE='BI';
    'H5':
      PIN_NUMBER='(H5,0)';
      BIDIRECTIONAL='TRUE';
      INPUT_LOAD='(-0.01,0.01)';
      OUTPUT_LOAD='(1.0,-1.0)';
      PINUSE='BI';
    'I8':
      PIN_NUMBER='(I8,0)';
      BIDIRECTIONAL='TRUE';
      INPUT_LOAD='(-0.01,0.01)';
      OUTPUT_LOAD='(1.0,-1.0)';
      PINUSE='BI';
    'I7':
      PIN_NUMBER='(I7,0)';
      BIDIRECTIONAL='TRUE';
      INPUT_LOAD='(-0.01,0.01)';
      OUTPUT_LOAD='(1.0,-1.0)';
      PINUSE='BI';
    'I6':
      PIN_NUMBER='(I6,0)';
      BIDIRECTIONAL='TRUE';
      INPUT_LOAD='(-0.01,0.01)';
      OUTPUT_LOAD='(1.0,-1.0)';
      PINUSE='BI';
    'I5':
      PIN_NUMBER='(I5,0)';
      BIDIRECTIONAL='TRUE';
      INPUT_LOAD='(-0.01,0.01)';
      OUTPUT_LOAD='(1.0,-1.0)';
      PINUSE='BI';
    'J8':
      PIN_NUMBER='(J8,0)';
      BIDIRECTIONAL='TRUE';
      INPUT_LOAD='(-0.01,0.01)';
      OUTPUT_LOAD='(1.0,-1.0)';
      PINUSE='BI';
    'J7':
      PIN_NUMBER='(J7,0)';
      BIDIRECTIONAL='TRUE';
      INPUT_LOAD='(-0.01,0.01)';
      OUTPUT_LOAD='(1.0,-1.0)';
      PINUSE='BI';
    'J6':
      PIN_NUMBER='(J6,0)';
      BIDIRECTIONAL='TRUE';
      INPUT_LOAD='(-0.01,0.01)';
      OUTPUT_LOAD='(1.0,-1.0)';
      PINUSE='BI';
    'J5':
      PIN_NUMBER='(J5,0)';
      BIDIRECTIONAL='TRUE';
      INPUT_LOAD='(-0.01,0.01)';
      OUTPUT_LOAD='(1.0,-1.0)';
      PINUSE='BI';
    'K8':
      PIN_NUMBER='(K8,0)';
      BIDIRECTIONAL='TRUE';
      INPUT_LOAD='(-0.01,0.01)';
      OUTPUT_LOAD='(1.0,-1.0)';
      PINUSE='BI';
    'K7':
      PIN_NUMBER='(K7,0)';
      BIDIRECTIONAL='TRUE';
      INPUT_LOAD='(-0.01,0.01)';
      OUTPUT_LOAD='(1.0,-1.0)';
      PINUSE='BI';
    'K6':
      PIN_NUMBER='(K6,0)';
      BIDIRECTIONAL='TRUE';
      INPUT_LOAD='(-0.01,0.01)';
      OUTPUT_LOAD='(1.0,-1.0)';
      PINUSE='BI';
    'K5':
      PIN_NUMBER='(K5,0)';
      BIDIRECTIONAL='TRUE';
      INPUT_LOAD='(-0.01,0.01)';
      OUTPUT_LOAD='(1.0,-1.0)';
      PINUSE='BI';
    'L8':
      PIN_NUMBER='(L8,0)';
      BIDIRECTIONAL='TRUE';
      INPUT_LOAD='(-0.01,0.01)';
      OUTPUT_LOAD='(1.0,-1.0)';
      PINUSE='BI';
    'L7':
      PIN_NUMBER='(L7,0)';
      BIDIRECTIONAL='TRUE';
      INPUT_LOAD='(-0.01,0.01)';
      OUTPUT_LOAD='(1.0,-1.0)';
      PINUSE='BI';
    'L6':
      PIN_NUMBER='(L6,0)';
      BIDIRECTIONAL='TRUE';
      INPUT_LOAD='(-0.01,0.01)';
      OUTPUT_LOAD='(1.0,-1.0)';
      PINUSE='BI';
    'L5':
      PIN_NUMBER='(L5,0)';
      BIDIRECTIONAL='TRUE';
      INPUT_LOAD='(-0.01,0.01)';
      OUTPUT_LOAD='(1.0,-1.0)';
      PINUSE='BI';
    'M5':
      PIN_NUMBER='(M5,0)';
      BIDIRECTIONAL='TRUE';
      INPUT_LOAD='(-0.01,0.01)';
      OUTPUT_LOAD='(1.0,-1.0)';
      PINUSE='BI';
    'N5':
      PIN_NUMBER='(N5,0)';
      BIDIRECTIONAL='TRUE';
      INPUT_LOAD='(-0.01,0.01)';
      OUTPUT_LOAD='(1.0,-1.0)';
      PINUSE='BI';
    'M6':
      PIN_NUMBER='(M6,0)';
      BIDIRECTIONAL='TRUE';
      INPUT_LOAD='(-0.01,0.01)';
      OUTPUT_LOAD='(1.0,-1.0)';
      PINUSE='BI';
    'N6':
      PIN_NUMBER='(N6,0)';
      BIDIRECTIONAL='TRUE';
      INPUT_LOAD='(-0.01,0.01)';
      OUTPUT_LOAD='(1.0,-1.0)';
      PINUSE='BI';
    'M7':
      PIN_NUMBER='(M7,0)';
      BIDIRECTIONAL='TRUE';
      INPUT_LOAD='(-0.01,0.01)';
      OUTPUT_LOAD='(1.0,-1.0)';
      PINUSE='BI';
    'N7':
      PIN_NUMBER='(N7,0)';
      BIDIRECTIONAL='TRUE';
      INPUT_LOAD='(-0.01,0.01)';
      OUTPUT_LOAD='(1.0,-1.0)';
      PINUSE='BI';
    'M8':
      PIN_NUMBER='(M8,0)';
      BIDIRECTIONAL='TRUE';
      INPUT_LOAD='(-0.01,0.01)';
      OUTPUT_LOAD='(1.0,-1.0)';
      PINUSE='BI';
    'N8':
      PIN_NUMBER='(N8,0)';
      BIDIRECTIONAL='TRUE';
      INPUT_LOAD='(-0.01,0.01)';
      OUTPUT_LOAD='(1.0,-1.0)';
      PINUSE='BI';
    'O5':
      PIN_NUMBER='(O5,0)';
      BIDIRECTIONAL='TRUE';
      INPUT_LOAD='(-0.01,0.01)';
      OUTPUT_LOAD='(1.0,-1.0)';
      PINUSE='BI';
    'P5':
      PIN_NUMBER='(P5,0)';
      BIDIRECTIONAL='TRUE';
      INPUT_LOAD='(-0.01,0.01)';
      OUTPUT_LOAD='(1.0,-1.0)';
      PINUSE='BI';
    'Q5':
      PIN_NUMBER='(Q5,0)';
      BIDIRECTIONAL='TRUE';
      INPUT_LOAD='(-0.01,0.01)';
      OUTPUT_LOAD='(1.0,-1.0)';
      PINUSE='BI';
    'R5':
      PIN_NUMBER='(R5,0)';
      BIDIRECTIONAL='TRUE';
      INPUT_LOAD='(-0.01,0.01)';
      OUTPUT_LOAD='(1.0,-1.0)';
      PINUSE='BI';
    'S5':
      PIN_NUMBER='(S5,0)';
      BIDIRECTIONAL='TRUE';
      INPUT_LOAD='(-0.01,0.01)';
      OUTPUT_LOAD='(1.0,-1.0)';
      PINUSE='BI';
    'T5':
      PIN_NUMBER='(T5,0)';
      BIDIRECTIONAL='TRUE';
      INPUT_LOAD='(-0.01,0.01)';
      OUTPUT_LOAD='(1.0,-1.0)';
      PINUSE='BI';
    'O6':
      PIN_NUMBER='(O6,0)';
      BIDIRECTIONAL='TRUE';
      INPUT_LOAD='(-0.01,0.01)';
      OUTPUT_LOAD='(1.0,-1.0)';
      PINUSE='BI';
    'P6':
      PIN_NUMBER='(P6,0)';
      BIDIRECTIONAL='TRUE';
      INPUT_LOAD='(-0.01,0.01)';
      OUTPUT_LOAD='(1.0,-1.0)';
      PINUSE='BI';
    'Q6':
      PIN_NUMBER='(Q6,0)';
      BIDIRECTIONAL='TRUE';
      INPUT_LOAD='(-0.01,0.01)';
      OUTPUT_LOAD='(1.0,-1.0)';
      PINUSE='BI';
    'R6':
      PIN_NUMBER='(R6,0)';
      BIDIRECTIONAL='TRUE';
      INPUT_LOAD='(-0.01,0.01)';
      OUTPUT_LOAD='(1.0,-1.0)';
      PINUSE='BI';
    'S6':
      PIN_NUMBER='(S6,0)';
      BIDIRECTIONAL='TRUE';
      INPUT_LOAD='(-0.01,0.01)';
      OUTPUT_LOAD='(1.0,-1.0)';
      PINUSE='BI';
    'T6':
      PIN_NUMBER='(T6,0)';
      BIDIRECTIONAL='TRUE';
      INPUT_LOAD='(-0.01,0.01)';
      OUTPUT_LOAD='(1.0,-1.0)';
      PINUSE='BI';
    'O7':
      PIN_NUMBER='(O7,0)';
      BIDIRECTIONAL='TRUE';
      INPUT_LOAD='(-0.01,0.01)';
      OUTPUT_LOAD='(1.0,-1.0)';
      PINUSE='BI';
    'P7':
      PIN_NUMBER='(P7,0)';
      BIDIRECTIONAL='TRUE';
      INPUT_LOAD='(-0.01,0.01)';
      OUTPUT_LOAD='(1.0,-1.0)';
      PINUSE='BI';
    'Q7':
      PIN_NUMBER='(Q7,0)';
      BIDIRECTIONAL='TRUE';
      INPUT_LOAD='(-0.01,0.01)';
      OUTPUT_LOAD='(1.0,-1.0)';
      PINUSE='BI';
    'R7':
      PIN_NUMBER='(R7,0)';
      BIDIRECTIONAL='TRUE';
      INPUT_LOAD='(-0.01,0.01)';
      OUTPUT_LOAD='(1.0,-1.0)';
      PINUSE='BI';
    'S7':
      PIN_NUMBER='(S7,0)';
      BIDIRECTIONAL='TRUE';
      INPUT_LOAD='(-0.01,0.01)';
      OUTPUT_LOAD='(1.0,-1.0)';
      PINUSE='BI';
    'T7':
      PIN_NUMBER='(T7,0)';
      BIDIRECTIONAL='TRUE';
      INPUT_LOAD='(-0.01,0.01)';
      OUTPUT_LOAD='(1.0,-1.0)';
      PINUSE='BI';
    'O8':
      PIN_NUMBER='(O8,0)';
      BIDIRECTIONAL='TRUE';
      INPUT_LOAD='(-0.01,0.01)';
      OUTPUT_LOAD='(1.0,-1.0)';
      PINUSE='BI';
    'P8':
      PIN_NUMBER='(P8,0)';
      BIDIRECTIONAL='TRUE';
      INPUT_LOAD='(-0.01,0.01)';
      OUTPUT_LOAD='(1.0,-1.0)';
      PINUSE='BI';
    'Q8':
      PIN_NUMBER='(Q8,0)';
      BIDIRECTIONAL='TRUE';
      INPUT_LOAD='(-0.01,0.01)';
      OUTPUT_LOAD='(1.0,-1.0)';
      PINUSE='BI';
    'R8':
      PIN_NUMBER='(R8,0)';
      BIDIRECTIONAL='TRUE';
      INPUT_LOAD='(-0.01,0.01)';
      OUTPUT_LOAD='(1.0,-1.0)';
      PINUSE='BI';
    'S8':
      PIN_NUMBER='(S8,0)';
      BIDIRECTIONAL='TRUE';
      INPUT_LOAD='(-0.01,0.01)';
      OUTPUT_LOAD='(1.0,-1.0)';
      PINUSE='BI';
    'T8':
      PIN_NUMBER='(T8,0)';
      BIDIRECTIONAL='TRUE';
      INPUT_LOAD='(-0.01,0.01)';
      OUTPUT_LOAD='(1.0,-1.0)';
      PINUSE='BI';
    'A4':
      PIN_NUMBER='(0,A4)';
      BIDIRECTIONAL='TRUE';
      INPUT_LOAD='(-0.01,0.01)';
      OUTPUT_LOAD='(1.0,-1.0)';
      PINUSE='BI';
    'A3':
      PIN_NUMBER='(0,A3)';
      BIDIRECTIONAL='TRUE';
      INPUT_LOAD='(-0.01,0.01)';
      OUTPUT_LOAD='(1.0,-1.0)';
      PINUSE='BI';
    'A2':
      PIN_NUMBER='(0,A2)';
      BIDIRECTIONAL='TRUE';
      INPUT_LOAD='(-0.01,0.01)';
      OUTPUT_LOAD='(1.0,-1.0)';
      PINUSE='BI';
    'A1':
      PIN_NUMBER='(0,A1)';
      BIDIRECTIONAL='TRUE';
      INPUT_LOAD='(-0.01,0.01)';
      OUTPUT_LOAD='(1.0,-1.0)';
      PINUSE='BI';
    'B4':
      PIN_NUMBER='(0,B4)';
      BIDIRECTIONAL='TRUE';
      INPUT_LOAD='(-0.01,0.01)';
      OUTPUT_LOAD='(1.0,-1.0)';
      PINUSE='BI';
    'B3':
      PIN_NUMBER='(0,B3)';
      BIDIRECTIONAL='TRUE';
      INPUT_LOAD='(-0.01,0.01)';
      OUTPUT_LOAD='(1.0,-1.0)';
      PINUSE='BI';
    'B2':
      PIN_NUMBER='(0,B2)';
      BIDIRECTIONAL='TRUE';
      INPUT_LOAD='(-0.01,0.01)';
      OUTPUT_LOAD='(1.0,-1.0)';
      PINUSE='BI';
    'B1':
      PIN_NUMBER='(0,B1)';
      BIDIRECTIONAL='TRUE';
      INPUT_LOAD='(-0.01,0.01)';
      OUTPUT_LOAD='(1.0,-1.0)';
      PINUSE='BI';
    'C4':
      PIN_NUMBER='(0,C4)';
      BIDIRECTIONAL='TRUE';
      INPUT_LOAD='(-0.01,0.01)';
      OUTPUT_LOAD='(1.0,-1.0)';
      PINUSE='BI';
    'C3':
      PIN_NUMBER='(0,C3)';
      BIDIRECTIONAL='TRUE';
      INPUT_LOAD='(-0.01,0.01)';
      OUTPUT_LOAD='(1.0,-1.0)';
      PINUSE='BI';
    'C2':
      PIN_NUMBER='(0,C2)';
      BIDIRECTIONAL='TRUE';
      INPUT_LOAD='(-0.01,0.01)';
      OUTPUT_LOAD='(1.0,-1.0)';
      PINUSE='BI';
    'C1':
      PIN_NUMBER='(0,C1)';
      BIDIRECTIONAL='TRUE';
      INPUT_LOAD='(-0.01,0.01)';
      OUTPUT_LOAD='(1.0,-1.0)';
      PINUSE='BI';
    'D4':
      PIN_NUMBER='(0,D4)';
      BIDIRECTIONAL='TRUE';
      INPUT_LOAD='(-0.01,0.01)';
      OUTPUT_LOAD='(1.0,-1.0)';
      PINUSE='BI';
    'D3':
      PIN_NUMBER='(0,D3)';
      BIDIRECTIONAL='TRUE';
      INPUT_LOAD='(-0.01,0.01)';
      OUTPUT_LOAD='(1.0,-1.0)';
      PINUSE='BI';
    'D2':
      PIN_NUMBER='(0,D2)';
      BIDIRECTIONAL='TRUE';
      INPUT_LOAD='(-0.01,0.01)';
      OUTPUT_LOAD='(1.0,-1.0)';
      PINUSE='BI';
    'D1':
      PIN_NUMBER='(0,D1)';
      BIDIRECTIONAL='TRUE';
      INPUT_LOAD='(-0.01,0.01)';
      OUTPUT_LOAD='(1.0,-1.0)';
      PINUSE='BI';
    'E4':
      PIN_NUMBER='(0,E4)';
      BIDIRECTIONAL='TRUE';
      INPUT_LOAD='(-0.01,0.01)';
      OUTPUT_LOAD='(1.0,-1.0)';
      PINUSE='BI';
    'E3':
      PIN_NUMBER='(0,E3)';
      BIDIRECTIONAL='TRUE';
      INPUT_LOAD='(-0.01,0.01)';
      OUTPUT_LOAD='(1.0,-1.0)';
      PINUSE='BI';
    'E2':
      PIN_NUMBER='(0,E2)';
      BIDIRECTIONAL='TRUE';
      INPUT_LOAD='(-0.01,0.01)';
      OUTPUT_LOAD='(1.0,-1.0)';
      PINUSE='BI';
    'E1':
      PIN_NUMBER='(0,E1)';
      BIDIRECTIONAL='TRUE';
      INPUT_LOAD='(-0.01,0.01)';
      OUTPUT_LOAD='(1.0,-1.0)';
      PINUSE='BI';
    'F4':
      PIN_NUMBER='(0,F4)';
      BIDIRECTIONAL='TRUE';
      INPUT_LOAD='(-0.01,0.01)';
      OUTPUT_LOAD='(1.0,-1.0)';
      PINUSE='BI';
    'F3':
      PIN_NUMBER='(0,F3)';
      BIDIRECTIONAL='TRUE';
      INPUT_LOAD='(-0.01,0.01)';
      OUTPUT_LOAD='(1.0,-1.0)';
      PINUSE='BI';
    'F2':
      PIN_NUMBER='(0,F2)';
      BIDIRECTIONAL='TRUE';
      INPUT_LOAD='(-0.01,0.01)';
      OUTPUT_LOAD='(1.0,-1.0)';
      PINUSE='BI';
    'F1':
      PIN_NUMBER='(0,F1)';
      BIDIRECTIONAL='TRUE';
      INPUT_LOAD='(-0.01,0.01)';
      OUTPUT_LOAD='(1.0,-1.0)';
      PINUSE='BI';
    'G4':
      PIN_NUMBER='(0,G4)';
      BIDIRECTIONAL='TRUE';
      INPUT_LOAD='(-0.01,0.01)';
      OUTPUT_LOAD='(1.0,-1.0)';
      PINUSE='BI';
    'G3':
      PIN_NUMBER='(0,G3)';
      BIDIRECTIONAL='TRUE';
      INPUT_LOAD='(-0.01,0.01)';
      OUTPUT_LOAD='(1.0,-1.0)';
      PINUSE='BI';
    'G2':
      PIN_NUMBER='(0,G2)';
      BIDIRECTIONAL='TRUE';
      INPUT_LOAD='(-0.01,0.01)';
      OUTPUT_LOAD='(1.0,-1.0)';
      PINUSE='BI';
    'G1':
      PIN_NUMBER='(0,G1)';
      BIDIRECTIONAL='TRUE';
      INPUT_LOAD='(-0.01,0.01)';
      OUTPUT_LOAD='(1.0,-1.0)';
      PINUSE='BI';
    'H4':
      PIN_NUMBER='(0,H4)';
      BIDIRECTIONAL='TRUE';
      INPUT_LOAD='(-0.01,0.01)';
      OUTPUT_LOAD='(1.0,-1.0)';
      PINUSE='BI';
    'H3':
      PIN_NUMBER='(0,H3)';
      BIDIRECTIONAL='TRUE';
      INPUT_LOAD='(-0.01,0.01)';
      OUTPUT_LOAD='(1.0,-1.0)';
      PINUSE='BI';
    'H2':
      PIN_NUMBER='(0,H2)';
      BIDIRECTIONAL='TRUE';
      INPUT_LOAD='(-0.01,0.01)';
      OUTPUT_LOAD='(1.0,-1.0)';
      PINUSE='BI';
    'H1':
      PIN_NUMBER='(0,H1)';
      BIDIRECTIONAL='TRUE';
      INPUT_LOAD='(-0.01,0.01)';
      OUTPUT_LOAD='(1.0,-1.0)';
      PINUSE='BI';
    'I4':
      PIN_NUMBER='(0,I4)';
      BIDIRECTIONAL='TRUE';
      INPUT_LOAD='(-0.01,0.01)';
      OUTPUT_LOAD='(1.0,-1.0)';
      PINUSE='BI';
    'I3':
      PIN_NUMBER='(0,I3)';
      BIDIRECTIONAL='TRUE';
      INPUT_LOAD='(-0.01,0.01)';
      OUTPUT_LOAD='(1.0,-1.0)';
      PINUSE='BI';
    'I2':
      PIN_NUMBER='(0,I2)';
      BIDIRECTIONAL='TRUE';
      INPUT_LOAD='(-0.01,0.01)';
      OUTPUT_LOAD='(1.0,-1.0)';
      PINUSE='BI';
    'I1':
      PIN_NUMBER='(0,I1)';
      BIDIRECTIONAL='TRUE';
      INPUT_LOAD='(-0.01,0.01)';
      OUTPUT_LOAD='(1.0,-1.0)';
      PINUSE='BI';
    'J4':
      PIN_NUMBER='(0,J4)';
      BIDIRECTIONAL='TRUE';
      INPUT_LOAD='(-0.01,0.01)';
      OUTPUT_LOAD='(1.0,-1.0)';
      PINUSE='BI';
    'J3':
      PIN_NUMBER='(0,J3)';
      BIDIRECTIONAL='TRUE';
      INPUT_LOAD='(-0.01,0.01)';
      OUTPUT_LOAD='(1.0,-1.0)';
      PINUSE='BI';
    'J2':
      PIN_NUMBER='(0,J2)';
      BIDIRECTIONAL='TRUE';
      INPUT_LOAD='(-0.01,0.01)';
      OUTPUT_LOAD='(1.0,-1.0)';
      PINUSE='BI';
    'J1':
      PIN_NUMBER='(0,J1)';
      BIDIRECTIONAL='TRUE';
      INPUT_LOAD='(-0.01,0.01)';
      OUTPUT_LOAD='(1.0,-1.0)';
      PINUSE='BI';
    'K4':
      PIN_NUMBER='(0,K4)';
      BIDIRECTIONAL='TRUE';
      INPUT_LOAD='(-0.01,0.01)';
      OUTPUT_LOAD='(1.0,-1.0)';
      PINUSE='BI';
    'K3':
      PIN_NUMBER='(0,K3)';
      BIDIRECTIONAL='TRUE';
      INPUT_LOAD='(-0.01,0.01)';
      OUTPUT_LOAD='(1.0,-1.0)';
      PINUSE='BI';
    'K2':
      PIN_NUMBER='(0,K2)';
      BIDIRECTIONAL='TRUE';
      INPUT_LOAD='(-0.01,0.01)';
      OUTPUT_LOAD='(1.0,-1.0)';
      PINUSE='BI';
    'K1':
      PIN_NUMBER='(0,K1)';
      BIDIRECTIONAL='TRUE';
      INPUT_LOAD='(-0.01,0.01)';
      OUTPUT_LOAD='(1.0,-1.0)';
      PINUSE='BI';
    'L4':
      PIN_NUMBER='(0,L4)';
      BIDIRECTIONAL='TRUE';
      INPUT_LOAD='(-0.01,0.01)';
      OUTPUT_LOAD='(1.0,-1.0)';
      PINUSE='BI';
    'L3':
      PIN_NUMBER='(0,L3)';
      BIDIRECTIONAL='TRUE';
      INPUT_LOAD='(-0.01,0.01)';
      OUTPUT_LOAD='(1.0,-1.0)';
      PINUSE='BI';
    'L2':
      PIN_NUMBER='(0,L2)';
      BIDIRECTIONAL='TRUE';
      INPUT_LOAD='(-0.01,0.01)';
      OUTPUT_LOAD='(1.0,-1.0)';
      PINUSE='BI';
    'L1':
      PIN_NUMBER='(0,L1)';
      BIDIRECTIONAL='TRUE';
      INPUT_LOAD='(-0.01,0.01)';
      OUTPUT_LOAD='(1.0,-1.0)';
      PINUSE='BI';
    'M1':
      PIN_NUMBER='(0,M1)';
      BIDIRECTIONAL='TRUE';
      INPUT_LOAD='(-0.01,0.01)';
      OUTPUT_LOAD='(1.0,-1.0)';
      PINUSE='BI';
    'N1':
      PIN_NUMBER='(0,N1)';
      BIDIRECTIONAL='TRUE';
      INPUT_LOAD='(-0.01,0.01)';
      OUTPUT_LOAD='(1.0,-1.0)';
      PINUSE='BI';
    'M2':
      PIN_NUMBER='(0,M2)';
      BIDIRECTIONAL='TRUE';
      INPUT_LOAD='(-0.01,0.01)';
      OUTPUT_LOAD='(1.0,-1.0)';
      PINUSE='BI';
    'N2':
      PIN_NUMBER='(0,N2)';
      BIDIRECTIONAL='TRUE';
      INPUT_LOAD='(-0.01,0.01)';
      OUTPUT_LOAD='(1.0,-1.0)';
      PINUSE='BI';
    'M3':
      PIN_NUMBER='(0,M3)';
      BIDIRECTIONAL='TRUE';
      INPUT_LOAD='(-0.01,0.01)';
      OUTPUT_LOAD='(1.0,-1.0)';
      PINUSE='BI';
    'N3':
      PIN_NUMBER='(0,N3)';
      BIDIRECTIONAL='TRUE';
      INPUT_LOAD='(-0.01,0.01)';
      OUTPUT_LOAD='(1.0,-1.0)';
      PINUSE='BI';
    'M4':
      PIN_NUMBER='(0,M4)';
      BIDIRECTIONAL='TRUE';
      INPUT_LOAD='(-0.01,0.01)';
      OUTPUT_LOAD='(1.0,-1.0)';
      PINUSE='BI';
    'N4':
      PIN_NUMBER='(0,N4)';
      BIDIRECTIONAL='TRUE';
      INPUT_LOAD='(-0.01,0.01)';
      OUTPUT_LOAD='(1.0,-1.0)';
      PINUSE='BI';
    'O1':
      PIN_NUMBER='(0,O1)';
      BIDIRECTIONAL='TRUE';
      INPUT_LOAD='(-0.01,0.01)';
      OUTPUT_LOAD='(1.0,-1.0)';
      PINUSE='BI';
    'P1':
      PIN_NUMBER='(0,P1)';
      BIDIRECTIONAL='TRUE';
      INPUT_LOAD='(-0.01,0.01)';
      OUTPUT_LOAD='(1.0,-1.0)';
      PINUSE='BI';
    'Q1':
      PIN_NUMBER='(0,Q1)';
      BIDIRECTIONAL='TRUE';
      INPUT_LOAD='(-0.01,0.01)';
      OUTPUT_LOAD='(1.0,-1.0)';
      PINUSE='BI';
    'R1':
      PIN_NUMBER='(0,R1)';
      BIDIRECTIONAL='TRUE';
      INPUT_LOAD='(-0.01,0.01)';
      OUTPUT_LOAD='(1.0,-1.0)';
      PINUSE='BI';
    'S1':
      PIN_NUMBER='(0,S1)';
      BIDIRECTIONAL='TRUE';
      INPUT_LOAD='(-0.01,0.01)';
      OUTPUT_LOAD='(1.0,-1.0)';
      PINUSE='BI';
    'T1':
      PIN_NUMBER='(0,T1)';
      BIDIRECTIONAL='TRUE';
      INPUT_LOAD='(-0.01,0.01)';
      OUTPUT_LOAD='(1.0,-1.0)';
      PINUSE='BI';
    'O2':
      PIN_NUMBER='(0,O2)';
      BIDIRECTIONAL='TRUE';
      INPUT_LOAD='(-0.01,0.01)';
      OUTPUT_LOAD='(1.0,-1.0)';
      PINUSE='BI';
    'P2':
      PIN_NUMBER='(0,P2)';
      BIDIRECTIONAL='TRUE';
      INPUT_LOAD='(-0.01,0.01)';
      OUTPUT_LOAD='(1.0,-1.0)';
      PINUSE='BI';
    'Q2':
      PIN_NUMBER='(0,Q2)';
      BIDIRECTIONAL='TRUE';
      INPUT_LOAD='(-0.01,0.01)';
      OUTPUT_LOAD='(1.0,-1.0)';
      PINUSE='BI';
    'R2':
      PIN_NUMBER='(0,R2)';
      BIDIRECTIONAL='TRUE';
      INPUT_LOAD='(-0.01,0.01)';
      OUTPUT_LOAD='(1.0,-1.0)';
      PINUSE='BI';
    'S2':
      PIN_NUMBER='(0,S2)';
      BIDIRECTIONAL='TRUE';
      INPUT_LOAD='(-0.01,0.01)';
      OUTPUT_LOAD='(1.0,-1.0)';
      PINUSE='BI';
    'T2':
      PIN_NUMBER='(0,T2)';
      BIDIRECTIONAL='TRUE';
      INPUT_LOAD='(-0.01,0.01)';
      OUTPUT_LOAD='(1.0,-1.0)';
      PINUSE='BI';
    'O3':
      PIN_NUMBER='(0,O3)';
      BIDIRECTIONAL='TRUE';
      INPUT_LOAD='(-0.01,0.01)';
      OUTPUT_LOAD='(1.0,-1.0)';
      PINUSE='BI';
    'P3':
      PIN_NUMBER='(0,P3)';
      BIDIRECTIONAL='TRUE';
      INPUT_LOAD='(-0.01,0.01)';
      OUTPUT_LOAD='(1.0,-1.0)';
      PINUSE='BI';
    'Q3':
      PIN_NUMBER='(0,Q3)';
      BIDIRECTIONAL='TRUE';
      INPUT_LOAD='(-0.01,0.01)';
      OUTPUT_LOAD='(1.0,-1.0)';
      PINUSE='BI';
    'R3':
      PIN_NUMBER='(0,R3)';
      BIDIRECTIONAL='TRUE';
      INPUT_LOAD='(-0.01,0.01)';
      OUTPUT_LOAD='(1.0,-1.0)';
      PINUSE='BI';
    'S3':
      PIN_NUMBER='(0,S3)';
      BIDIRECTIONAL='TRUE';
      INPUT_LOAD='(-0.01,0.01)';
      OUTPUT_LOAD='(1.0,-1.0)';
      PINUSE='BI';
    'T3':
      PIN_NUMBER='(0,T3)';
      BIDIRECTIONAL='TRUE';
      INPUT_LOAD='(-0.01,0.01)';
      OUTPUT_LOAD='(1.0,-1.0)';
      PINUSE='BI';
    'O4':
      PIN_NUMBER='(0,O4)';
      BIDIRECTIONAL='TRUE';
      INPUT_LOAD='(-0.01,0.01)';
      OUTPUT_LOAD='(1.0,-1.0)';
      PINUSE='BI';
    'P4':
      PIN_NUMBER='(0,P4)';
      BIDIRECTIONAL='TRUE';
      INPUT_LOAD='(-0.01,0.01)';
      OUTPUT_LOAD='(1.0,-1.0)';
      PINUSE='BI';
    'Q4':
      PIN_NUMBER='(0,Q4)';
      BIDIRECTIONAL='TRUE';
      INPUT_LOAD='(-0.01,0.01)';
      OUTPUT_LOAD='(1.0,-1.0)';
      PINUSE='BI';
    'R4':
      PIN_NUMBER='(0,R4)';
      BIDIRECTIONAL='TRUE';
      INPUT_LOAD='(-0.01,0.01)';
      OUTPUT_LOAD='(1.0,-1.0)';
      PINUSE='BI';
    'S4':
      PIN_NUMBER='(0,S4)';
      BIDIRECTIONAL='TRUE';
      INPUT_LOAD='(-0.01,0.01)';
      OUTPUT_LOAD='(1.0,-1.0)';
      PINUSE='BI';
    'T4':
      PIN_NUMBER='(0,T4)';
      BIDIRECTIONAL='TRUE';
      INPUT_LOAD='(-0.01,0.01)';
      OUTPUT_LOAD='(1.0,-1.0)';
      PINUSE='BI';
  end_pin;
  body
      PART_NAME='CONN160_10131762101LF';
      BODY_NAME='CONN160_10131762101LF';
      PHYS_DES_PREFIX='J';
      CLASS='IO';
      STANDARD='';
      LIFECYCLE='';
      PART_NUMBER='DFHSG0FR007';
      JEDEC_TYPE='HSD_F160D8_P2W1-2_RDH';
      DESCRIPTION='CONN DIP HOUSING 160P 8R FR(P1.2,H25.1)';
      MANUFTR='BER';
      MANUF_PN='10131762-101LF';
      RD_CMPLS_LVL='EP(V1)';
      CMPLS_LVL='';
      DIP_SMD='DIP';
      FROM_PJ='JG5-ALBERT';
      DATA='BER_10131762-101LF.pdf';
      FP_ECN='';
      EE_CHECK_LIST='';
      CREATOR='';
      CREATEDAY='20180413';
      PSL='';
      STATUS='';
      ESD_CDM='NA';
      ESD_HBM='NA';
      ESD_MM='NA';
      MSD='NA';
      PIN_LENGTH_LONG_PIN='71 MILS';
      PIN_LENGTH_SHORT_PIN='63 MILS';
      PARENT_PART_TYPE='CONN160_10131762101LF';
      PARENT_PPT='CONN160_10131762101LF';
      PARENT_PPT_PART='CONN160_10131762101LF-CONN160_10131762-101LF,THLF,IO,DFHSG0FR007';
  end_body;
end_primitive;
primitive 'CONN1_10165288101LF-CONN1_10165288-101LF,THLF,IO,DA';
  pin
    'NC1':
      PIN_NUMBER='(SCR_H1)';
      BIDIRECTIONAL='TRUE';
      INPUT_LOAD='(-0.01,0.01)';
      OUTPUT_LOAD='(1.0,-1.0)';
      PINUSE='BI';
  end_pin;
  body
      PART_NAME='CONN1_10165288101LF';
      BODY_NAME='CONN1_10165288101LF';
      PHYS_DES_PREFIX='J';
      CLASS='IO';
      NC_PINS='(H1,H2)';
      STANDARD='';
      LIFECYCLE='';
      PART_NUMBER='DFHS03FR030';
      JEDEC_TYPE='CON_GUIDE-F1XG';
      DESCRIPTION='CONN DIP HOUSING 3P 1R FR(H14.7)';
      MANUFTR='APL';
      MANUF_PN='10165288-101LF';
      RD_CMPLS_LVL='EP(V1)';
      CMPLS_LVL='';
      DIP_SMD='DIP';
      FROM_PJ='F0T-BOB-JON';
      DATA='APL_10165288-101LF.pdf';
      FP_ECN='10165288-101LF.msg';
      EE_CHECK_LIST='';
      CREATOR='';
      CREATEDAY='20211213';
      PSL='';
      STATUS='';
      ESD_CDM='';
      ESD_HBM='';
      ESD_MM='';
      MSD='';
      PIN_LENGTH_LONG_PIN='158 MILS';
      PIN_LENGTH_SHORT_PIN='158 MILS';
      PARENT_PART_TYPE='CONN1_10165288101LF';
      PARENT_PPT='CONN1_10165288101LF';
      PARENT_PPT_PART='CONN1_10165288101LF-CONN1_10165288-101LF,THLF,IO,DFHS03FR030';
  end_body;
end_primitive;
primitive 'CONN2_AAABAT029Y19-CONN2_AAA-BAT-029-Y19,THLF,IO,DA';
  pin
    '1':
      PIN_NUMBER='(1)';
      PINUSE='POWER';
      NO_LOAD_CHECK='Both';
      NO_IO_CHECK='Both';
      NO_ASSERT_CHECK='TRUE';
      NO_DIR_CHECK='TRUE';
      ALLOW_CONNECT='TRUE';
    '2':
      PIN_NUMBER='(2)';
      PINUSE='POWER';
      NO_LOAD_CHECK='Both';
      NO_IO_CHECK='Both';
      NO_ASSERT_CHECK='TRUE';
      NO_DIR_CHECK='TRUE';
      ALLOW_CONNECT='TRUE';
  end_pin;
  body
      PART_NAME='CONN2_AAABAT029Y19';
      BODY_NAME='CONN2_AAABAT029Y19';
      PHYS_DES_PREFIX='BT';
      CLASS='IO';
      STANDARD='';
      LIFECYCLE='';
      PART_NUMBER='DFHS02FR062';
      JEDEC_TYPE='BATTERY_AAA-BAT-029-Y19';
      DESCRIPTION='CONN DIP HOUSING 2P 1R FR(P20,H8.80)';
      MANUFTR='LTS';
      MANUF_PN='AAA-BAT-029-Y19';
      RD_CMPLS_LVL='EP(V1)';
      CMPLS_LVL='EP(V1)';
      DIP_SMD='DIP';
      FROM_PJ='S1L-LI-JYUAN';
      DATA='LTS_AAA-BAT-029-Y19.pdf';
      FP_ECN='AAA-BAT-029-Y19.msg';
      EE_CHECK_LIST='';
      CREATOR='';
      CREATEDAY='20200909';
      PSL='';
      STATUS='';
      ESD_CDM='NA';
      ESD_HBM='NA';
      ESD_MM='NA';
      MSD='NA';
      PIN_LENGTH_LONG_PIN='124 MILS';
      PIN_LENGTH_SHORT_PIN='124 MILS';
      PARENT_PART_TYPE='CONN2_AAABAT029Y19';
      PARENT_PPT='CONN2_AAABAT029Y19';
      PARENT_PPT_PART='CONN2_AAABAT029Y19-CONN2_AAA-BAT-029-Y19,THLF,IO,DFHS02FR062';
  end_body;
end_primitive;
primitive 'CONN3_210HP1030BR1-CONN3_210-HP1-030BR1,THLF,IO,DFA';
  pin
    '3':
      PIN_NUMBER='(3)';
      BIDIRECTIONAL='TRUE';
      INPUT_LOAD='(-0.01,0.01)';
      OUTPUT_LOAD='(1.0,-1.0)';
      PINUSE='BI';
    '2':
      PIN_NUMBER='(2)';
      BIDIRECTIONAL='TRUE';
      INPUT_LOAD='(-0.01,0.01)';
      OUTPUT_LOAD='(1.0,-1.0)';
      PINUSE='BI';
    '1':
      PIN_NUMBER='(1)';
      BIDIRECTIONAL='TRUE';
      INPUT_LOAD='(-0.01,0.01)';
      OUTPUT_LOAD='(1.0,-1.0)';
      PINUSE='BI';
  end_pin;
  body
      PART_NAME='CONN3_210HP1030BR1';
      BODY_NAME='CONN3_210HP1030BR1';
      PHYS_DES_PREFIX='JP';
      CLASS='IO';
      STANDARD='';
      LIFECYCLE='';
      PART_NUMBER='DFHD03MS213';
      JEDEC_TYPE='HEADER1X3XG';
      DESCRIPTION='CONN DIP HEADER 3P 1R MS(P2.54,H8.6)';
      MANUFTR='PRX';
      MANUF_PN='210-HP1-030BR1';
      RD_CMPLS_LVL='EP(V1)';
      CMPLS_LVL='EP(V1)';
      DIP_SMD='DIP';
      FROM_PJ='F08-OWEN';
      DATA='PRX_210-HP1-030BR1.pdf';
      FP_ECN='';
      EE_CHECK_LIST='';
      CREATOR='';
      CREATEDAY='20160621';
      PSL='';
      STATUS='';
      ESD_CDM='NA';
      ESD_HBM='NA';
      ESD_MM='NA';
      MSD='NA';
      PIN_LENGTH_LONG_PIN='119 MILS';
      PIN_LENGTH_SHORT_PIN='119 MILS';
      PARENT_PART_TYPE='CONN3_210HP1030BR1';
      PARENT_PPT='CONN3_210HP1030BR1';
      PARENT_PPT_PART='CONN3_210HP1030BR1-CONN3_210-HP1-030BR1,THLF,IO,DFHD03MS213';
  end_body;
end_primitive;
primitive 'CONN4_HFK1040L0P1L7H-CONN4_HFK1040-L0P1L-7H,THLF,IA';
  pin
    '4':
      PIN_NUMBER='(4)';
      BIDIRECTIONAL='TRUE';
      INPUT_LOAD='(-0.01,0.01)';
      OUTPUT_LOAD='(1.0,-1.0)';
      PINUSE='BI';
    '3':
      PIN_NUMBER='(3)';
      BIDIRECTIONAL='TRUE';
      INPUT_LOAD='(-0.01,0.01)';
      OUTPUT_LOAD='(1.0,-1.0)';
      PINUSE='BI';
    '2':
      PIN_NUMBER='(2)';
      BIDIRECTIONAL='TRUE';
      INPUT_LOAD='(-0.01,0.01)';
      OUTPUT_LOAD='(1.0,-1.0)';
      PINUSE='BI';
    '1':
      PIN_NUMBER='(1)';
      BIDIRECTIONAL='TRUE';
      INPUT_LOAD='(-0.01,0.01)';
      OUTPUT_LOAD='(1.0,-1.0)';
      PINUSE='BI';
  end_pin;
  body
      PART_NAME='CONN4_HFK1040L0P1L7H';
      BODY_NAME='CONN4_HFK1040L0P1L7H';
      PHYS_DES_PREFIX='J';
      CLASS='IO';
      NC_PINS='(H1)';
      STANDARD='';
      LIFECYCLE='';
      PART_NUMBER='DFHD04MS460';
      JEDEC_TYPE='HEADER1X4BHXA';
      DESCRIPTION='CONN DIP HEADER 4P 1R MS(P2,H6)';
      MANUFTR='FOX';
      MANUF_PN='HFK1040-L0P1L-7H';
      RD_CMPLS_LVL='EP(V1)';
      CMPLS_LVL='EP(V1)';
      DIP_SMD='DIP';
      FROM_PJ='A5R-BINGLIN';
      DATA='FOX_HFK1040-L0P1L-7H.pdf';
      FP_ECN='';
      EE_CHECK_LIST='';
      CREATOR='';
      CREATEDAY='20190308';
      PSL='';
      STATUS='';
      ESD_CDM='NA';
      ESD_HBM='NA';
      ESD_MM='NA';
      MSD='NA';
      PIN_LENGTH_LONG_PIN='65 MILS';
      PIN_LENGTH_SHORT_PIN='134 MILS';
      PARENT_PART_TYPE='CONN4_HFK1040L0P1L7H';
      PARENT_PPT='CONN4_HFK1040L0P1L7H';
      PARENT_PPT_PART='CONN4_HFK1040L0P1L7H-CONN4_HFK1040-L0P1L-7H,THLF,IO,DFHD04MS460';
  end_body;
end_primitive;
primitive 'CONN60_101062636003K02LF-CONN60_10106263-6003K02LFA';
  pin
    'A2':
      PIN_NUMBER='(A2)';
      BIDIRECTIONAL='TRUE';
      INPUT_LOAD='(-0.01,0.01)';
      OUTPUT_LOAD='(1.0,-1.0)';
      PINUSE='BI';
    'B2':
      PIN_NUMBER='(B2)';
      BIDIRECTIONAL='TRUE';
      INPUT_LOAD='(-0.01,0.01)';
      OUTPUT_LOAD='(1.0,-1.0)';
      PINUSE='BI';
    'C2':
      PIN_NUMBER='(C2)';
      BIDIRECTIONAL='TRUE';
      INPUT_LOAD='(-0.01,0.01)';
      OUTPUT_LOAD='(1.0,-1.0)';
      PINUSE='BI';
    'D2':
      PIN_NUMBER='(D2)';
      BIDIRECTIONAL='TRUE';
      INPUT_LOAD='(-0.01,0.01)';
      OUTPUT_LOAD='(1.0,-1.0)';
      PINUSE='BI';
    'P1_1':
      PIN_NUMBER='(P1_1)';
      PINUSE='POWER';
      NO_LOAD_CHECK='Both';
      NO_IO_CHECK='Both';
      NO_ASSERT_CHECK='TRUE';
      NO_DIR_CHECK='TRUE';
      ALLOW_CONNECT='TRUE';
    'P1_2':
      PIN_NUMBER='(P1_2)';
      PINUSE='POWER';
      NO_LOAD_CHECK='Both';
      NO_IO_CHECK='Both';
      NO_ASSERT_CHECK='TRUE';
      NO_DIR_CHECK='TRUE';
      ALLOW_CONNECT='TRUE';
    'P1_3':
      PIN_NUMBER='(P1_3)';
      PINUSE='POWER';
      NO_LOAD_CHECK='Both';
      NO_IO_CHECK='Both';
      NO_ASSERT_CHECK='TRUE';
      NO_DIR_CHECK='TRUE';
      ALLOW_CONNECT='TRUE';
    'P1_4':
      PIN_NUMBER='(P1_4)';
      PINUSE='POWER';
      NO_LOAD_CHECK='Both';
      NO_IO_CHECK='Both';
      NO_ASSERT_CHECK='TRUE';
      NO_DIR_CHECK='TRUE';
      ALLOW_CONNECT='TRUE';
    'P1_5':
      PIN_NUMBER='(P1_5)';
      PINUSE='POWER';
      NO_LOAD_CHECK='Both';
      NO_IO_CHECK='Both';
      NO_ASSERT_CHECK='TRUE';
      NO_DIR_CHECK='TRUE';
      ALLOW_CONNECT='TRUE';
    'P1_6':
      PIN_NUMBER='(P1_6)';
      PINUSE='POWER';
      NO_LOAD_CHECK='Both';
      NO_IO_CHECK='Both';
      NO_ASSERT_CHECK='TRUE';
      NO_DIR_CHECK='TRUE';
      ALLOW_CONNECT='TRUE';
    'P1_7':
      PIN_NUMBER='(P1_7)';
      PINUSE='POWER';
      NO_LOAD_CHECK='Both';
      NO_IO_CHECK='Both';
      NO_ASSERT_CHECK='TRUE';
      NO_DIR_CHECK='TRUE';
      ALLOW_CONNECT='TRUE';
    'P1_8':
      PIN_NUMBER='(P1_8)';
      PINUSE='POWER';
      NO_LOAD_CHECK='Both';
      NO_IO_CHECK='Both';
      NO_ASSERT_CHECK='TRUE';
      NO_DIR_CHECK='TRUE';
      ALLOW_CONNECT='TRUE';
    'P2_1':
      PIN_NUMBER='(P2_1)';
      PINUSE='POWER';
      NO_LOAD_CHECK='Both';
      NO_IO_CHECK='Both';
      NO_ASSERT_CHECK='TRUE';
      NO_DIR_CHECK='TRUE';
      ALLOW_CONNECT='TRUE';
    'P2_2':
      PIN_NUMBER='(P2_2)';
      PINUSE='POWER';
      NO_LOAD_CHECK='Both';
      NO_IO_CHECK='Both';
      NO_ASSERT_CHECK='TRUE';
      NO_DIR_CHECK='TRUE';
      ALLOW_CONNECT='TRUE';
    'P2_3':
      PIN_NUMBER='(P2_3)';
      PINUSE='POWER';
      NO_LOAD_CHECK='Both';
      NO_IO_CHECK='Both';
      NO_ASSERT_CHECK='TRUE';
      NO_DIR_CHECK='TRUE';
      ALLOW_CONNECT='TRUE';
    'P2_4':
      PIN_NUMBER='(P2_4)';
      PINUSE='POWER';
      NO_LOAD_CHECK='Both';
      NO_IO_CHECK='Both';
      NO_ASSERT_CHECK='TRUE';
      NO_DIR_CHECK='TRUE';
      ALLOW_CONNECT='TRUE';
    'P2_5':
      PIN_NUMBER='(P2_5)';
      PINUSE='POWER';
      NO_LOAD_CHECK='Both';
      NO_IO_CHECK='Both';
      NO_ASSERT_CHECK='TRUE';
      NO_DIR_CHECK='TRUE';
      ALLOW_CONNECT='TRUE';
    'P2_6':
      PIN_NUMBER='(P2_6)';
      PINUSE='POWER';
      NO_LOAD_CHECK='Both';
      NO_IO_CHECK='Both';
      NO_ASSERT_CHECK='TRUE';
      NO_DIR_CHECK='TRUE';
      ALLOW_CONNECT='TRUE';
    'P2_7':
      PIN_NUMBER='(P2_7)';
      PINUSE='POWER';
      NO_LOAD_CHECK='Both';
      NO_IO_CHECK='Both';
      NO_ASSERT_CHECK='TRUE';
      NO_DIR_CHECK='TRUE';
      ALLOW_CONNECT='TRUE';
    'P2_8':
      PIN_NUMBER='(P2_8)';
      PINUSE='POWER';
      NO_LOAD_CHECK='Both';
      NO_IO_CHECK='Both';
      NO_ASSERT_CHECK='TRUE';
      NO_DIR_CHECK='TRUE';
      ALLOW_CONNECT='TRUE';
    'P4_1':
      PIN_NUMBER='(P4_1)';
      PINUSE='POWER';
      NO_LOAD_CHECK='Both';
      NO_IO_CHECK='Both';
      NO_ASSERT_CHECK='TRUE';
      NO_DIR_CHECK='TRUE';
      ALLOW_CONNECT='TRUE';
    'P4_2':
      PIN_NUMBER='(P4_2)';
      PINUSE='POWER';
      NO_LOAD_CHECK='Both';
      NO_IO_CHECK='Both';
      NO_ASSERT_CHECK='TRUE';
      NO_DIR_CHECK='TRUE';
      ALLOW_CONNECT='TRUE';
    'P4_3':
      PIN_NUMBER='(P4_3)';
      PINUSE='POWER';
      NO_LOAD_CHECK='Both';
      NO_IO_CHECK='Both';
      NO_ASSERT_CHECK='TRUE';
      NO_DIR_CHECK='TRUE';
      ALLOW_CONNECT='TRUE';
    'P4_4':
      PIN_NUMBER='(P4_4)';
      PINUSE='POWER';
      NO_LOAD_CHECK='Both';
      NO_IO_CHECK='Both';
      NO_ASSERT_CHECK='TRUE';
      NO_DIR_CHECK='TRUE';
      ALLOW_CONNECT='TRUE';
    'P4_5':
      PIN_NUMBER='(P4_5)';
      PINUSE='POWER';
      NO_LOAD_CHECK='Both';
      NO_IO_CHECK='Both';
      NO_ASSERT_CHECK='TRUE';
      NO_DIR_CHECK='TRUE';
      ALLOW_CONNECT='TRUE';
    'P4_6':
      PIN_NUMBER='(P4_6)';
      PINUSE='POWER';
      NO_LOAD_CHECK='Both';
      NO_IO_CHECK='Both';
      NO_ASSERT_CHECK='TRUE';
      NO_DIR_CHECK='TRUE';
      ALLOW_CONNECT='TRUE';
    'P4_7':
      PIN_NUMBER='(P4_7)';
      PINUSE='POWER';
      NO_LOAD_CHECK='Both';
      NO_IO_CHECK='Both';
      NO_ASSERT_CHECK='TRUE';
      NO_DIR_CHECK='TRUE';
      ALLOW_CONNECT='TRUE';
    'P4_8':
      PIN_NUMBER='(P4_8)';
      PINUSE='POWER';
      NO_LOAD_CHECK='Both';
      NO_IO_CHECK='Both';
      NO_ASSERT_CHECK='TRUE';
      NO_DIR_CHECK='TRUE';
      ALLOW_CONNECT='TRUE';
    'A1':
      PIN_NUMBER='(A1)';
      BIDIRECTIONAL='TRUE';
      INPUT_LOAD='(-0.01,0.01)';
      OUTPUT_LOAD='(1.0,-1.0)';
      PINUSE='BI';
    'B1':
      PIN_NUMBER='(B1)';
      BIDIRECTIONAL='TRUE';
      INPUT_LOAD='(-0.01,0.01)';
      OUTPUT_LOAD='(1.0,-1.0)';
      PINUSE='BI';
    'C1':
      PIN_NUMBER='(C1)';
      BIDIRECTIONAL='TRUE';
      INPUT_LOAD='(-0.01,0.01)';
      OUTPUT_LOAD='(1.0,-1.0)';
      PINUSE='BI';
    'D1':
      PIN_NUMBER='(D1)';
      BIDIRECTIONAL='TRUE';
      INPUT_LOAD='(-0.01,0.01)';
      OUTPUT_LOAD='(1.0,-1.0)';
      PINUSE='BI';
    'P5_1':
      PIN_NUMBER='(P5_1)';
      PINUSE='POWER';
      NO_LOAD_CHECK='Both';
      NO_IO_CHECK='Both';
      NO_ASSERT_CHECK='TRUE';
      NO_DIR_CHECK='TRUE';
      ALLOW_CONNECT='TRUE';
    'P5_2':
      PIN_NUMBER='(P5_2)';
      PINUSE='POWER';
      NO_LOAD_CHECK='Both';
      NO_IO_CHECK='Both';
      NO_ASSERT_CHECK='TRUE';
      NO_DIR_CHECK='TRUE';
      ALLOW_CONNECT='TRUE';
    'P5_3':
      PIN_NUMBER='(P5_3)';
      PINUSE='POWER';
      NO_LOAD_CHECK='Both';
      NO_IO_CHECK='Both';
      NO_ASSERT_CHECK='TRUE';
      NO_DIR_CHECK='TRUE';
      ALLOW_CONNECT='TRUE';
    'P5_4':
      PIN_NUMBER='(P5_4)';
      PINUSE='POWER';
      NO_LOAD_CHECK='Both';
      NO_IO_CHECK='Both';
      NO_ASSERT_CHECK='TRUE';
      NO_DIR_CHECK='TRUE';
      ALLOW_CONNECT='TRUE';
    'P5_5':
      PIN_NUMBER='(P5_5)';
      PINUSE='POWER';
      NO_LOAD_CHECK='Both';
      NO_IO_CHECK='Both';
      NO_ASSERT_CHECK='TRUE';
      NO_DIR_CHECK='TRUE';
      ALLOW_CONNECT='TRUE';
    'P5_6':
      PIN_NUMBER='(P5_6)';
      PINUSE='POWER';
      NO_LOAD_CHECK='Both';
      NO_IO_CHECK='Both';
      NO_ASSERT_CHECK='TRUE';
      NO_DIR_CHECK='TRUE';
      ALLOW_CONNECT='TRUE';
    'P5_7':
      PIN_NUMBER='(P5_7)';
      PINUSE='POWER';
      NO_LOAD_CHECK='Both';
      NO_IO_CHECK='Both';
      NO_ASSERT_CHECK='TRUE';
      NO_DIR_CHECK='TRUE';
      ALLOW_CONNECT='TRUE';
    'P5_8':
      PIN_NUMBER='(P5_8)';
      PINUSE='POWER';
      NO_LOAD_CHECK='Both';
      NO_IO_CHECK='Both';
      NO_ASSERT_CHECK='TRUE';
      NO_DIR_CHECK='TRUE';
      ALLOW_CONNECT='TRUE';
    'P3_1':
      PIN_NUMBER='(P3_1)';
      PINUSE='POWER';
      NO_LOAD_CHECK='Both';
      NO_IO_CHECK='Both';
      NO_ASSERT_CHECK='TRUE';
      NO_DIR_CHECK='TRUE';
      ALLOW_CONNECT='TRUE';
    'P3_2':
      PIN_NUMBER='(P3_2)';
      PINUSE='POWER';
      NO_LOAD_CHECK='Both';
      NO_IO_CHECK='Both';
      NO_ASSERT_CHECK='TRUE';
      NO_DIR_CHECK='TRUE';
      ALLOW_CONNECT='TRUE';
    'P3_3':
      PIN_NUMBER='(P3_3)';
      PINUSE='POWER';
      NO_LOAD_CHECK='Both';
      NO_IO_CHECK='Both';
      NO_ASSERT_CHECK='TRUE';
      NO_DIR_CHECK='TRUE';
      ALLOW_CONNECT='TRUE';
    'P3_4':
      PIN_NUMBER='(P3_4)';
      PINUSE='POWER';
      NO_LOAD_CHECK='Both';
      NO_IO_CHECK='Both';
      NO_ASSERT_CHECK='TRUE';
      NO_DIR_CHECK='TRUE';
      ALLOW_CONNECT='TRUE';
    'P3_5':
      PIN_NUMBER='(P3_5)';
      PINUSE='POWER';
      NO_LOAD_CHECK='Both';
      NO_IO_CHECK='Both';
      NO_ASSERT_CHECK='TRUE';
      NO_DIR_CHECK='TRUE';
      ALLOW_CONNECT='TRUE';
    'P3_6':
      PIN_NUMBER='(P3_6)';
      PINUSE='POWER';
      NO_LOAD_CHECK='Both';
      NO_IO_CHECK='Both';
      NO_ASSERT_CHECK='TRUE';
      NO_DIR_CHECK='TRUE';
      ALLOW_CONNECT='TRUE';
    'P3_7':
      PIN_NUMBER='(P3_7)';
      PINUSE='POWER';
      NO_LOAD_CHECK='Both';
      NO_IO_CHECK='Both';
      NO_ASSERT_CHECK='TRUE';
      NO_DIR_CHECK='TRUE';
      ALLOW_CONNECT='TRUE';
    'P3_8':
      PIN_NUMBER='(P3_8)';
      PINUSE='POWER';
      NO_LOAD_CHECK='Both';
      NO_IO_CHECK='Both';
      NO_ASSERT_CHECK='TRUE';
      NO_DIR_CHECK='TRUE';
      ALLOW_CONNECT='TRUE';
    'P6_1':
      PIN_NUMBER='(P6_1)';
      PINUSE='POWER';
      NO_LOAD_CHECK='Both';
      NO_IO_CHECK='Both';
      NO_ASSERT_CHECK='TRUE';
      NO_DIR_CHECK='TRUE';
      ALLOW_CONNECT='TRUE';
    'P6_2':
      PIN_NUMBER='(P6_2)';
      PINUSE='POWER';
      NO_LOAD_CHECK='Both';
      NO_IO_CHECK='Both';
      NO_ASSERT_CHECK='TRUE';
      NO_DIR_CHECK='TRUE';
      ALLOW_CONNECT='TRUE';
    'P6_3':
      PIN_NUMBER='(P6_3)';
      PINUSE='POWER';
      NO_LOAD_CHECK='Both';
      NO_IO_CHECK='Both';
      NO_ASSERT_CHECK='TRUE';
      NO_DIR_CHECK='TRUE';
      ALLOW_CONNECT='TRUE';
    'P6_4':
      PIN_NUMBER='(P6_4)';
      PINUSE='POWER';
      NO_LOAD_CHECK='Both';
      NO_IO_CHECK='Both';
      NO_ASSERT_CHECK='TRUE';
      NO_DIR_CHECK='TRUE';
      ALLOW_CONNECT='TRUE';
    'P6_5':
      PIN_NUMBER='(P6_5)';
      PINUSE='POWER';
      NO_LOAD_CHECK='Both';
      NO_IO_CHECK='Both';
      NO_ASSERT_CHECK='TRUE';
      NO_DIR_CHECK='TRUE';
      ALLOW_CONNECT='TRUE';
    'P6_6':
      PIN_NUMBER='(P6_6)';
      PINUSE='POWER';
      NO_LOAD_CHECK='Both';
      NO_IO_CHECK='Both';
      NO_ASSERT_CHECK='TRUE';
      NO_DIR_CHECK='TRUE';
      ALLOW_CONNECT='TRUE';
    'P6_7':
      PIN_NUMBER='(P6_7)';
      PINUSE='POWER';
      NO_LOAD_CHECK='Both';
      NO_IO_CHECK='Both';
      NO_ASSERT_CHECK='TRUE';
      NO_DIR_CHECK='TRUE';
      ALLOW_CONNECT='TRUE';
    'P6_8':
      PIN_NUMBER='(P6_8)';
      PINUSE='POWER';
      NO_LOAD_CHECK='Both';
      NO_IO_CHECK='Both';
      NO_ASSERT_CHECK='TRUE';
      NO_DIR_CHECK='TRUE';
      ALLOW_CONNECT='TRUE';
    'A3':
      PIN_NUMBER='(A3)';
      BIDIRECTIONAL='TRUE';
      INPUT_LOAD='(-0.01,0.01)';
      OUTPUT_LOAD='(1.0,-1.0)';
      PINUSE='BI';
    'B3':
      PIN_NUMBER='(B3)';
      BIDIRECTIONAL='TRUE';
      INPUT_LOAD='(-0.01,0.01)';
      OUTPUT_LOAD='(1.0,-1.0)';
      PINUSE='BI';
    'C3':
      PIN_NUMBER='(C3)';
      BIDIRECTIONAL='TRUE';
      INPUT_LOAD='(-0.01,0.01)';
      OUTPUT_LOAD='(1.0,-1.0)';
      PINUSE='BI';
    'D3':
      PIN_NUMBER='(D3)';
      BIDIRECTIONAL='TRUE';
      INPUT_LOAD='(-0.01,0.01)';
      OUTPUT_LOAD='(1.0,-1.0)';
      PINUSE='BI';
  end_pin;
  body
      PART_NAME='CONN60_101062636003K02LF';
      BODY_NAME='CONN60_101062636003K02LF';
      PHYS_DES_PREFIX='J';
      CLASS='IO';
      NC_PINS='(SCR_H1,SCR_H2)';
      STANDARD='';
      LIFECYCLE='';
      PART_NUMBER='DFHD60MR024';
      JEDEC_TYPE='HSD_M60D4H2D_P2-54W2-54_LDHXB';
      DESCRIPTION='CONN DIP HEADER 60P 4R MR(P2.54,H12.57)';
      MANUFTR='APL';
      MANUF_PN='10106263-6003K02LF';
      RD_CMPLS_LVL='EP(V1)';
      CMPLS_LVL='';
      DIP_SMD='DIP';
      FROM_PJ='F0T-IVES';
      DATA='APL_10106263-6003K02LF.pdf';
      FP_ECN='10106263-6003K02LF.msg';
      EE_CHECK_LIST='';
      CREATOR='';
      CREATEDAY='20220513';
      PSL='';
      STATUS='';
      ESD_CDM='';
      ESD_HBM='';
      ESD_MM='';
      MSD='';
      PIN_LENGTH_LONG_PIN='136 MILS';
      PIN_LENGTH_SHORT_PIN='136 MILS';
      PARENT_PART_TYPE='CONN60_101062636003K02LF';
      PARENT_PPT='CONN60_101062636003K02LF';
      PARENT_PPT_PART='CONN60_101062636003K02LF-CONN60_10106263-6003K02LF,THLF,IO,DFHD60MR024';
  end_body;
end_primitive;
primitive 'CONN6_HBC1031L200D8H-CONN6_HBC1031-L200D-8H,THLF,IA';
  pin
    '1':
      PIN_NUMBER='(1)';
      BIDIRECTIONAL='TRUE';
      INPUT_LOAD='(-0.01,0.01)';
      OUTPUT_LOAD='(1.0,-1.0)';
      PINUSE='BI';
    '2':
      PIN_NUMBER='(2)';
      BIDIRECTIONAL='TRUE';
      INPUT_LOAD='(-0.01,0.01)';
      OUTPUT_LOAD='(1.0,-1.0)';
      PINUSE='BI';
    '3':
      PIN_NUMBER='(3)';
      BIDIRECTIONAL='TRUE';
      INPUT_LOAD='(-0.01,0.01)';
      OUTPUT_LOAD='(1.0,-1.0)';
      PINUSE='BI';
    '4':
      PIN_NUMBER='(4)';
      BIDIRECTIONAL='TRUE';
      INPUT_LOAD='(-0.01,0.01)';
      OUTPUT_LOAD='(1.0,-1.0)';
      PINUSE='BI';
    '5':
      PIN_NUMBER='(5)';
      BIDIRECTIONAL='TRUE';
      INPUT_LOAD='(-0.01,0.01)';
      OUTPUT_LOAD='(1.0,-1.0)';
      PINUSE='BI';
    '6':
      PIN_NUMBER='(6)';
      BIDIRECTIONAL='TRUE';
      INPUT_LOAD='(-0.01,0.01)';
      OUTPUT_LOAD='(1.0,-1.0)';
      PINUSE='BI';
  end_pin;
  body
      PART_NAME='CONN6_HBC1031L200D8H';
      BODY_NAME='CONN6_HBC1031L200D8H';
      PHYS_DES_PREFIX='J';
      CLASS='IO';
      STANDARD='';
      LIFECYCLE='';
      PART_NUMBER='DFHD06MS263';
      JEDEC_TYPE='HEADER2X3XE';
      DESCRIPTION='CONN DIP HEADER 6P 2R MS(P2.54,H8.38)';
      MANUFTR='FOX';
      MANUF_PN='HBC1031-L200D-8H';
      RD_CMPLS_LVL='EP(V1)';
      CMPLS_LVL='EP(V1)';
      DIP_SMD='DIP';
      FROM_PJ='S9T-DAVID';
      DATA='FOX_HBC1031-L200D-8H.pdf';
      FP_ECN='';
      EE_CHECK_LIST='';
      CREATOR='';
      CREATEDAY='20210512';
      PSL='';
      STATUS='';
      ESD_CDM='';
      ESD_HBM='';
      ESD_MM='';
      MSD='';
      PIN_LENGTH_LONG_PIN='110 MILS';
      PIN_LENGTH_SHORT_PIN='110 MILS';
      PARENT_PART_TYPE='CONN6_HBC1031L200D8H';
      PARENT_PPT='CONN6_HBC1031L200D8H';
      PARENT_PPT_PART='CONN6_HBC1031L200D8H-CONN6_HBC1031-L200D-8H,THLF,IO,DFHD06MS263';
  end_body;
end_primitive;
primitive 'CONN8_HBB1081L200D8H-CONN8_HBB1081-L200D-8H,THLF,IA';
  pin
    '1':
      PIN_NUMBER='(1)';
      BIDIRECTIONAL='TRUE';
      INPUT_LOAD='(-0.01,0.01)';
      OUTPUT_LOAD='(1.0,-1.0)';
      PINUSE='BI';
    '2':
      PIN_NUMBER='(2)';
      BIDIRECTIONAL='TRUE';
      INPUT_LOAD='(-0.01,0.01)';
      OUTPUT_LOAD='(1.0,-1.0)';
      PINUSE='BI';
    '3':
      PIN_NUMBER='(3)';
      BIDIRECTIONAL='TRUE';
      INPUT_LOAD='(-0.01,0.01)';
      OUTPUT_LOAD='(1.0,-1.0)';
      PINUSE='BI';
    '4':
      PIN_NUMBER='(4)';
      BIDIRECTIONAL='TRUE';
      INPUT_LOAD='(-0.01,0.01)';
      OUTPUT_LOAD='(1.0,-1.0)';
      PINUSE='BI';
    '5':
      PIN_NUMBER='(5)';
      BIDIRECTIONAL='TRUE';
      INPUT_LOAD='(-0.01,0.01)';
      OUTPUT_LOAD='(1.0,-1.0)';
      PINUSE='BI';
    '6':
      PIN_NUMBER='(6)';
      BIDIRECTIONAL='TRUE';
      INPUT_LOAD='(-0.01,0.01)';
      OUTPUT_LOAD='(1.0,-1.0)';
      PINUSE='BI';
    '7':
      PIN_NUMBER='(7)';
      BIDIRECTIONAL='TRUE';
      INPUT_LOAD='(-0.01,0.01)';
      OUTPUT_LOAD='(1.0,-1.0)';
      PINUSE='BI';
    '8':
      PIN_NUMBER='(8)';
      BIDIRECTIONAL='TRUE';
      INPUT_LOAD='(-0.01,0.01)';
      OUTPUT_LOAD='(1.0,-1.0)';
      PINUSE='BI';
  end_pin;
  body
      PART_NAME='CONN8_HBB1081L200D8H';
      BODY_NAME='CONN8_HBB1081L200D8H';
      PHYS_DES_PREFIX='J';
      CLASS='IO';
      STANDARD='';
      LIFECYCLE='';
      PART_NUMBER='DFHD08MS197';
      JEDEC_TYPE='HEADER1X8XA_H340';
      DESCRIPTION='CONN DIP HEADER 8P 1R MS(P2.54,H8.38)';
      MANUFTR='FOX';
      MANUF_PN='HBB1081-L200D-8H';
      RD_CMPLS_LVL='EP(V1)';
      CMPLS_LVL='EP(V1)';
      DIP_SMD='DIP';
      FROM_PJ='S3S-IAN';
      DATA='FOX_HBB1081-L200D-8H.pdf';
      FP_ECN='';
      EE_CHECK_LIST='';
      CREATOR='';
      CREATEDAY='20190819';
      PSL='';
      STATUS='';
      ESD_CDM='NA';
      ESD_HBM='NA';
      ESD_MM='NA';
      MSD='NA';
      PIN_LENGTH_LONG_PIN='120 MILS';
      PIN_LENGTH_SHORT_PIN='120 MILS';
      PARENT_PART_TYPE='CONN8_HBB1081L200D8H';
      PARENT_PPT='CONN8_HBB1081L200D8H';
      PARENT_PPT_PART='CONN8_HBB1081L200D8H-CONN8_HBB1081-L200D-8H,THLF,IO,DFHD08MS197';
  end_body;
end_primitive;
primitive 'CYUSB330468LTXI-CYUSB3304-68LTXI,SMLF,IC,AJ0330400A';
  pin
    'DS1_DP':
      PIN_NUMBER='(60,0)';
      BIDIRECTIONAL='TRUE';
      INPUT_LOAD='(-0.01,0.01)';
      OUTPUT_LOAD='(1.0,-1.0)';
      PINUSE='BI';
    'DS1_DM':
      PIN_NUMBER='(59,0)';
      BIDIRECTIONAL='TRUE';
      INPUT_LOAD='(-0.01,0.01)';
      OUTPUT_LOAD='(1.0,-1.0)';
      PINUSE='BI';
    'DS1_RXP':
      PIN_NUMBER='(51,0)';
      INPUT_LOAD='(-0.01,0.01)';
      PINUSE='IN';
    'DS1_RXM':
      PIN_NUMBER='(50,0)';
      INPUT_LOAD='(-0.01,0.01)';
      PINUSE='IN';
    'DS1_TXP':
      PIN_NUMBER='(47,0)';
      OUTPUT_LOAD='(1.0,-1.0)';
      PINUSE='OUT';
    'DS1_TXM':
      PIN_NUMBER='(48,0)';
      OUTPUT_LOAD='(1.0,-1.0)';
      PINUSE='OUT';
    'DS2_DP':
      PIN_NUMBER='(62,0)';
      BIDIRECTIONAL='TRUE';
      INPUT_LOAD='(-0.01,0.01)';
      OUTPUT_LOAD='(1.0,-1.0)';
      PINUSE='BI';
    'DS2_DM':
      PIN_NUMBER='(63,0)';
      BIDIRECTIONAL='TRUE';
      INPUT_LOAD='(-0.01,0.01)';
      OUTPUT_LOAD='(1.0,-1.0)';
      PINUSE='BI';
    'DS2_RXP':
      PIN_NUMBER='(45,0)';
      INPUT_LOAD='(-0.01,0.01)';
      PINUSE='IN';
    'DS2_RXM':
      PIN_NUMBER='(44,0)';
      INPUT_LOAD='(-0.01,0.01)';
      PINUSE='IN';
    'DS2_TXP':
      PIN_NUMBER='(41,0)';
      OUTPUT_LOAD='(1.0,-1.0)';
      PINUSE='OUT';
    'DS2_TXM':
      PIN_NUMBER='(42,0)';
      OUTPUT_LOAD='(1.0,-1.0)';
      PINUSE='OUT';
    'DS3_DP':
      PIN_NUMBER='(65,0)';
      BIDIRECTIONAL='TRUE';
      INPUT_LOAD='(-0.01,0.01)';
      OUTPUT_LOAD='(1.0,-1.0)';
      PINUSE='BI';
    'DS3_DM':
      PIN_NUMBER='(64,0)';
      BIDIRECTIONAL='TRUE';
      INPUT_LOAD='(-0.01,0.01)';
      OUTPUT_LOAD='(1.0,-1.0)';
      PINUSE='BI';
    'DS3_RXP':
      PIN_NUMBER='(35,0)';
      INPUT_LOAD='(-0.01,0.01)';
      PINUSE='IN';
    'DS3_RXM':
      PIN_NUMBER='(36,0)';
      INPUT_LOAD='(-0.01,0.01)';
      PINUSE='IN';
    'DS3_TXP':
      PIN_NUMBER='(38,0)';
      OUTPUT_LOAD='(1.0,-1.0)';
      PINUSE='OUT';
    'DS3_TXM':
      PIN_NUMBER='(39,0)';
      OUTPUT_LOAD='(1.0,-1.0)';
      PINUSE='OUT';
    'DS4_DP':
      PIN_NUMBER='(67,0)';
      BIDIRECTIONAL='TRUE';
      INPUT_LOAD='(-0.01,0.01)';
      OUTPUT_LOAD='(1.0,-1.0)';
      PINUSE='BI';
    'DS4_DM':
      PIN_NUMBER='(68,0)';
      BIDIRECTIONAL='TRUE';
      INPUT_LOAD='(-0.01,0.01)';
      OUTPUT_LOAD='(1.0,-1.0)';
      PINUSE='BI';
    'DS4_RXP':
      PIN_NUMBER='(15,0)';
      INPUT_LOAD='(-0.01,0.01)';
      PINUSE='IN';
    'DS4_RXM':
      PIN_NUMBER='(14,0)';
      INPUT_LOAD='(-0.01,0.01)';
      PINUSE='IN';
    'DS4_TXP':
      PIN_NUMBER='(11,0)';
      OUTPUT_LOAD='(1.0,-1.0)';
      PINUSE='OUT';
    'DS4_TXM':
      PIN_NUMBER='(12,0)';
      OUTPUT_LOAD='(1.0,-1.0)';
      PINUSE='OUT';
    'VBUS_DS':
      PIN_NUMBER='(18,0)';
      PINUSE='POWER';
      NO_LOAD_CHECK='Both';
      NO_IO_CHECK='Both';
      NO_ASSERT_CHECK='TRUE';
      NO_DIR_CHECK='TRUE';
      ALLOW_CONNECT='TRUE';
    'I2C_CLK':
      PIN_NUMBER='(32,0)';
      BIDIRECTIONAL='TRUE';
      INPUT_LOAD='(-0.01,0.01)';
      OUTPUT_LOAD='(1.0,-1.0)';
      PINUSE='BI';
    'I2C_DATA':
      PIN_NUMBER='(33,0)';
      BIDIRECTIONAL='TRUE';
      INPUT_LOAD='(-0.01,0.01)';
      OUTPUT_LOAD='(1.0,-1.0)';
      PINUSE='BI';
    'SUSPEND':
      PIN_NUMBER='(20,0)';
      BIDIRECTIONAL='TRUE';
      INPUT_LOAD='(-0.01,0.01)';
      OUTPUT_LOAD='(1.0,-1.0)';
      PINUSE='BI';
    'XTL_IN':
      PIN_NUMBER='(55,0)';
      INPUT_LOAD='(-0.01,0.01)';
      PINUSE='IN';
    'XTL_OUT':
      PIN_NUMBER='(54,0)';
      OUTPUT_LOAD='(1.0,-1.0)';
      PINUSE='OUT';
    'MODE_SEL0':
      PIN_NUMBER='(23,0)';
      INPUT_LOAD='(-0.01,0.01)';
      PINUSE='IN';
    'MODE_SEL1':
      PIN_NUMBER='(24,0)';
      INPUT_LOAD='(-0.01,0.01)';
      PINUSE='IN';
    'GND':
      PIN_NUMBER='(40,0)';
      PINUSE='POWER';
      NO_LOAD_CHECK='Both';
      NO_IO_CHECK='Both';
      NO_ASSERT_CHECK='TRUE';
      NO_DIR_CHECK='TRUE';
      ALLOW_CONNECT='TRUE';
    'VBUS_US':
      PIN_NUMBER='(17,0)';
      PINUSE='POWER';
      NO_LOAD_CHECK='Both';
      NO_IO_CHECK='Both';
      NO_ASSERT_CHECK='TRUE';
      NO_DIR_CHECK='TRUE';
      ALLOW_CONNECT='TRUE';
    'US_DP':
      PIN_NUMBER='(57,0)';
      BIDIRECTIONAL='TRUE';
      INPUT_LOAD='(-0.01,0.01)';
      OUTPUT_LOAD='(1.0,-1.0)';
      PINUSE='BI';
    'US_DM':
      PIN_NUMBER='(58,0)';
      BIDIRECTIONAL='TRUE';
      INPUT_LOAD='(-0.01,0.01)';
      OUTPUT_LOAD='(1.0,-1.0)';
      PINUSE='BI';
    'US_RXP':
      PIN_NUMBER='(9,0)';
      INPUT_LOAD='(-0.01,0.01)';
      PINUSE='IN';
    'US_RXM':
      PIN_NUMBER='(8,0)';
      INPUT_LOAD='(-0.01,0.01)';
      PINUSE='IN';
    'US_TXP':
      PIN_NUMBER='(6,0)';
      OUTPUT_LOAD='(1.0,-1.0)';
      PINUSE='OUT';
    'US_TXM':
      PIN_NUMBER='(5,0)';
      OUTPUT_LOAD='(1.0,-1.0)';
      PINUSE='OUT';
    'RREF_SS':
      PIN_NUMBER='(26,0)';
      BIDIRECTIONAL='TRUE';
      INPUT_LOAD='(-0.01,0.01)';
      OUTPUT_LOAD='(1.0,-1.0)';
      PINUSE='BI';
    'RREF_USB2':
      PIN_NUMBER='(2,0)';
      BIDIRECTIONAL='TRUE';
      INPUT_LOAD='(-0.01,0.01)';
      OUTPUT_LOAD='(1.0,-1.0)';
      PINUSE='BI';
    'NC_25':
      PIN_NUMBER='(25,0)';
      OUTPUT_TYPE='(TS,TS)';
      INPUT_LOAD='(-0.01,0.01)';
      OUTPUT_LOAD='(1.0,-1.0)';
      PINUSE='TRI';
    'PWR_EN':
      PIN_NUMBER='(29,0)';
      BIDIRECTIONAL='TRUE';
      INPUT_LOAD='(-0.01,0.01)';
      OUTPUT_LOAD='(1.0,-1.0)';
      PINUSE='BI';
    'OVRCURR':
      PIN_NUMBER='(30,0)';
      INPUT_LOAD='(-0.01,0.01)';
      PINUSE='IN';
    'RESET#':
      PIN_NUMBER='(31,0)';
      INPUT_LOAD='(-0.01,0.01)';
      PINUSE='IN';
    'RESERVED2':
      PIN_NUMBER='(22,0)';
      BIDIRECTIONAL='TRUE';
      INPUT_LOAD='(-0.01,0.01)';
      OUTPUT_LOAD='(1.0,-1.0)';
      PINUSE='BI';
    'RESERVED1':
      PIN_NUMBER='(21,0)';
      BIDIRECTIONAL='TRUE';
      INPUT_LOAD='(-0.01,0.01)';
      OUTPUT_LOAD='(1.0,-1.0)';
      PINUSE='BI';
    'EPAD':
      PIN_NUMBER='(TH,0)';
      PINUSE='POWER';
      NO_LOAD_CHECK='Both';
      NO_IO_CHECK='Both';
      NO_ASSERT_CHECK='TRUE';
      NO_DIR_CHECK='TRUE';
      ALLOW_CONNECT='TRUE';
    'DVDD12_1':
      PIN_NUMBER='(0,1)';
      PINUSE='POWER';
      NO_LOAD_CHECK='Both';
      NO_IO_CHECK='Both';
      NO_ASSERT_CHECK='TRUE';
      NO_DIR_CHECK='TRUE';
      ALLOW_CONNECT='TRUE';
    'DVDD12_2':
      PIN_NUMBER='(0,3)';
      PINUSE='POWER';
      NO_LOAD_CHECK='Both';
      NO_IO_CHECK='Both';
      NO_ASSERT_CHECK='TRUE';
      NO_DIR_CHECK='TRUE';
      ALLOW_CONNECT='TRUE';
    'VDD_EFUSE':
      PIN_NUMBER='(0,19)';
      PINUSE='POWER';
      NO_LOAD_CHECK='Both';
      NO_IO_CHECK='Both';
      NO_ASSERT_CHECK='TRUE';
      NO_DIR_CHECK='TRUE';
      ALLOW_CONNECT='TRUE';
    'DVDD12_3':
      PIN_NUMBER='(0,27)';
      PINUSE='POWER';
      NO_LOAD_CHECK='Both';
      NO_IO_CHECK='Both';
      NO_ASSERT_CHECK='TRUE';
      NO_DIR_CHECK='TRUE';
      ALLOW_CONNECT='TRUE';
    'DVDD12_8':
      PIN_NUMBER='(0,43)';
      PINUSE='POWER';
      NO_LOAD_CHECK='Both';
      NO_IO_CHECK='Both';
      NO_ASSERT_CHECK='TRUE';
      NO_DIR_CHECK='TRUE';
      ALLOW_CONNECT='TRUE';
    'DVDD12_4':
      PIN_NUMBER='(0,49)';
      PINUSE='POWER';
      NO_LOAD_CHECK='Both';
      NO_IO_CHECK='Both';
      NO_ASSERT_CHECK='TRUE';
      NO_DIR_CHECK='TRUE';
      ALLOW_CONNECT='TRUE';
    'AVDD12_6':
      PIN_NUMBER='(0,53)';
      PINUSE='POWER';
      NO_LOAD_CHECK='Both';
      NO_IO_CHECK='Both';
      NO_ASSERT_CHECK='TRUE';
      NO_DIR_CHECK='TRUE';
      ALLOW_CONNECT='TRUE';
    'DVDD12_5':
      PIN_NUMBER='(0,7)';
      PINUSE='POWER';
      NO_LOAD_CHECK='Both';
      NO_IO_CHECK='Both';
      NO_ASSERT_CHECK='TRUE';
      NO_DIR_CHECK='TRUE';
      ALLOW_CONNECT='TRUE';
    'DVDD12_6':
      PIN_NUMBER='(0,13)';
      PINUSE='POWER';
      NO_LOAD_CHECK='Both';
      NO_IO_CHECK='Both';
      NO_ASSERT_CHECK='TRUE';
      NO_DIR_CHECK='TRUE';
      ALLOW_CONNECT='TRUE';
    'DVDD12_7':
      PIN_NUMBER='(0,37)';
      PINUSE='POWER';
      NO_LOAD_CHECK='Both';
      NO_IO_CHECK='Both';
      NO_ASSERT_CHECK='TRUE';
      NO_DIR_CHECK='TRUE';
      ALLOW_CONNECT='TRUE';
    'AVDD33_1':
      PIN_NUMBER='(0,4)';
      PINUSE='POWER';
      NO_LOAD_CHECK='Both';
      NO_IO_CHECK='Both';
      NO_ASSERT_CHECK='TRUE';
      NO_DIR_CHECK='TRUE';
      ALLOW_CONNECT='TRUE';
    'AVDD33_2':
      PIN_NUMBER='(0,56)';
      PINUSE='POWER';
      NO_LOAD_CHECK='Both';
      NO_IO_CHECK='Both';
      NO_ASSERT_CHECK='TRUE';
      NO_DIR_CHECK='TRUE';
      ALLOW_CONNECT='TRUE';
    'AVDD33_3':
      PIN_NUMBER='(0,61)';
      PINUSE='POWER';
      NO_LOAD_CHECK='Both';
      NO_IO_CHECK='Both';
      NO_ASSERT_CHECK='TRUE';
      NO_DIR_CHECK='TRUE';
      ALLOW_CONNECT='TRUE';
    'AVDD33_4':
      PIN_NUMBER='(0,66)';
      PINUSE='POWER';
      NO_LOAD_CHECK='Both';
      NO_IO_CHECK='Both';
      NO_ASSERT_CHECK='TRUE';
      NO_DIR_CHECK='TRUE';
      ALLOW_CONNECT='TRUE';
    'VDD_IO':
      PIN_NUMBER='(0,28)';
      PINUSE='POWER';
      NO_LOAD_CHECK='Both';
      NO_IO_CHECK='Both';
      NO_ASSERT_CHECK='TRUE';
      NO_DIR_CHECK='TRUE';
      ALLOW_CONNECT='TRUE';
    'AVDD12_1':
      PIN_NUMBER='(0,10)';
      PINUSE='POWER';
      NO_LOAD_CHECK='Both';
      NO_IO_CHECK='Both';
      NO_ASSERT_CHECK='TRUE';
      NO_DIR_CHECK='TRUE';
      ALLOW_CONNECT='TRUE';
    'AVDD12_2':
      PIN_NUMBER='(0,16)';
      PINUSE='POWER';
      NO_LOAD_CHECK='Both';
      NO_IO_CHECK='Both';
      NO_ASSERT_CHECK='TRUE';
      NO_DIR_CHECK='TRUE';
      ALLOW_CONNECT='TRUE';
    'AVDD12_3':
      PIN_NUMBER='(0,34)';
      PINUSE='POWER';
      NO_LOAD_CHECK='Both';
      NO_IO_CHECK='Both';
      NO_ASSERT_CHECK='TRUE';
      NO_DIR_CHECK='TRUE';
      ALLOW_CONNECT='TRUE';
    'AVDD12_4':
      PIN_NUMBER='(0,46)';
      PINUSE='POWER';
      NO_LOAD_CHECK='Both';
      NO_IO_CHECK='Both';
      NO_ASSERT_CHECK='TRUE';
      NO_DIR_CHECK='TRUE';
      ALLOW_CONNECT='TRUE';
    'AVDD12_5':
      PIN_NUMBER='(0,52)';
      PINUSE='POWER';
      NO_LOAD_CHECK='Both';
      NO_IO_CHECK='Both';
      NO_ASSERT_CHECK='TRUE';
      NO_DIR_CHECK='TRUE';
      ALLOW_CONNECT='TRUE';
  end_pin;
  body
      PART_NAME='CYUSB330468LTXI';
      BODY_NAME='CYUSB330468LTXI';
      PHYS_DES_PREFIX='U';
      CLASS='IC';
      STANDARD='';
      LIFECYCLE='';
      PART_NUMBER='AJ033040001';
      JEDEC_TYPE='QFN68_TH_0-4_8X8';
      DESCRIPTION='IC CTRL(68P)CYUSB3304-68LTXI(QFN)';
      MANUFTR='CYP';
      MANUF_PN='CYUSB3304-68LTXI';
      RD_CMPLS_LVL='EU(V1)';
      CMPLS_LVL='EP(V1)';
      FROM_PJ='S5M-ROGER';
      DIP_SMD='';
      DATA='CYP_CYUSB3304-68LTXI';
      EE_CHECK_LIST='';
      FP_ECN='';
      PSL='';
      CREATOR='';
      STATUS='';
      MSD='NA';
      ESD_CDM='NA';
      ESD_HBM='+/- 2200V';
      ESD_MM='NA';
      PIN_LENGTH_SHORT_PIN='0 MILS';
      PIN_LENGTH_LONG_PIN='0 MILS';
      CREATEDAY='20170901';
      PARENT_PART_TYPE='CYUSB330468LTXI';
      PARENT_PPT='CYUSB330468LTXI';
      PARENT_PPT_PART='CYUSB330468LTXI-CYUSB3304-68LTXI,SMLF,IC,AJ033040001';
  end_body;
end_primitive;
primitive 'DIODE_TVS-SMF14A,SMLF,IC,BCSMF14AZ01';
  pin
    'A':
      PIN_NUMBER='(A)';
      INPUT_LOAD='(-0.01,0.01)';
      PINUSE='IN';
    'C':
      PIN_NUMBER='(C)';
      OUTPUT_LOAD='(1.0,-1.0)';
      PINUSE='OUT';
  end_pin;
  body
      PART_NAME='DIODE_TVS';
      BODY_NAME='DIODE_TVS';
      PHYS_DES_PREFIX='D';
      CLASS='IC';
      STANDARD='';
      LIFECYCLE='';
      PART_NUMBER='BCSMF14AZ01';
      JEDEC_TYPE='SOD123F';
      DESCRIPTION='DIODE SMF14A(14V,8.6A)SOD-123FL';
      MANUFTR='LFI';
      MANUF_PN='SMF14A';
      RD_CMPLS_LVL='EP(V1)';
      CMPLS_LVL='EP(V1)';
      DIP_SMD='';
      FP_ECN='';
      FROM_PJ='F0G-EGBERT';
      DATA='LFI_SMF14A.pdf';
      EE_CHECK_LIST='';
      STATUS='';
      PSL='';
      PREFERENCE='';
      CREATOR='';
      CREATEDAY='20190805';
      PARENT_PART_TYPE='DIODE_TVS';
      PARENT_PPT='DIODE_TVS';
      PARENT_PPT_PART='DIODE_TVS-SMF14A,SMLF,IC,BCSMF14AZ01';
  end_body;
end_primitive;
primitive 'DS125BR111RTWR-DS125BR111RTWR,SMLF,IC,AL000125003';
  pin
    'EQB0||AD3':
      PIN_NUMBER='(1)';
      INPUT_LOAD='(-0.01,0.01)';
      PINUSE='IN';
    'EQB1||AD2':
      PIN_NUMBER='(2)';
      INPUT_LOAD='(-0.01,0.01)';
      PINUSE='IN';
    'ENSMB':
      PIN_NUMBER='(3)';
      INPUT_LOAD='(-0.01,0.01)';
      PINUSE='IN';
    'SDA||VODA_DB':
      PIN_NUMBER='(4)';
      BIDIRECTIONAL='TRUE';
      INPUT_LOAD='(-0.01,0.01)';
      OUTPUT_LOAD='(1.0,-1.0)';
      PINUSE='BI';
    'SCL||VODB_DB':
      PIN_NUMBER='(5)';
      BIDIRECTIONAL='TRUE';
      INPUT_LOAD='(-0.01,0.01)';
      OUTPUT_LOAD='(1.0,-1.0)';
      PINUSE='BI';
    'PWDN':
      PIN_NUMBER='(6)';
      INPUT_LOAD='(-0.01,0.01)';
      PINUSE='IN';
    'OUTA+':
      PIN_NUMBER='(7)';
      OUTPUT_LOAD='(1.0,-1.0)';
      PINUSE='OUT';
    'OUTA-':
      PIN_NUMBER='(8)';
      OUTPUT_LOAD='(1.0,-1.0)';
      PINUSE='OUT';
    'EQA1||AD1':
      PIN_NUMBER='(9)';
      INPUT_LOAD='(-0.01,0.01)';
      PINUSE='IN';
    'EQA0||AD0':
      PIN_NUMBER='(10)';
      INPUT_LOAD='(-0.01,0.01)';
      PINUSE='IN';
    'INB+':
      PIN_NUMBER='(11)';
      INPUT_LOAD='(-0.01,0.01)';
      PINUSE='IN';
    'INB-':
      PIN_NUMBER='(12)';
      INPUT_LOAD='(-0.01,0.01)';
      PINUSE='IN';
    'RES':
      PIN_NUMBER='(13)';
      INPUT_LOAD='(-0.01,0.01)';
      PINUSE='IN';
    'SD_TH':
      PIN_NUMBER='(14)';
      INPUT_LOAD='(-0.01,0.01)';
      PINUSE='IN';
    'VIN':
      PIN_NUMBER='(15)';
      PINUSE='POWER';
      NO_LOAD_CHECK='Both';
      NO_IO_CHECK='Both';
      NO_ASSERT_CHECK='TRUE';
      NO_DIR_CHECK='TRUE';
      ALLOW_CONNECT='TRUE';
    'VDD_SEL':
      PIN_NUMBER='(16)';
      INPUT_LOAD='(-0.01,0.01)';
      PINUSE='IN';
    'VOD_SEL||READEN#':
      PIN_NUMBER='(17)';
      INPUT_LOAD='(-0.01,0.01)';
      PINUSE='IN';
    'RXDET||DONE#':
      PIN_NUMBER='(18)';
      BIDIRECTIONAL='TRUE';
      INPUT_LOAD='(-0.01,0.01)';
      OUTPUT_LOAD='(1.0,-1.0)';
      PINUSE='BI';
    'OUTB-':
      PIN_NUMBER='(19)';
      OUTPUT_LOAD='(1.0,-1.0)';
      PINUSE='OUT';
    'OUTB+':
      PIN_NUMBER='(20)';
      OUTPUT_LOAD='(1.0,-1.0)';
      PINUSE='OUT';
    'VDD_21':
      PIN_NUMBER='(21)';
      PINUSE='POWER';
      NO_LOAD_CHECK='Both';
      NO_IO_CHECK='Both';
      NO_ASSERT_CHECK='TRUE';
      NO_DIR_CHECK='TRUE';
      ALLOW_CONNECT='TRUE';
    'VDD_22':
      PIN_NUMBER='(22)';
      PINUSE='POWER';
      NO_LOAD_CHECK='Both';
      NO_IO_CHECK='Both';
      NO_ASSERT_CHECK='TRUE';
      NO_DIR_CHECK='TRUE';
      ALLOW_CONNECT='TRUE';
    'INA-':
      PIN_NUMBER='(23)';
      INPUT_LOAD='(-0.01,0.01)';
      PINUSE='IN';
    'INA+':
      PIN_NUMBER='(24)';
      INPUT_LOAD='(-0.01,0.01)';
      PINUSE='IN';
    'TH_GND':
      PIN_NUMBER='(25)';
      PINUSE='POWER';
      NO_LOAD_CHECK='Both';
      NO_IO_CHECK='Both';
      NO_ASSERT_CHECK='TRUE';
      NO_DIR_CHECK='TRUE';
      ALLOW_CONNECT='TRUE';
  end_pin;
  body
      PART_NAME='DS125BR111RTWR';
      BODY_NAME='DS125BR111RTWR';
      PHYS_DES_PREFIX='U';
      CLASS='IC';
      STANDARD='';
      LIFECYCLE='';
      PART_NUMBER='AL000125003';
      JEDEC_TYPE='WQFN24_TH_0-5_4X4XA';
      DESCRIPTION='IC OTHER(24P)DS125BR111RTWR(WQFN)';
      MANUFTR='TIC';
      MANUF_PN='DS125BR111RTWR';
      RD_CMPLS_LVL='EP(V1)';
      CMPLS_LVL='EP(V1)';
      FROM_PJ='F0T-IVES';
      DIP_SMD='';
      DATA='TIC_DS125BR111RTWR.pdf';
      EE_CHECK_LIST='';
      FP_ECN='';
      PSL='';
      CREATOR='';
      STATUS='';
      MSD='';
      ESD_CDM='';
      ESD_HBM='';
      ESD_MM='';
      PIN_LENGTH_SHORT_PIN='0 MILS';
      PIN_LENGTH_LONG_PIN='0 MILS';
      CREATEDAY='20220331';
      PARENT_PART_TYPE='DS125BR111RTWR';
      PARENT_PPT='DS125BR111RTWR';
      PARENT_PPT_PART='DS125BR111RTWR-DS125BR111RTWR,SMLF,IC,AL000125003';
  end_body;
end_primitive;
primitive 'GENOA_SP5-SOCKET6096_13568-001,SMLF,IO,DGA^6000030';
  pin
    'MA_ALERT_L':
      PIN_NUMBER='(AR74,0,0,0,0,0,0,0,0,0,0,0,0,0,0,0,0,0,0,0,0,0,0,0,0,0,0,0,0,~
0,0,0,0,0,0,0,0,0,0,0)';
      INPUT_LOAD='(-0.01,0.01)';
      PINUSE='IN';
    'MA_RESET_L':
      PIN_NUMBER='(AT74,0,0,0,0,0,0,0,0,0,0,0,0,0,0,0,0,0,0,0,0,0,0,0,0,0,0,0,0,~
0,0,0,0,0,0,0,0,0,0,0)';
      OUTPUT_LOAD='(1.0,-1.0)';
      PINUSE='OUT';
    'MAB_DQS_L5':
      PIN_NUMBER='(CE73,0,0,0,0,0,0,0,0,0,0,0,0,0,0,0,0,0,0,0,0,0,0,0,0,0,0,0,0,~
0,0,0,0,0,0,0,0,0,0,0)';
      BIDIRECTIONAL='TRUE';
      INPUT_LOAD='(-0.01,0.01)';
      OUTPUT_LOAD='(1.0,-1.0)';
      PINUSE='BI';
    'MAB_DQS_H1':
      PIN_NUMBER='(CK74,0,0,0,0,0,0,0,0,0,0,0,0,0,0,0,0,0,0,0,0,0,0,0,0,0,0,0,0,~
0,0,0,0,0,0,0,0,0,0,0)';
      BIDIRECTIONAL='TRUE';
      INPUT_LOAD='(-0.01,0.01)';
      OUTPUT_LOAD='(1.0,-1.0)';
      PINUSE='BI';
    'MAB_DATA29':
      PIN_NUMBER='(DE73,0,0,0,0,0,0,0,0,0,0,0,0,0,0,0,0,0,0,0,0,0,0,0,0,0,0,0,0,~
0,0,0,0,0,0,0,0,0,0,0)';
      BIDIRECTIONAL='TRUE';
      INPUT_LOAD='(-0.01,0.01)';
      OUTPUT_LOAD='(1.0,-1.0)';
      PINUSE='BI';
    'MAB_DATA18':
      PIN_NUMBER='(CR74,0,0,0,0,0,0,0,0,0,0,0,0,0,0,0,0,0,0,0,0,0,0,0,0,0,0,0,0,~
0,0,0,0,0,0,0,0,0,0,0)';
      BIDIRECTIONAL='TRUE';
      INPUT_LOAD='(-0.01,0.01)';
      OUTPUT_LOAD='(1.0,-1.0)';
      PINUSE='BI';
    'MAB_DATA3':
      PIN_NUMBER='(CD72,0,0,0,0,0,0,0,0,0,0,0,0,0,0,0,0,0,0,0,0,0,0,0,0,0,0,0,0,~
0,0,0,0,0,0,0,0,0,0,0)';
      BIDIRECTIONAL='TRUE';
      INPUT_LOAD='(-0.01,0.01)';
      OUTPUT_LOAD='(1.0,-1.0)';
      PINUSE='BI';
    'MAA_DQS_H7':
      PIN_NUMBER='(AA73,0,0,0,0,0,0,0,0,0,0,0,0,0,0,0,0,0,0,0,0,0,0,0,0,0,0,0,0,~
0,0,0,0,0,0,0,0,0,0,0)';
      BIDIRECTIONAL='TRUE';
      INPUT_LOAD='(-0.01,0.01)';
      OUTPUT_LOAD='(1.0,-1.0)';
      PINUSE='BI';
    'MAA_DATA4':
      PIN_NUMBER='(J74,0,0,0,0,0,0,0,0,0,0,0,0,0,0,0,0,0,0,0,0,0,0,0,0,0,0,0,0,0~
,0,0,0,0,0,0,0,0,0,0)';
      BIDIRECTIONAL='TRUE';
      INPUT_LOAD='(-0.01,0.01)';
      OUTPUT_LOAD='(1.0,-1.0)';
      PINUSE='BI';
    'MAA1_CS_L0':
      PIN_NUMBER='(AU74,0,0,0,0,0,0,0,0,0,0,0,0,0,0,0,0,0,0,0,0,0,0,0,0,0,0,0,0,~
0,0,0,0,0,0,0,0,0,0,0)';
      OUTPUT_LOAD='(1.0,-1.0)';
      PINUSE='OUT';
    'MAA0_CS_L1':
      PIN_NUMBER='(AW73,0,0,0,0,0,0,0,0,0,0,0,0,0,0,0,0,0,0,0,0,0,0,0,0,0,0,0,0,~
0,0,0,0,0,0,0,0,0,0,0)';
      OUTPUT_LOAD='(1.0,-1.0)';
      PINUSE='OUT';
    'MAB_DQS_L6':
      PIN_NUMBER='(CL73,0,0,0,0,0,0,0,0,0,0,0,0,0,0,0,0,0,0,0,0,0,0,0,0,0,0,0,0,~
0,0,0,0,0,0,0,0,0,0,0)';
      BIDIRECTIONAL='TRUE';
      INPUT_LOAD='(-0.01,0.01)';
      OUTPUT_LOAD='(1.0,-1.0)';
      PINUSE='BI';
    'MAB_DQS_H2':
      PIN_NUMBER='(CT74,0,0,0,0,0,0,0,0,0,0,0,0,0,0,0,0,0,0,0,0,0,0,0,0,0,0,0,0,~
0,0,0,0,0,0,0,0,0,0,0)';
      BIDIRECTIONAL='TRUE';
      INPUT_LOAD='(-0.01,0.01)';
      OUTPUT_LOAD='(1.0,-1.0)';
      PINUSE='BI';
    'MAB_DATA19':
      PIN_NUMBER='(CT72,0,0,0,0,0,0,0,0,0,0,0,0,0,0,0,0,0,0,0,0,0,0,0,0,0,0,0,0,~
0,0,0,0,0,0,0,0,0,0,0)';
      BIDIRECTIONAL='TRUE';
      INPUT_LOAD='(-0.01,0.01)';
      OUTPUT_LOAD='(1.0,-1.0)';
      PINUSE='BI';
    'MAB_DATA4':
      PIN_NUMBER='(CF74,0,0,0,0,0,0,0,0,0,0,0,0,0,0,0,0,0,0,0,0,0,0,0,0,0,0,0,0,~
0,0,0,0,0,0,0,0,0,0,0)';
      BIDIRECTIONAL='TRUE';
      INPUT_LOAD='(-0.01,0.01)';
      OUTPUT_LOAD='(1.0,-1.0)';
      PINUSE='BI';
    'MAA_DQS_H8':
      PIN_NUMBER='(AG73,0,0,0,0,0,0,0,0,0,0,0,0,0,0,0,0,0,0,0,0,0,0,0,0,0,0,0,0,~
0,0,0,0,0,0,0,0,0,0,0)';
      BIDIRECTIONAL='TRUE';
      INPUT_LOAD='(-0.01,0.01)';
      OUTPUT_LOAD='(1.0,-1.0)';
      PINUSE='BI';
    'MAA_DATA30':
      PIN_NUMBER='(AH74,0,0,0,0,0,0,0,0,0,0,0,0,0,0,0,0,0,0,0,0,0,0,0,0,0,0,0,0,~
0,0,0,0,0,0,0,0,0,0,0)';
      BIDIRECTIONAL='TRUE';
      INPUT_LOAD='(-0.01,0.01)';
      OUTPUT_LOAD='(1.0,-1.0)';
      PINUSE='BI';
    'MAA_DATA5':
      PIN_NUMBER='(K72,0,0,0,0,0,0,0,0,0,0,0,0,0,0,0,0,0,0,0,0,0,0,0,0,0,0,0,0,0~
,0,0,0,0,0,0,0,0,0,0)';
      BIDIRECTIONAL='TRUE';
      INPUT_LOAD='(-0.01,0.01)';
      OUTPUT_LOAD='(1.0,-1.0)';
      PINUSE='BI';
    'MAA1_CS_L1':
      PIN_NUMBER='(AV72,0,0,0,0,0,0,0,0,0,0,0,0,0,0,0,0,0,0,0,0,0,0,0,0,0,0,0,0,~
0,0,0,0,0,0,0,0,0,0,0)';
      OUTPUT_LOAD='(1.0,-1.0)';
      PINUSE='OUT';
    'MAB_DQS_L7':
      PIN_NUMBER='(CU73,0,0,0,0,0,0,0,0,0,0,0,0,0,0,0,0,0,0,0,0,0,0,0,0,0,0,0,0,~
0,0,0,0,0,0,0,0,0,0,0)';
      BIDIRECTIONAL='TRUE';
      INPUT_LOAD='(-0.01,0.01)';
      OUTPUT_LOAD='(1.0,-1.0)';
      PINUSE='BI';
    'MAB_DQS_H3':
      PIN_NUMBER='(DB74,0,0,0,0,0,0,0,0,0,0,0,0,0,0,0,0,0,0,0,0,0,0,0,0,0,0,0,0,~
0,0,0,0,0,0,0,0,0,0,0)';
      BIDIRECTIONAL='TRUE';
      INPUT_LOAD='(-0.01,0.01)';
      OUTPUT_LOAD='(1.0,-1.0)';
      PINUSE='BI';
    'MAB_DATA5':
      PIN_NUMBER='(CG73,0,0,0,0,0,0,0,0,0,0,0,0,0,0,0,0,0,0,0,0,0,0,0,0,0,0,0,0,~
0,0,0,0,0,0,0,0,0,0,0)';
      BIDIRECTIONAL='TRUE';
      INPUT_LOAD='(-0.01,0.01)';
      OUTPUT_LOAD='(1.0,-1.0)';
      PINUSE='BI';
    'MAA_DQS_H9':
      PIN_NUMBER='(AN73,0,0,0,0,0,0,0,0,0,0,0,0,0,0,0,0,0,0,0,0,0,0,0,0,0,0,0,0,~
0,0,0,0,0,0,0,0,0,0,0)';
      BIDIRECTIONAL='TRUE';
      INPUT_LOAD='(-0.01,0.01)';
      OUTPUT_LOAD='(1.0,-1.0)';
      PINUSE='BI';
    'MAA_DATA31':
      PIN_NUMBER='(AJ73,0,0,0,0,0,0,0,0,0,0,0,0,0,0,0,0,0,0,0,0,0,0,0,0,0,0,0,0,~
0,0,0,0,0,0,0,0,0,0,0)';
      BIDIRECTIONAL='TRUE';
      INPUT_LOAD='(-0.01,0.01)';
      OUTPUT_LOAD='(1.0,-1.0)';
      PINUSE='BI';
    'MAA_DATA20':
      PIN_NUMBER='(AA74,0,0,0,0,0,0,0,0,0,0,0,0,0,0,0,0,0,0,0,0,0,0,0,0,0,0,0,0,~
0,0,0,0,0,0,0,0,0,0,0)';
      BIDIRECTIONAL='TRUE';
      INPUT_LOAD='(-0.01,0.01)';
      OUTPUT_LOAD='(1.0,-1.0)';
      PINUSE='BI';
    'MAA_DATA6':
      PIN_NUMBER='(K74,0,0,0,0,0,0,0,0,0,0,0,0,0,0,0,0,0,0,0,0,0,0,0,0,0,0,0,0,0~
,0,0,0,0,0,0,0,0,0,0)';
      BIDIRECTIONAL='TRUE';
      INPUT_LOAD='(-0.01,0.01)';
      OUTPUT_LOAD='(1.0,-1.0)';
      PINUSE='BI';
    'MAA_CHECK0':
      PIN_NUMBER='(AJ74,0,0,0,0,0,0,0,0,0,0,0,0,0,0,0,0,0,0,0,0,0,0,0,0,0,0,0,0,~
0,0,0,0,0,0,0,0,0,0,0)';
      BIDIRECTIONAL='TRUE';
      INPUT_LOAD='(-0.01,0.01)';
      OUTPUT_LOAD='(1.0,-1.0)';
      PINUSE='BI';
    'MAB_DQS_L8':
      PIN_NUMBER='(DC73,0,0,0,0,0,0,0,0,0,0,0,0,0,0,0,0,0,0,0,0,0,0,0,0,0,0,0,0,~
0,0,0,0,0,0,0,0,0,0,0)';
      BIDIRECTIONAL='TRUE';
      INPUT_LOAD='(-0.01,0.01)';
      OUTPUT_LOAD='(1.0,-1.0)';
      PINUSE='BI';
    'MAB_DQS_H4':
      PIN_NUMBER='(BY72,0,0,0,0,0,0,0,0,0,0,0,0,0,0,0,0,0,0,0,0,0,0,0,0,0,0,0,0,~
0,0,0,0,0,0,0,0,0,0,0)';
      BIDIRECTIONAL='TRUE';
      INPUT_LOAD='(-0.01,0.01)';
      OUTPUT_LOAD='(1.0,-1.0)';
      PINUSE='BI';
    'MAB_DATA6':
      PIN_NUMBER='(CG74,0,0,0,0,0,0,0,0,0,0,0,0,0,0,0,0,0,0,0,0,0,0,0,0,0,0,0,0,~
0,0,0,0,0,0,0,0,0,0,0)';
      BIDIRECTIONAL='TRUE';
      INPUT_LOAD='(-0.01,0.01)';
      OUTPUT_LOAD='(1.0,-1.0)';
      PINUSE='BI';
    'MAA_DATA21':
      PIN_NUMBER='(AB72,0,0,0,0,0,0,0,0,0,0,0,0,0,0,0,0,0,0,0,0,0,0,0,0,0,0,0,0,~
0,0,0,0,0,0,0,0,0,0,0)';
      BIDIRECTIONAL='TRUE';
      INPUT_LOAD='(-0.01,0.01)';
      OUTPUT_LOAD='(1.0,-1.0)';
      PINUSE='BI';
    'MAA_DATA10':
      PIN_NUMBER='(M74,0,0,0,0,0,0,0,0,0,0,0,0,0,0,0,0,0,0,0,0,0,0,0,0,0,0,0,0,0~
,0,0,0,0,0,0,0,0,0,0)';
      BIDIRECTIONAL='TRUE';
      INPUT_LOAD='(-0.01,0.01)';
      OUTPUT_LOAD='(1.0,-1.0)';
      PINUSE='BI';
    'MAA_DATA7':
      PIN_NUMBER='(L73,0,0,0,0,0,0,0,0,0,0,0,0,0,0,0,0,0,0,0,0,0,0,0,0,0,0,0,0,0~
,0,0,0,0,0,0,0,0,0,0)';
      BIDIRECTIONAL='TRUE';
      INPUT_LOAD='(-0.01,0.01)';
      OUTPUT_LOAD='(1.0,-1.0)';
      PINUSE='BI';
    'MAA_CHECK1':
      PIN_NUMBER='(AK72,0,0,0,0,0,0,0,0,0,0,0,0,0,0,0,0,0,0,0,0,0,0,0,0,0,0,0,0,~
0,0,0,0,0,0,0,0,0,0,0)';
      BIDIRECTIONAL='TRUE';
      INPUT_LOAD='(-0.01,0.01)';
      OUTPUT_LOAD='(1.0,-1.0)';
      PINUSE='BI';
    'MAB_DQS_L9':
      PIN_NUMBER='(BW74,0,0,0,0,0,0,0,0,0,0,0,0,0,0,0,0,0,0,0,0,0,0,0,0,0,0,0,0,~
0,0,0,0,0,0,0,0,0,0,0)';
      BIDIRECTIONAL='TRUE';
      INPUT_LOAD='(-0.01,0.01)';
      OUTPUT_LOAD='(1.0,-1.0)';
      PINUSE='BI';
    'MAB_DQS_H5':
      PIN_NUMBER='(CF72,0,0,0,0,0,0,0,0,0,0,0,0,0,0,0,0,0,0,0,0,0,0,0,0,0,0,0,0,~
0,0,0,0,0,0,0,0,0,0,0)';
      BIDIRECTIONAL='TRUE';
      INPUT_LOAD='(-0.01,0.01)';
      OUTPUT_LOAD='(1.0,-1.0)';
      PINUSE='BI';
    'MAB_DATA7':
      PIN_NUMBER='(CH72,0,0,0,0,0,0,0,0,0,0,0,0,0,0,0,0,0,0,0,0,0,0,0,0,0,0,0,0,~
0,0,0,0,0,0,0,0,0,0,0)';
      BIDIRECTIONAL='TRUE';
      INPUT_LOAD='(-0.01,0.01)';
      OUTPUT_LOAD='(1.0,-1.0)';
      PINUSE='BI';
    'MAA_DATA22':
      PIN_NUMBER='(AB74,0,0,0,0,0,0,0,0,0,0,0,0,0,0,0,0,0,0,0,0,0,0,0,0,0,0,0,0,~
0,0,0,0,0,0,0,0,0,0,0)';
      BIDIRECTIONAL='TRUE';
      INPUT_LOAD='(-0.01,0.01)';
      OUTPUT_LOAD='(1.0,-1.0)';
      PINUSE='BI';
    'MAA_DATA11':
      PIN_NUMBER='(N73,0,0,0,0,0,0,0,0,0,0,0,0,0,0,0,0,0,0,0,0,0,0,0,0,0,0,0,0,0~
,0,0,0,0,0,0,0,0,0,0)';
      BIDIRECTIONAL='TRUE';
      INPUT_LOAD='(-0.01,0.01)';
      OUTPUT_LOAD='(1.0,-1.0)';
      PINUSE='BI';
    'MAA_DATA8':
      PIN_NUMBER='(L74,0,0,0,0,0,0,0,0,0,0,0,0,0,0,0,0,0,0,0,0,0,0,0,0,0,0,0,0,0~
,0,0,0,0,0,0,0,0,0,0)';
      BIDIRECTIONAL='TRUE';
      INPUT_LOAD='(-0.01,0.01)';
      OUTPUT_LOAD='(1.0,-1.0)';
      PINUSE='BI';
    'MAA_CHECK2':
      PIN_NUMBER='(AK74,0,0,0,0,0,0,0,0,0,0,0,0,0,0,0,0,0,0,0,0,0,0,0,0,0,0,0,0,~
0,0,0,0,0,0,0,0,0,0,0)';
      BIDIRECTIONAL='TRUE';
      INPUT_LOAD='(-0.01,0.01)';
      OUTPUT_LOAD='(1.0,-1.0)';
      PINUSE='BI';
    'MAB_DQS_H6':
      PIN_NUMBER='(CM72,0,0,0,0,0,0,0,0,0,0,0,0,0,0,0,0,0,0,0,0,0,0,0,0,0,0,0,0,~
0,0,0,0,0,0,0,0,0,0,0)';
      BIDIRECTIONAL='TRUE';
      INPUT_LOAD='(-0.01,0.01)';
      OUTPUT_LOAD='(1.0,-1.0)';
      PINUSE='BI';
    'MAB_DATA8':
      PIN_NUMBER='(CH74,0,0,0,0,0,0,0,0,0,0,0,0,0,0,0,0,0,0,0,0,0,0,0,0,0,0,0,0,~
0,0,0,0,0,0,0,0,0,0,0)';
      BIDIRECTIONAL='TRUE';
      INPUT_LOAD='(-0.01,0.01)';
      OUTPUT_LOAD='(1.0,-1.0)';
      PINUSE='BI';
    'MAB0_CS_L0':
      PIN_NUMBER='(BM72,0,0,0,0,0,0,0,0,0,0,0,0,0,0,0,0,0,0,0,0,0,0,0,0,0,0,0,0,~
0,0,0,0,0,0,0,0,0,0,0)';
      OUTPUT_LOAD='(1.0,-1.0)';
      PINUSE='OUT';
    'MAA_DATA23':
      PIN_NUMBER='(AC73,0,0,0,0,0,0,0,0,0,0,0,0,0,0,0,0,0,0,0,0,0,0,0,0,0,0,0,0,~
0,0,0,0,0,0,0,0,0,0,0)';
      BIDIRECTIONAL='TRUE';
      INPUT_LOAD='(-0.01,0.01)';
      OUTPUT_LOAD='(1.0,-1.0)';
      PINUSE='BI';
    'MAA_DATA12':
      PIN_NUMBER='(R74,0,0,0,0,0,0,0,0,0,0,0,0,0,0,0,0,0,0,0,0,0,0,0,0,0,0,0,0,0~
,0,0,0,0,0,0,0,0,0,0)';
      BIDIRECTIONAL='TRUE';
      INPUT_LOAD='(-0.01,0.01)';
      OUTPUT_LOAD='(1.0,-1.0)';
      PINUSE='BI';
    'MAA_DATA9':
      PIN_NUMBER='(M72,0,0,0,0,0,0,0,0,0,0,0,0,0,0,0,0,0,0,0,0,0,0,0,0,0,0,0,0,0~
,0,0,0,0,0,0,0,0,0,0)';
      BIDIRECTIONAL='TRUE';
      INPUT_LOAD='(-0.01,0.01)';
      OUTPUT_LOAD='(1.0,-1.0)';
      PINUSE='BI';
    'MAA_CHECK3':
      PIN_NUMBER='(AL73,0,0,0,0,0,0,0,0,0,0,0,0,0,0,0,0,0,0,0,0,0,0,0,0,0,0,0,0,~
0,0,0,0,0,0,0,0,0,0,0)';
      BIDIRECTIONAL='TRUE';
      INPUT_LOAD='(-0.01,0.01)';
      OUTPUT_LOAD='(1.0,-1.0)';
      PINUSE='BI';
    'MAB_DQS_H7':
      PIN_NUMBER='(CV72,0,0,0,0,0,0,0,0,0,0,0,0,0,0,0,0,0,0,0,0,0,0,0,0,0,0,0,0,~
0,0,0,0,0,0,0,0,0,0,0)';
      BIDIRECTIONAL='TRUE';
      INPUT_LOAD='(-0.01,0.01)';
      OUTPUT_LOAD='(1.0,-1.0)';
      PINUSE='BI';
    'MAB_DATA9':
      PIN_NUMBER='(CJ73,0,0,0,0,0,0,0,0,0,0,0,0,0,0,0,0,0,0,0,0,0,0,0,0,0,0,0,0,~
0,0,0,0,0,0,0,0,0,0,0)';
      BIDIRECTIONAL='TRUE';
      INPUT_LOAD='(-0.01,0.01)';
      OUTPUT_LOAD='(1.0,-1.0)';
      PINUSE='BI';
    'MAB1_CS_L0':
      PIN_NUMBER='(BL73,0,0,0,0,0,0,0,0,0,0,0,0,0,0,0,0,0,0,0,0,0,0,0,0,0,0,0,0,~
0,0,0,0,0,0,0,0,0,0,0)';
      OUTPUT_LOAD='(1.0,-1.0)';
      PINUSE='OUT';
    'MAB0_CS_L1':
      PIN_NUMBER='(BN74,0,0,0,0,0,0,0,0,0,0,0,0,0,0,0,0,0,0,0,0,0,0,0,0,0,0,0,0,~
0,0,0,0,0,0,0,0,0,0,0)';
      OUTPUT_LOAD='(1.0,-1.0)';
      PINUSE='OUT';
    'MAA_DQS_L0':
      PIN_NUMBER='(H74,0,0,0,0,0,0,0,0,0,0,0,0,0,0,0,0,0,0,0,0,0,0,0,0,0,0,0,0,0~
,0,0,0,0,0,0,0,0,0,0)';
      BIDIRECTIONAL='TRUE';
      INPUT_LOAD='(-0.01,0.01)';
      OUTPUT_LOAD='(1.0,-1.0)';
      PINUSE='BI';
    'MAA_DATA24':
      PIN_NUMBER='(AC74,0,0,0,0,0,0,0,0,0,0,0,0,0,0,0,0,0,0,0,0,0,0,0,0,0,0,0,0,~
0,0,0,0,0,0,0,0,0,0,0)';
      BIDIRECTIONAL='TRUE';
      INPUT_LOAD='(-0.01,0.01)';
      OUTPUT_LOAD='(1.0,-1.0)';
      PINUSE='BI';
    'MAA_DATA13':
      PIN_NUMBER='(T72,0,0,0,0,0,0,0,0,0,0,0,0,0,0,0,0,0,0,0,0,0,0,0,0,0,0,0,0,0~
,0,0,0,0,0,0,0,0,0,0)';
      BIDIRECTIONAL='TRUE';
      INPUT_LOAD='(-0.01,0.01)';
      OUTPUT_LOAD='(1.0,-1.0)';
      PINUSE='BI';
    'MAA_CHECK4':
      PIN_NUMBER='(AN74,0,0,0,0,0,0,0,0,0,0,0,0,0,0,0,0,0,0,0,0,0,0,0,0,0,0,0,0,~
0,0,0,0,0,0,0,0,0,0,0)';
      BIDIRECTIONAL='TRUE';
      INPUT_LOAD='(-0.01,0.01)';
      OUTPUT_LOAD='(1.0,-1.0)';
      PINUSE='BI';
    'MAB_DQS_H8':
      PIN_NUMBER='(DD72,0,0,0,0,0,0,0,0,0,0,0,0,0,0,0,0,0,0,0,0,0,0,0,0,0,0,0,0,~
0,0,0,0,0,0,0,0,0,0,0)';
      BIDIRECTIONAL='TRUE';
      INPUT_LOAD='(-0.01,0.01)';
      OUTPUT_LOAD='(1.0,-1.0)';
      PINUSE='BI';
    'MAB_DATA30':
      PIN_NUMBER='(DE74,0,0,0,0,0,0,0,0,0,0,0,0,0,0,0,0,0,0,0,0,0,0,0,0,0,0,0,0,~
0,0,0,0,0,0,0,0,0,0,0)';
      BIDIRECTIONAL='TRUE';
      INPUT_LOAD='(-0.01,0.01)';
      OUTPUT_LOAD='(1.0,-1.0)';
      PINUSE='BI';
    'MAB1_CS_L1':
      PIN_NUMBER='(BM74,0,0,0,0,0,0,0,0,0,0,0,0,0,0,0,0,0,0,0,0,0,0,0,0,0,0,0,0,~
0,0,0,0,0,0,0,0,0,0,0)';
      OUTPUT_LOAD='(1.0,-1.0)';
      PINUSE='OUT';
    'MAA_DQS_L1':
      PIN_NUMBER='(P74,0,0,0,0,0,0,0,0,0,0,0,0,0,0,0,0,0,0,0,0,0,0,0,0,0,0,0,0,0~
,0,0,0,0,0,0,0,0,0,0)';
      BIDIRECTIONAL='TRUE';
      INPUT_LOAD='(-0.01,0.01)';
      OUTPUT_LOAD='(1.0,-1.0)';
      PINUSE='BI';
    'MAA_DATA25':
      PIN_NUMBER='(AD72,0,0,0,0,0,0,0,0,0,0,0,0,0,0,0,0,0,0,0,0,0,0,0,0,0,0,0,0,~
0,0,0,0,0,0,0,0,0,0,0)';
      BIDIRECTIONAL='TRUE';
      INPUT_LOAD='(-0.01,0.01)';
      OUTPUT_LOAD='(1.0,-1.0)';
      PINUSE='BI';
    'MAA_DATA14':
      PIN_NUMBER='(T74,0,0,0,0,0,0,0,0,0,0,0,0,0,0,0,0,0,0,0,0,0,0,0,0,0,0,0,0,0~
,0,0,0,0,0,0,0,0,0,0)';
      BIDIRECTIONAL='TRUE';
      INPUT_LOAD='(-0.01,0.01)';
      OUTPUT_LOAD='(1.0,-1.0)';
      PINUSE='BI';
    'MAA_CHECK5':
      PIN_NUMBER='(AP72,0,0,0,0,0,0,0,0,0,0,0,0,0,0,0,0,0,0,0,0,0,0,0,0,0,0,0,0,~
0,0,0,0,0,0,0,0,0,0,0)';
      BIDIRECTIONAL='TRUE';
      INPUT_LOAD='(-0.01,0.01)';
      OUTPUT_LOAD='(1.0,-1.0)';
      PINUSE='BI';
    'MAB_DATA31':
      PIN_NUMBER='(DF74,0,0,0,0,0,0,0,0,0,0,0,0,0,0,0,0,0,0,0,0,0,0,0,0,0,0,0,0,~
0,0,0,0,0,0,0,0,0,0,0)';
      BIDIRECTIONAL='TRUE';
      INPUT_LOAD='(-0.01,0.01)';
      OUTPUT_LOAD='(1.0,-1.0)';
      PINUSE='BI';
    'MAB_DATA20':
      PIN_NUMBER='(CV74,0,0,0,0,0,0,0,0,0,0,0,0,0,0,0,0,0,0,0,0,0,0,0,0,0,0,0,0,~
0,0,0,0,0,0,0,0,0,0,0)';
      BIDIRECTIONAL='TRUE';
      INPUT_LOAD='(-0.01,0.01)';
      OUTPUT_LOAD='(1.0,-1.0)';
      PINUSE='BI';
    'MAB_CHECK0':
      PIN_NUMBER='(BY74,0,0,0,0,0,0,0,0,0,0,0,0,0,0,0,0,0,0,0,0,0,0,0,0,0,0,0,0,~
0,0,0,0,0,0,0,0,0,0,0)';
      BIDIRECTIONAL='TRUE';
      INPUT_LOAD='(-0.01,0.01)';
      OUTPUT_LOAD='(1.0,-1.0)';
      PINUSE='BI';
    'MAA_DQS_L2':
      PIN_NUMBER='(Y74,0,0,0,0,0,0,0,0,0,0,0,0,0,0,0,0,0,0,0,0,0,0,0,0,0,0,0,0,0~
,0,0,0,0,0,0,0,0,0,0)';
      BIDIRECTIONAL='TRUE';
      INPUT_LOAD='(-0.01,0.01)';
      OUTPUT_LOAD='(1.0,-1.0)';
      PINUSE='BI';
    'MAA_DATA26':
      PIN_NUMBER='(AD74,0,0,0,0,0,0,0,0,0,0,0,0,0,0,0,0,0,0,0,0,0,0,0,0,0,0,0,0,~
0,0,0,0,0,0,0,0,0,0,0)';
      BIDIRECTIONAL='TRUE';
      INPUT_LOAD='(-0.01,0.01)';
      OUTPUT_LOAD='(1.0,-1.0)';
      PINUSE='BI';
    'MAA_DATA15':
      PIN_NUMBER='(U73,0,0,0,0,0,0,0,0,0,0,0,0,0,0,0,0,0,0,0,0,0,0,0,0,0,0,0,0,0~
,0,0,0,0,0,0,0,0,0,0)';
      BIDIRECTIONAL='TRUE';
      INPUT_LOAD='(-0.01,0.01)';
      OUTPUT_LOAD='(1.0,-1.0)';
      PINUSE='BI';
    'MAA_CHECK6':
      PIN_NUMBER='(AP74,0,0,0,0,0,0,0,0,0,0,0,0,0,0,0,0,0,0,0,0,0,0,0,0,0,0,0,0,~
0,0,0,0,0,0,0,0,0,0,0)';
      BIDIRECTIONAL='TRUE';
      INPUT_LOAD='(-0.01,0.01)';
      OUTPUT_LOAD='(1.0,-1.0)';
      PINUSE='BI';
    'MAA0_RSP_L':
      PIN_NUMBER='(BN73,0,0,0,0,0,0,0,0,0,0,0,0,0,0,0,0,0,0,0,0,0,0,0,0,0,0,0,0,~
0,0,0,0,0,0,0,0,0,0,0)';
      INPUT_LOAD='(-0.01,0.01)';
      PINUSE='IN';
    'MAB_DATA21':
      PIN_NUMBER='(CW73,0,0,0,0,0,0,0,0,0,0,0,0,0,0,0,0,0,0,0,0,0,0,0,0,0,0,0,0,~
0,0,0,0,0,0,0,0,0,0,0)';
      BIDIRECTIONAL='TRUE';
      INPUT_LOAD='(-0.01,0.01)';
      OUTPUT_LOAD='(1.0,-1.0)';
      PINUSE='BI';
    'MAB_DATA10':
      PIN_NUMBER='(CJ74,0,0,0,0,0,0,0,0,0,0,0,0,0,0,0,0,0,0,0,0,0,0,0,0,0,0,0,0,~
0,0,0,0,0,0,0,0,0,0,0)';
      BIDIRECTIONAL='TRUE';
      INPUT_LOAD='(-0.01,0.01)';
      OUTPUT_LOAD='(1.0,-1.0)';
      PINUSE='BI';
    'MAB_CHECK1':
      PIN_NUMBER='(CA73,0,0,0,0,0,0,0,0,0,0,0,0,0,0,0,0,0,0,0,0,0,0,0,0,0,0,0,0,~
0,0,0,0,0,0,0,0,0,0,0)';
      BIDIRECTIONAL='TRUE';
      INPUT_LOAD='(-0.01,0.01)';
      OUTPUT_LOAD='(1.0,-1.0)';
      PINUSE='BI';
    'MAA_DQS_L3':
      PIN_NUMBER='(AF74,0,0,0,0,0,0,0,0,0,0,0,0,0,0,0,0,0,0,0,0,0,0,0,0,0,0,0,0,~
0,0,0,0,0,0,0,0,0,0,0)';
      BIDIRECTIONAL='TRUE';
      INPUT_LOAD='(-0.01,0.01)';
      OUTPUT_LOAD='(1.0,-1.0)';
      PINUSE='BI';
    'MAA_DATA27':
      PIN_NUMBER='(AE73,0,0,0,0,0,0,0,0,0,0,0,0,0,0,0,0,0,0,0,0,0,0,0,0,0,0,0,0,~
0,0,0,0,0,0,0,0,0,0,0)';
      BIDIRECTIONAL='TRUE';
      INPUT_LOAD='(-0.01,0.01)';
      OUTPUT_LOAD='(1.0,-1.0)';
      PINUSE='BI';
    'MAA_DATA16':
      PIN_NUMBER='(U74,0,0,0,0,0,0,0,0,0,0,0,0,0,0,0,0,0,0,0,0,0,0,0,0,0,0,0,0,0~
,0,0,0,0,0,0,0,0,0,0)';
      BIDIRECTIONAL='TRUE';
      INPUT_LOAD='(-0.01,0.01)';
      OUTPUT_LOAD='(1.0,-1.0)';
      PINUSE='BI';
    'MAA_CHECK7':
      PIN_NUMBER='(AR73,0,0,0,0,0,0,0,0,0,0,0,0,0,0,0,0,0,0,0,0,0,0,0,0,0,0,0,0,~
0,0,0,0,0,0,0,0,0,0,0)';
      BIDIRECTIONAL='TRUE';
      INPUT_LOAD='(-0.01,0.01)';
      OUTPUT_LOAD='(1.0,-1.0)';
      PINUSE='BI';
    'MAA_CA0':
      PIN_NUMBER='(AW74,0,0,0,0,0,0,0,0,0,0,0,0,0,0,0,0,0,0,0,0,0,0,0,0,0,0,0,0,~
0,0,0,0,0,0,0,0,0,0,0)';
      OUTPUT_LOAD='(1.0,-1.0)';
      PINUSE='OUT';
    'MAA1_RSP_L':
      PIN_NUMBER='(BP72,0,0,0,0,0,0,0,0,0,0,0,0,0,0,0,0,0,0,0,0,0,0,0,0,0,0,0,0,~
0,0,0,0,0,0,0,0,0,0,0)';
      INPUT_LOAD='(-0.01,0.01)';
      PINUSE='IN';
    'MAB_DATA22':
      PIN_NUMBER='(CW74,0,0,0,0,0,0,0,0,0,0,0,0,0,0,0,0,0,0,0,0,0,0,0,0,0,0,0,0,~
0,0,0,0,0,0,0,0,0,0,0)';
      BIDIRECTIONAL='TRUE';
      INPUT_LOAD='(-0.01,0.01)';
      OUTPUT_LOAD='(1.0,-1.0)';
      PINUSE='BI';
    'MAB_DATA11':
      PIN_NUMBER='(CK72,0,0,0,0,0,0,0,0,0,0,0,0,0,0,0,0,0,0,0,0,0,0,0,0,0,0,0,0,~
0,0,0,0,0,0,0,0,0,0,0)';
      BIDIRECTIONAL='TRUE';
      INPUT_LOAD='(-0.01,0.01)';
      OUTPUT_LOAD='(1.0,-1.0)';
      PINUSE='BI';
    'MAB_CHECK2':
      PIN_NUMBER='(CA74,0,0,0,0,0,0,0,0,0,0,0,0,0,0,0,0,0,0,0,0,0,0,0,0,0,0,0,0,~
0,0,0,0,0,0,0,0,0,0,0)';
      BIDIRECTIONAL='TRUE';
      INPUT_LOAD='(-0.01,0.01)';
      OUTPUT_LOAD='(1.0,-1.0)';
      PINUSE='BI';
    'MAB_CA0':
      PIN_NUMBER='(BG73,0,0,0,0,0,0,0,0,0,0,0,0,0,0,0,0,0,0,0,0,0,0,0,0,0,0,0,0,~
0,0,0,0,0,0,0,0,0,0,0)';
      OUTPUT_LOAD='(1.0,-1.0)';
      PINUSE='OUT';
    'MAA_DQS_L4':
      PIN_NUMBER='(AM74,0,0,0,0,0,0,0,0,0,0,0,0,0,0,0,0,0,0,0,0,0,0,0,0,0,0,0,0,~
0,0,0,0,0,0,0,0,0,0,0)';
      BIDIRECTIONAL='TRUE';
      INPUT_LOAD='(-0.01,0.01)';
      OUTPUT_LOAD='(1.0,-1.0)';
      PINUSE='BI';
    'MAA_DQS_H0':
      PIN_NUMBER='(G74,0,0,0,0,0,0,0,0,0,0,0,0,0,0,0,0,0,0,0,0,0,0,0,0,0,0,0,0,0~
,0,0,0,0,0,0,0,0,0,0)';
      BIDIRECTIONAL='TRUE';
      INPUT_LOAD='(-0.01,0.01)';
      OUTPUT_LOAD='(1.0,-1.0)';
      PINUSE='BI';
    'MAA_DATA28':
      PIN_NUMBER='(AG74,0,0,0,0,0,0,0,0,0,0,0,0,0,0,0,0,0,0,0,0,0,0,0,0,0,0,0,0,~
0,0,0,0,0,0,0,0,0,0,0)';
      BIDIRECTIONAL='TRUE';
      INPUT_LOAD='(-0.01,0.01)';
      OUTPUT_LOAD='(1.0,-1.0)';
      PINUSE='BI';
    'MAA_DATA17':
      PIN_NUMBER='(V72,0,0,0,0,0,0,0,0,0,0,0,0,0,0,0,0,0,0,0,0,0,0,0,0,0,0,0,0,0~
,0,0,0,0,0,0,0,0,0,0)';
      BIDIRECTIONAL='TRUE';
      INPUT_LOAD='(-0.01,0.01)';
      OUTPUT_LOAD='(1.0,-1.0)';
      PINUSE='BI';
    'MAA_CA1':
      PIN_NUMBER='(AY74,0,0,0,0,0,0,0,0,0,0,0,0,0,0,0,0,0,0,0,0,0,0,0,0,0,0,0,0,~
0,0,0,0,0,0,0,0,0,0,0)';
      OUTPUT_LOAD='(1.0,-1.0)';
      PINUSE='OUT';
    'MAB_DATA23':
      PIN_NUMBER='(CY72,0,0,0,0,0,0,0,0,0,0,0,0,0,0,0,0,0,0,0,0,0,0,0,0,0,0,0,0,~
0,0,0,0,0,0,0,0,0,0,0)';
      BIDIRECTIONAL='TRUE';
      INPUT_LOAD='(-0.01,0.01)';
      OUTPUT_LOAD='(1.0,-1.0)';
      PINUSE='BI';
    'MAB_DATA12':
      PIN_NUMBER='(CM74,0,0,0,0,0,0,0,0,0,0,0,0,0,0,0,0,0,0,0,0,0,0,0,0,0,0,0,0,~
0,0,0,0,0,0,0,0,0,0,0)';
      BIDIRECTIONAL='TRUE';
      INPUT_LOAD='(-0.01,0.01)';
      OUTPUT_LOAD='(1.0,-1.0)';
      PINUSE='BI';
    'MAB_CHECK3':
      PIN_NUMBER='(CB72,0,0,0,0,0,0,0,0,0,0,0,0,0,0,0,0,0,0,0,0,0,0,0,0,0,0,0,0,~
0,0,0,0,0,0,0,0,0,0,0)';
      BIDIRECTIONAL='TRUE';
      INPUT_LOAD='(-0.01,0.01)';
      OUTPUT_LOAD='(1.0,-1.0)';
      PINUSE='BI';
    'MAB_CA1':
      PIN_NUMBER='(BH72,0,0,0,0,0,0,0,0,0,0,0,0,0,0,0,0,0,0,0,0,0,0,0,0,0,0,0,0,~
0,0,0,0,0,0,0,0,0,0,0)';
      OUTPUT_LOAD='(1.0,-1.0)';
      PINUSE='OUT';
    'MAA_DQS_L5':
      PIN_NUMBER='(H72,0,0,0,0,0,0,0,0,0,0,0,0,0,0,0,0,0,0,0,0,0,0,0,0,0,0,0,0,0~
,0,0,0,0,0,0,0,0,0,0)';
      BIDIRECTIONAL='TRUE';
      INPUT_LOAD='(-0.01,0.01)';
      OUTPUT_LOAD='(1.0,-1.0)';
      PINUSE='BI';
    'MAA_DQS_H1':
      PIN_NUMBER='(N74,0,0,0,0,0,0,0,0,0,0,0,0,0,0,0,0,0,0,0,0,0,0,0,0,0,0,0,0,0~
,0,0,0,0,0,0,0,0,0,0)';
      BIDIRECTIONAL='TRUE';
      INPUT_LOAD='(-0.01,0.01)';
      OUTPUT_LOAD='(1.0,-1.0)';
      PINUSE='BI';
    'MAA_DATA29':
      PIN_NUMBER='(AH72,0,0,0,0,0,0,0,0,0,0,0,0,0,0,0,0,0,0,0,0,0,0,0,0,0,0,0,0,~
0,0,0,0,0,0,0,0,0,0,0)';
      BIDIRECTIONAL='TRUE';
      INPUT_LOAD='(-0.01,0.01)';
      OUTPUT_LOAD='(1.0,-1.0)';
      PINUSE='BI';
    'MAA_DATA18':
      PIN_NUMBER='(V74,0,0,0,0,0,0,0,0,0,0,0,0,0,0,0,0,0,0,0,0,0,0,0,0,0,0,0,0,0~
,0,0,0,0,0,0,0,0,0,0)';
      BIDIRECTIONAL='TRUE';
      INPUT_LOAD='(-0.01,0.01)';
      OUTPUT_LOAD='(1.0,-1.0)';
      PINUSE='BI';
    'MAA_CA2':
      PIN_NUMBER='(AY72,0,0,0,0,0,0,0,0,0,0,0,0,0,0,0,0,0,0,0,0,0,0,0,0,0,0,0,0,~
0,0,0,0,0,0,0,0,0,0,0)';
      OUTPUT_LOAD='(1.0,-1.0)';
      PINUSE='OUT';
    'MAB_DQS_L0':
      PIN_NUMBER='(CE74,0,0,0,0,0,0,0,0,0,0,0,0,0,0,0,0,0,0,0,0,0,0,0,0,0,0,0,0,~
0,0,0,0,0,0,0,0,0,0,0)';
      BIDIRECTIONAL='TRUE';
      INPUT_LOAD='(-0.01,0.01)';
      OUTPUT_LOAD='(1.0,-1.0)';
      PINUSE='BI';
    'MAB_DATA24':
      PIN_NUMBER='(CY74,0,0,0,0,0,0,0,0,0,0,0,0,0,0,0,0,0,0,0,0,0,0,0,0,0,0,0,0,~
0,0,0,0,0,0,0,0,0,0,0)';
      BIDIRECTIONAL='TRUE';
      INPUT_LOAD='(-0.01,0.01)';
      OUTPUT_LOAD='(1.0,-1.0)';
      PINUSE='BI';
    'MAB_DATA13':
      PIN_NUMBER='(CN73,0,0,0,0,0,0,0,0,0,0,0,0,0,0,0,0,0,0,0,0,0,0,0,0,0,0,0,0,~
0,0,0,0,0,0,0,0,0,0,0)';
      BIDIRECTIONAL='TRUE';
      INPUT_LOAD='(-0.01,0.01)';
      OUTPUT_LOAD='(1.0,-1.0)';
      PINUSE='BI';
    'MAB_CHECK4':
      PIN_NUMBER='(BT74,0,0,0,0,0,0,0,0,0,0,0,0,0,0,0,0,0,0,0,0,0,0,0,0,0,0,0,0,~
0,0,0,0,0,0,0,0,0,0,0)';
      BIDIRECTIONAL='TRUE';
      INPUT_LOAD='(-0.01,0.01)';
      OUTPUT_LOAD='(1.0,-1.0)';
      PINUSE='BI';
    'MAB_CA2':
      PIN_NUMBER='(BH74,0,0,0,0,0,0,0,0,0,0,0,0,0,0,0,0,0,0,0,0,0,0,0,0,0,0,0,0,~
0,0,0,0,0,0,0,0,0,0,0)';
      OUTPUT_LOAD='(1.0,-1.0)';
      PINUSE='OUT';
    'MAA_DQS_L6':
      PIN_NUMBER='(P72,0,0,0,0,0,0,0,0,0,0,0,0,0,0,0,0,0,0,0,0,0,0,0,0,0,0,0,0,0~
,0,0,0,0,0,0,0,0,0,0)';
      BIDIRECTIONAL='TRUE';
      INPUT_LOAD='(-0.01,0.01)';
      OUTPUT_LOAD='(1.0,-1.0)';
      PINUSE='BI';
    'MAA_DQS_H2':
      PIN_NUMBER='(W74,0,0,0,0,0,0,0,0,0,0,0,0,0,0,0,0,0,0,0,0,0,0,0,0,0,0,0,0,0~
,0,0,0,0,0,0,0,0,0,0)';
      BIDIRECTIONAL='TRUE';
      INPUT_LOAD='(-0.01,0.01)';
      OUTPUT_LOAD='(1.0,-1.0)';
      PINUSE='BI';
    'MAA_DATA19':
      PIN_NUMBER='(W73,0,0,0,0,0,0,0,0,0,0,0,0,0,0,0,0,0,0,0,0,0,0,0,0,0,0,0,0,0~
,0,0,0,0,0,0,0,0,0,0)';
      BIDIRECTIONAL='TRUE';
      INPUT_LOAD='(-0.01,0.01)';
      OUTPUT_LOAD='(1.0,-1.0)';
      PINUSE='BI';
    'MAA_CA3':
      PIN_NUMBER='(BA73,0,0,0,0,0,0,0,0,0,0,0,0,0,0,0,0,0,0,0,0,0,0,0,0,0,0,0,0,~
0,0,0,0,0,0,0,0,0,0,0)';
      OUTPUT_LOAD='(1.0,-1.0)';
      PINUSE='OUT';
    'MAB_DQS_L1':
      PIN_NUMBER='(CL74,0,0,0,0,0,0,0,0,0,0,0,0,0,0,0,0,0,0,0,0,0,0,0,0,0,0,0,0,~
0,0,0,0,0,0,0,0,0,0,0)';
      BIDIRECTIONAL='TRUE';
      INPUT_LOAD='(-0.01,0.01)';
      OUTPUT_LOAD='(1.0,-1.0)';
      PINUSE='BI';
    'MAB_DATA25':
      PIN_NUMBER='(DA73,0,0,0,0,0,0,0,0,0,0,0,0,0,0,0,0,0,0,0,0,0,0,0,0,0,0,0,0,~
0,0,0,0,0,0,0,0,0,0,0)';
      BIDIRECTIONAL='TRUE';
      INPUT_LOAD='(-0.01,0.01)';
      OUTPUT_LOAD='(1.0,-1.0)';
      PINUSE='BI';
    'MAB_DATA14':
      PIN_NUMBER='(CN74,0,0,0,0,0,0,0,0,0,0,0,0,0,0,0,0,0,0,0,0,0,0,0,0,0,0,0,0,~
0,0,0,0,0,0,0,0,0,0,0)';
      BIDIRECTIONAL='TRUE';
      INPUT_LOAD='(-0.01,0.01)';
      OUTPUT_LOAD='(1.0,-1.0)';
      PINUSE='BI';
    'MAB_CHECK5':
      PIN_NUMBER='(BU73,0,0,0,0,0,0,0,0,0,0,0,0,0,0,0,0,0,0,0,0,0,0,0,0,0,0,0,0,~
0,0,0,0,0,0,0,0,0,0,0)';
      BIDIRECTIONAL='TRUE';
      INPUT_LOAD='(-0.01,0.01)';
      OUTPUT_LOAD='(1.0,-1.0)';
      PINUSE='BI';
    'MAB_CA3':
      PIN_NUMBER='(BJ74,0,0,0,0,0,0,0,0,0,0,0,0,0,0,0,0,0,0,0,0,0,0,0,0,0,0,0,0,~
0,0,0,0,0,0,0,0,0,0,0)';
      OUTPUT_LOAD='(1.0,-1.0)';
      PINUSE='OUT';
    'MAA_DQS_L7':
      PIN_NUMBER='(Y72,0,0,0,0,0,0,0,0,0,0,0,0,0,0,0,0,0,0,0,0,0,0,0,0,0,0,0,0,0~
,0,0,0,0,0,0,0,0,0,0)';
      BIDIRECTIONAL='TRUE';
      INPUT_LOAD='(-0.01,0.01)';
      OUTPUT_LOAD='(1.0,-1.0)';
      PINUSE='BI';
    'MAA_DQS_H3':
      PIN_NUMBER='(AE74,0,0,0,0,0,0,0,0,0,0,0,0,0,0,0,0,0,0,0,0,0,0,0,0,0,0,0,0,~
0,0,0,0,0,0,0,0,0,0,0)';
      BIDIRECTIONAL='TRUE';
      INPUT_LOAD='(-0.01,0.01)';
      OUTPUT_LOAD='(1.0,-1.0)';
      PINUSE='BI';
    'MAA_DATA0':
      PIN_NUMBER='(E74,0,0,0,0,0,0,0,0,0,0,0,0,0,0,0,0,0,0,0,0,0,0,0,0,0,0,0,0,0~
,0,0,0,0,0,0,0,0,0,0)';
      BIDIRECTIONAL='TRUE';
      INPUT_LOAD='(-0.01,0.01)';
      OUTPUT_LOAD='(1.0,-1.0)';
      PINUSE='BI';
    'MAA_CA4':
      PIN_NUMBER='(BA74,0,0,0,0,0,0,0,0,0,0,0,0,0,0,0,0,0,0,0,0,0,0,0,0,0,0,0,0,~
0,0,0,0,0,0,0,0,0,0,0)';
      OUTPUT_LOAD='(1.0,-1.0)';
      PINUSE='OUT';
    'MAB_DQS_L2':
      PIN_NUMBER='(CU74,0,0,0,0,0,0,0,0,0,0,0,0,0,0,0,0,0,0,0,0,0,0,0,0,0,0,0,0,~
0,0,0,0,0,0,0,0,0,0,0)';
      BIDIRECTIONAL='TRUE';
      INPUT_LOAD='(-0.01,0.01)';
      OUTPUT_LOAD='(1.0,-1.0)';
      PINUSE='BI';
    'MAB_DATA26':
      PIN_NUMBER='(DA74,0,0,0,0,0,0,0,0,0,0,0,0,0,0,0,0,0,0,0,0,0,0,0,0,0,0,0,0,~
0,0,0,0,0,0,0,0,0,0,0)';
      BIDIRECTIONAL='TRUE';
      INPUT_LOAD='(-0.01,0.01)';
      OUTPUT_LOAD='(1.0,-1.0)';
      PINUSE='BI';
    'MAB_DATA15':
      PIN_NUMBER='(CP72,0,0,0,0,0,0,0,0,0,0,0,0,0,0,0,0,0,0,0,0,0,0,0,0,0,0,0,0,~
0,0,0,0,0,0,0,0,0,0,0)';
      BIDIRECTIONAL='TRUE';
      INPUT_LOAD='(-0.01,0.01)';
      OUTPUT_LOAD='(1.0,-1.0)';
      PINUSE='BI';
    'MAB_DATA0':
      PIN_NUMBER='(CB74,0,0,0,0,0,0,0,0,0,0,0,0,0,0,0,0,0,0,0,0,0,0,0,0,0,0,0,0,~
0,0,0,0,0,0,0,0,0,0,0)';
      BIDIRECTIONAL='TRUE';
      INPUT_LOAD='(-0.01,0.01)';
      OUTPUT_LOAD='(1.0,-1.0)';
      PINUSE='BI';
    'MAB_CHECK6':
      PIN_NUMBER='(BU74,0,0,0,0,0,0,0,0,0,0,0,0,0,0,0,0,0,0,0,0,0,0,0,0,0,0,0,0,~
0,0,0,0,0,0,0,0,0,0,0)';
      BIDIRECTIONAL='TRUE';
      INPUT_LOAD='(-0.01,0.01)';
      OUTPUT_LOAD='(1.0,-1.0)';
      PINUSE='BI';
    'MAB_CA4':
      PIN_NUMBER='(BJ73,0,0,0,0,0,0,0,0,0,0,0,0,0,0,0,0,0,0,0,0,0,0,0,0,0,0,0,0,~
0,0,0,0,0,0,0,0,0,0,0)';
      OUTPUT_LOAD='(1.0,-1.0)';
      PINUSE='OUT';
    'MAB0_RSP_L':
      PIN_NUMBER='(BP74,0,0,0,0,0,0,0,0,0,0,0,0,0,0,0,0,0,0,0,0,0,0,0,0,0,0,0,0,~
0,0,0,0,0,0,0,0,0,0,0)';
      INPUT_LOAD='(-0.01,0.01)';
      PINUSE='IN';
    'MAA_DQS_L8':
      PIN_NUMBER='(AF72,0,0,0,0,0,0,0,0,0,0,0,0,0,0,0,0,0,0,0,0,0,0,0,0,0,0,0,0,~
0,0,0,0,0,0,0,0,0,0,0)';
      BIDIRECTIONAL='TRUE';
      INPUT_LOAD='(-0.01,0.01)';
      OUTPUT_LOAD='(1.0,-1.0)';
      PINUSE='BI';
    'MAA_DQS_H4':
      PIN_NUMBER='(AL74,0,0,0,0,0,0,0,0,0,0,0,0,0,0,0,0,0,0,0,0,0,0,0,0,0,0,0,0,~
0,0,0,0,0,0,0,0,0,0,0)';
      BIDIRECTIONAL='TRUE';
      INPUT_LOAD='(-0.01,0.01)';
      OUTPUT_LOAD='(1.0,-1.0)';
      PINUSE='BI';
    'MAA_DATA1':
      PIN_NUMBER='(F72,0,0,0,0,0,0,0,0,0,0,0,0,0,0,0,0,0,0,0,0,0,0,0,0,0,0,0,0,0~
,0,0,0,0,0,0,0,0,0,0)';
      BIDIRECTIONAL='TRUE';
      INPUT_LOAD='(-0.01,0.01)';
      OUTPUT_LOAD='(1.0,-1.0)';
      PINUSE='BI';
    'MAA_CA5':
      PIN_NUMBER='(BB74,0,0,0,0,0,0,0,0,0,0,0,0,0,0,0,0,0,0,0,0,0,0,0,0,0,0,0,0,~
0,0,0,0,0,0,0,0,0,0,0)';
      OUTPUT_LOAD='(1.0,-1.0)';
      PINUSE='OUT';
    'MAB_DQS_L3':
      PIN_NUMBER='(DC74,0,0,0,0,0,0,0,0,0,0,0,0,0,0,0,0,0,0,0,0,0,0,0,0,0,0,0,0,~
0,0,0,0,0,0,0,0,0,0,0)';
      BIDIRECTIONAL='TRUE';
      INPUT_LOAD='(-0.01,0.01)';
      OUTPUT_LOAD='(1.0,-1.0)';
      PINUSE='BI';
    'MAB_DATA27':
      PIN_NUMBER='(DB72,0,0,0,0,0,0,0,0,0,0,0,0,0,0,0,0,0,0,0,0,0,0,0,0,0,0,0,0,~
0,0,0,0,0,0,0,0,0,0,0)';
      BIDIRECTIONAL='TRUE';
      INPUT_LOAD='(-0.01,0.01)';
      OUTPUT_LOAD='(1.0,-1.0)';
      PINUSE='BI';
    'MAB_DATA16':
      PIN_NUMBER='(CP74,0,0,0,0,0,0,0,0,0,0,0,0,0,0,0,0,0,0,0,0,0,0,0,0,0,0,0,0,~
0,0,0,0,0,0,0,0,0,0,0)';
      BIDIRECTIONAL='TRUE';
      INPUT_LOAD='(-0.01,0.01)';
      OUTPUT_LOAD='(1.0,-1.0)';
      PINUSE='BI';
    'MAB_DATA1':
      PIN_NUMBER='(CC73,0,0,0,0,0,0,0,0,0,0,0,0,0,0,0,0,0,0,0,0,0,0,0,0,0,0,0,0,~
0,0,0,0,0,0,0,0,0,0,0)';
      BIDIRECTIONAL='TRUE';
      INPUT_LOAD='(-0.01,0.01)';
      OUTPUT_LOAD='(1.0,-1.0)';
      PINUSE='BI';
    'MAB_CHECK7':
      PIN_NUMBER='(BV72,0,0,0,0,0,0,0,0,0,0,0,0,0,0,0,0,0,0,0,0,0,0,0,0,0,0,0,0,~
0,0,0,0,0,0,0,0,0,0,0)';
      BIDIRECTIONAL='TRUE';
      INPUT_LOAD='(-0.01,0.01)';
      OUTPUT_LOAD='(1.0,-1.0)';
      PINUSE='BI';
    'MAB_CA5':
      PIN_NUMBER='(BK72,0,0,0,0,0,0,0,0,0,0,0,0,0,0,0,0,0,0,0,0,0,0,0,0,0,0,0,0,~
0,0,0,0,0,0,0,0,0,0,0)';
      OUTPUT_LOAD='(1.0,-1.0)';
      PINUSE='OUT';
    'MAB1_RSP_L':
      PIN_NUMBER='(BR74,0,0,0,0,0,0,0,0,0,0,0,0,0,0,0,0,0,0,0,0,0,0,0,0,0,0,0,0,~
0,0,0,0,0,0,0,0,0,0,0)';
      INPUT_LOAD='(-0.01,0.01)';
      PINUSE='IN';
    'MAA_DQS_L9':
      PIN_NUMBER='(AM72,0,0,0,0,0,0,0,0,0,0,0,0,0,0,0,0,0,0,0,0,0,0,0,0,0,0,0,0,~
0,0,0,0,0,0,0,0,0,0,0)';
      BIDIRECTIONAL='TRUE';
      INPUT_LOAD='(-0.01,0.01)';
      OUTPUT_LOAD='(1.0,-1.0)';
      PINUSE='BI';
    'MAA_DQS_H5':
      PIN_NUMBER='(J73,0,0,0,0,0,0,0,0,0,0,0,0,0,0,0,0,0,0,0,0,0,0,0,0,0,0,0,0,0~
,0,0,0,0,0,0,0,0,0,0)';
      BIDIRECTIONAL='TRUE';
      INPUT_LOAD='(-0.01,0.01)';
      OUTPUT_LOAD='(1.0,-1.0)';
      PINUSE='BI';
    'MAA_DATA2':
      PIN_NUMBER='(F74,0,0,0,0,0,0,0,0,0,0,0,0,0,0,0,0,0,0,0,0,0,0,0,0,0,0,0,0,0~
,0,0,0,0,0,0,0,0,0,0)';
      BIDIRECTIONAL='TRUE';
      INPUT_LOAD='(-0.01,0.01)';
      OUTPUT_LOAD='(1.0,-1.0)';
      PINUSE='BI';
    'MAA_CA6':
      PIN_NUMBER='(BB72,0,0,0,0,0,0,0,0,0,0,0,0,0,0,0,0,0,0,0,0,0,0,0,0,0,0,0,0,~
0,0,0,0,0,0,0,0,0,0,0)';
      OUTPUT_LOAD='(1.0,-1.0)';
      PINUSE='OUT';
    'MAB_DQS_L4':
      PIN_NUMBER='(BW73,0,0,0,0,0,0,0,0,0,0,0,0,0,0,0,0,0,0,0,0,0,0,0,0,0,0,0,0,~
0,0,0,0,0,0,0,0,0,0,0)';
      BIDIRECTIONAL='TRUE';
      INPUT_LOAD='(-0.01,0.01)';
      OUTPUT_LOAD='(1.0,-1.0)';
      PINUSE='BI';
    'MAB_DQS_H0':
      PIN_NUMBER='(CD74,0,0,0,0,0,0,0,0,0,0,0,0,0,0,0,0,0,0,0,0,0,0,0,0,0,0,0,0,~
0,0,0,0,0,0,0,0,0,0,0)';
      BIDIRECTIONAL='TRUE';
      INPUT_LOAD='(-0.01,0.01)';
      OUTPUT_LOAD='(1.0,-1.0)';
      PINUSE='BI';
    'MAB_DATA28':
      PIN_NUMBER='(DD74,0,0,0,0,0,0,0,0,0,0,0,0,0,0,0,0,0,0,0,0,0,0,0,0,0,0,0,0,~
0,0,0,0,0,0,0,0,0,0,0)';
      BIDIRECTIONAL='TRUE';
      INPUT_LOAD='(-0.01,0.01)';
      OUTPUT_LOAD='(1.0,-1.0)';
      PINUSE='BI';
    'MAB_DATA17':
      PIN_NUMBER='(CR73,0,0,0,0,0,0,0,0,0,0,0,0,0,0,0,0,0,0,0,0,0,0,0,0,0,0,0,0,~
0,0,0,0,0,0,0,0,0,0,0)';
      BIDIRECTIONAL='TRUE';
      INPUT_LOAD='(-0.01,0.01)';
      OUTPUT_LOAD='(1.0,-1.0)';
      PINUSE='BI';
    'MAB_DATA2':
      PIN_NUMBER='(CC74,0,0,0,0,0,0,0,0,0,0,0,0,0,0,0,0,0,0,0,0,0,0,0,0,0,0,0,0,~
0,0,0,0,0,0,0,0,0,0,0)';
      BIDIRECTIONAL='TRUE';
      INPUT_LOAD='(-0.01,0.01)';
      OUTPUT_LOAD='(1.0,-1.0)';
      PINUSE='BI';
    'MAB_CA6':
      PIN_NUMBER='(BK74,0,0,0,0,0,0,0,0,0,0,0,0,0,0,0,0,0,0,0,0,0,0,0,0,0,0,0,0,~
0,0,0,0,0,0,0,0,0,0,0)';
      OUTPUT_LOAD='(1.0,-1.0)';
      PINUSE='OUT';
    'MAA_DQS_H6':
      PIN_NUMBER='(R73,0,0,0,0,0,0,0,0,0,0,0,0,0,0,0,0,0,0,0,0,0,0,0,0,0,0,0,0,0~
,0,0,0,0,0,0,0,0,0,0)';
      BIDIRECTIONAL='TRUE';
      INPUT_LOAD='(-0.01,0.01)';
      OUTPUT_LOAD='(1.0,-1.0)';
      PINUSE='BI';
    'MAA_DATA3':
      PIN_NUMBER='(G73,0,0,0,0,0,0,0,0,0,0,0,0,0,0,0,0,0,0,0,0,0,0,0,0,0,0,0,0,0~
,0,0,0,0,0,0,0,0,0,0)';
      BIDIRECTIONAL='TRUE';
      INPUT_LOAD='(-0.01,0.01)';
      OUTPUT_LOAD='(1.0,-1.0)';
      PINUSE='BI';
    'MAA0_CS_L0':
      PIN_NUMBER='(AV74,0,0,0,0,0,0,0,0,0,0,0,0,0,0,0,0,0,0,0,0,0,0,0,0,0,0,0,0,~
0,0,0,0,0,0,0,0,0,0,0)';
      OUTPUT_LOAD='(1.0,-1.0)';
      PINUSE='OUT';
    'MAA_PAR':
      PIN_NUMBER='(BC73,0,0,0,0,0,0,0,0,0,0,0,0,0,0,0,0,0,0,0,0,0,0,0,0,0,0,0,0,~
0,0,0,0,0,0,0,0,0,0,0)';
      OUTPUT_LOAD='(1.0,-1.0)';
      PINUSE='OUT';
    'MAB_PAR':
      PIN_NUMBER='(BL74,0,0,0,0,0,0,0,0,0,0,0,0,0,0,0,0,0,0,0,0,0,0,0,0,0,0,0,0,~
0,0,0,0,0,0,0,0,0,0,0)';
      OUTPUT_LOAD='(1.0,-1.0)';
      PINUSE='OUT';
    'MA0_CLK_H':
      PIN_NUMBER='(BC74,0,0,0,0,0,0,0,0,0,0,0,0,0,0,0,0,0,0,0,0,0,0,0,0,0,0,0,0,~
0,0,0,0,0,0,0,0,0,0,0)';
      OUTPUT_LOAD='(1.0,-1.0)';
      PINUSE='OUT';
    'MAB_DQS_H9':
      PIN_NUMBER='(BV74,0,0,0,0,0,0,0,0,0,0,0,0,0,0,0,0,0,0,0,0,0,0,0,0,0,0,0,0,~
0,0,0,0,0,0,0,0,0,0,0)';
      BIDIRECTIONAL='TRUE';
      INPUT_LOAD='(-0.01,0.01)';
      OUTPUT_LOAD='(1.0,-1.0)';
      PINUSE='BI';
    'MA1_CLK_H':
      PIN_NUMBER='(BF74,0,0,0,0,0,0,0,0,0,0,0,0,0,0,0,0,0,0,0,0,0,0,0,0,0,0,0,0,~
0,0,0,0,0,0,0,0,0,0,0)';
      OUTPUT_LOAD='(1.0,-1.0)';
      PINUSE='OUT';
    'MA0_CLK_L':
      PIN_NUMBER='(BD74,0,0,0,0,0,0,0,0,0,0,0,0,0,0,0,0,0,0,0,0,0,0,0,0,0,0,0,0,~
0,0,0,0,0,0,0,0,0,0,0)';
      OUTPUT_LOAD='(1.0,-1.0)';
      PINUSE='OUT';
    'MA1_CLK_L':
      PIN_NUMBER='(BG74,0,0,0,0,0,0,0,0,0,0,0,0,0,0,0,0,0,0,0,0,0,0,0,0,0,0,0,0,~
0,0,0,0,0,0,0,0,0,0,0)';
      OUTPUT_LOAD='(1.0,-1.0)';
      PINUSE='OUT';
    'TEST39A':
      PIN_NUMBER='(BF72,0,0,0,0,0,0,0,0,0,0,0,0,0,0,0,0,0,0,0,0,0,0,0,0,0,0,0,0,~
0,0,0,0,0,0,0,0,0,0,0)';
      OUTPUT_LOAD='(1.0,-1.0)';
      PINUSE='OUT';
    'TEST40':
      PIN_NUMBER='(C60,0,0,0,0,0,0,0,0,0,0,0,0,0,0,0,0,0,0,0,0,0,0,0,0,0,0,0,0,0~
,0,0,0,0,0,0,0,0,0,0)';
      OUTPUT_LOAD='(1.0,-1.0)';
      PINUSE='OUT';
    'MB_ALERT_L':
      PIN_NUMBER='(0,AT62,0,0,0,0,0,0,0,0,0,0,0,0,0,0,0,0,0,0,0,0,0,0,0,0,0,0,0,~
0,0,0,0,0,0,0,0,0,0,0)';
      INPUT_LOAD='(-0.01,0.01)';
      PINUSE='IN';
    'MB_RESET_L':
      PIN_NUMBER='(0,AU62,0,0,0,0,0,0,0,0,0,0,0,0,0,0,0,0,0,0,0,0,0,0,0,0,0,0,0,~
0,0,0,0,0,0,0,0,0,0,0)';
      OUTPUT_LOAD='(1.0,-1.0)';
      PINUSE='OUT';
    'MBB_DQS_L9':
      PIN_NUMBER='(0,BW64,0,0,0,0,0,0,0,0,0,0,0,0,0,0,0,0,0,0,0,0,0,0,0,0,0,0,0,~
0,0,0,0,0,0,0,0,0,0,0)';
      BIDIRECTIONAL='TRUE';
      INPUT_LOAD='(-0.01,0.01)';
      OUTPUT_LOAD='(1.0,-1.0)';
      PINUSE='BI';
    'MBB_DQS_H5':
      PIN_NUMBER='(0,CF62,0,0,0,0,0,0,0,0,0,0,0,0,0,0,0,0,0,0,0,0,0,0,0,0,0,0,0,~
0,0,0,0,0,0,0,0,0,0,0)';
      BIDIRECTIONAL='TRUE';
      INPUT_LOAD='(-0.01,0.01)';
      OUTPUT_LOAD='(1.0,-1.0)';
      PINUSE='BI';
    'MBA_DATA22':
      PIN_NUMBER='(0,AB63,0,0,0,0,0,0,0,0,0,0,0,0,0,0,0,0,0,0,0,0,0,0,0,0,0,0,0,~
0,0,0,0,0,0,0,0,0,0,0)';
      BIDIRECTIONAL='TRUE';
      INPUT_LOAD='(-0.01,0.01)';
      OUTPUT_LOAD='(1.0,-1.0)';
      PINUSE='BI';
    'MBA_DATA11':
      PIN_NUMBER='(0,N62,0,0,0,0,0,0,0,0,0,0,0,0,0,0,0,0,0,0,0,0,0,0,0,0,0,0,0,0~
,0,0,0,0,0,0,0,0,0,0)';
      BIDIRECTIONAL='TRUE';
      INPUT_LOAD='(-0.01,0.01)';
      OUTPUT_LOAD='(1.0,-1.0)';
      PINUSE='BI';
    'MBA_CHECK2':
      PIN_NUMBER='(0,AK63,0,0,0,0,0,0,0,0,0,0,0,0,0,0,0,0,0,0,0,0,0,0,0,0,0,0,0,~
0,0,0,0,0,0,0,0,0,0,0)';
      BIDIRECTIONAL='TRUE';
      INPUT_LOAD='(-0.01,0.01)';
      OUTPUT_LOAD='(1.0,-1.0)';
      PINUSE='BI';
    'MBB_DQS_H6':
      PIN_NUMBER='(0,CM62,0,0,0,0,0,0,0,0,0,0,0,0,0,0,0,0,0,0,0,0,0,0,0,0,0,0,0,~
0,0,0,0,0,0,0,0,0,0,0)';
      BIDIRECTIONAL='TRUE';
      INPUT_LOAD='(-0.01,0.01)';
      OUTPUT_LOAD='(1.0,-1.0)';
      PINUSE='BI';
    'MBA_DATA23':
      PIN_NUMBER='(0,AC62,0,0,0,0,0,0,0,0,0,0,0,0,0,0,0,0,0,0,0,0,0,0,0,0,0,0,0,~
0,0,0,0,0,0,0,0,0,0,0)';
      BIDIRECTIONAL='TRUE';
      INPUT_LOAD='(-0.01,0.01)';
      OUTPUT_LOAD='(1.0,-1.0)';
      PINUSE='BI';
    'MBA_DATA12':
      PIN_NUMBER='(0,R64,0,0,0,0,0,0,0,0,0,0,0,0,0,0,0,0,0,0,0,0,0,0,0,0,0,0,0,0~
,0,0,0,0,0,0,0,0,0,0)';
      BIDIRECTIONAL='TRUE';
      INPUT_LOAD='(-0.01,0.01)';
      OUTPUT_LOAD='(1.0,-1.0)';
      PINUSE='BI';
    'MBA_CHECK3':
      PIN_NUMBER='(0,AL62,0,0,0,0,0,0,0,0,0,0,0,0,0,0,0,0,0,0,0,0,0,0,0,0,0,0,0,~
0,0,0,0,0,0,0,0,0,0,0)';
      BIDIRECTIONAL='TRUE';
      INPUT_LOAD='(-0.01,0.01)';
      OUTPUT_LOAD='(1.0,-1.0)';
      PINUSE='BI';
    'MBB_DQS_H7':
      PIN_NUMBER='(0,CV62,0,0,0,0,0,0,0,0,0,0,0,0,0,0,0,0,0,0,0,0,0,0,0,0,0,0,0,~
0,0,0,0,0,0,0,0,0,0,0)';
      BIDIRECTIONAL='TRUE';
      INPUT_LOAD='(-0.01,0.01)';
      OUTPUT_LOAD='(1.0,-1.0)';
      PINUSE='BI';
    'MBB0_CS_L0':
      PIN_NUMBER='(0,BM62,0,0,0,0,0,0,0,0,0,0,0,0,0,0,0,0,0,0,0,0,0,0,0,0,0,0,0,~
0,0,0,0,0,0,0,0,0,0,0)';
      OUTPUT_LOAD='(1.0,-1.0)';
      PINUSE='OUT';
    'MBA_DQS_L0':
      PIN_NUMBER='(0,H63,0,0,0,0,0,0,0,0,0,0,0,0,0,0,0,0,0,0,0,0,0,0,0,0,0,0,0,0~
,0,0,0,0,0,0,0,0,0,0)';
      BIDIRECTIONAL='TRUE';
      INPUT_LOAD='(-0.01,0.01)';
      OUTPUT_LOAD='(1.0,-1.0)';
      PINUSE='BI';
    'MBA_DATA13':
      PIN_NUMBER='(0,T62,0,0,0,0,0,0,0,0,0,0,0,0,0,0,0,0,0,0,0,0,0,0,0,0,0,0,0,0~
,0,0,0,0,0,0,0,0,0,0)';
      BIDIRECTIONAL='TRUE';
      INPUT_LOAD='(-0.01,0.01)';
      OUTPUT_LOAD='(1.0,-1.0)';
      PINUSE='BI';
    'MBA_DATA0':
      PIN_NUMBER='(0,E64,0,0,0,0,0,0,0,0,0,0,0,0,0,0,0,0,0,0,0,0,0,0,0,0,0,0,0,0~
,0,0,0,0,0,0,0,0,0,0)';
      BIDIRECTIONAL='TRUE';
      INPUT_LOAD='(-0.01,0.01)';
      OUTPUT_LOAD='(1.0,-1.0)';
      PINUSE='BI';
    'MBA_CHECK4':
      PIN_NUMBER='(0,AN64,0,0,0,0,0,0,0,0,0,0,0,0,0,0,0,0,0,0,0,0,0,0,0,0,0,0,0,~
0,0,0,0,0,0,0,0,0,0,0)';
      BIDIRECTIONAL='TRUE';
      INPUT_LOAD='(-0.01,0.01)';
      OUTPUT_LOAD='(1.0,-1.0)';
      PINUSE='BI';
    'MBB_DQS_H8':
      PIN_NUMBER='(0,DD62,0,0,0,0,0,0,0,0,0,0,0,0,0,0,0,0,0,0,0,0,0,0,0,0,0,0,0,~
0,0,0,0,0,0,0,0,0,0,0)';
      BIDIRECTIONAL='TRUE';
      INPUT_LOAD='(-0.01,0.01)';
      OUTPUT_LOAD='(1.0,-1.0)';
      PINUSE='BI';
    'MBB_DATA30':
      PIN_NUMBER='(0,DE64,0,0,0,0,0,0,0,0,0,0,0,0,0,0,0,0,0,0,0,0,0,0,0,0,0,0,0,~
0,0,0,0,0,0,0,0,0,0,0)';
      BIDIRECTIONAL='TRUE';
      INPUT_LOAD='(-0.01,0.01)';
      OUTPUT_LOAD='(1.0,-1.0)';
      PINUSE='BI';
    'MBB_DATA0':
      PIN_NUMBER='(0,CB63,0,0,0,0,0,0,0,0,0,0,0,0,0,0,0,0,0,0,0,0,0,0,0,0,0,0,0,~
0,0,0,0,0,0,0,0,0,0,0)';
      BIDIRECTIONAL='TRUE';
      INPUT_LOAD='(-0.01,0.01)';
      OUTPUT_LOAD='(1.0,-1.0)';
      PINUSE='BI';
    'MBB1_CS_L0':
      PIN_NUMBER='(0,BL62,0,0,0,0,0,0,0,0,0,0,0,0,0,0,0,0,0,0,0,0,0,0,0,0,0,0,0,~
0,0,0,0,0,0,0,0,0,0,0)';
      OUTPUT_LOAD='(1.0,-1.0)';
      PINUSE='OUT';
    'MBB0_CS_L1':
      PIN_NUMBER='(0,BN64,0,0,0,0,0,0,0,0,0,0,0,0,0,0,0,0,0,0,0,0,0,0,0,0,0,0,0,~
0,0,0,0,0,0,0,0,0,0,0)';
      OUTPUT_LOAD='(1.0,-1.0)';
      PINUSE='OUT';
    'MBA_DQS_L1':
      PIN_NUMBER='(0,P63,0,0,0,0,0,0,0,0,0,0,0,0,0,0,0,0,0,0,0,0,0,0,0,0,0,0,0,0~
,0,0,0,0,0,0,0,0,0,0)';
      BIDIRECTIONAL='TRUE';
      INPUT_LOAD='(-0.01,0.01)';
      OUTPUT_LOAD='(1.0,-1.0)';
      PINUSE='BI';
    'MBA_DATA25':
      PIN_NUMBER='(0,AD62,0,0,0,0,0,0,0,0,0,0,0,0,0,0,0,0,0,0,0,0,0,0,0,0,0,0,0,~
0,0,0,0,0,0,0,0,0,0,0)';
      BIDIRECTIONAL='TRUE';
      INPUT_LOAD='(-0.01,0.01)';
      OUTPUT_LOAD='(1.0,-1.0)';
      PINUSE='BI';
    'MBA_DATA14':
      PIN_NUMBER='(0,T63,0,0,0,0,0,0,0,0,0,0,0,0,0,0,0,0,0,0,0,0,0,0,0,0,0,0,0,0~
,0,0,0,0,0,0,0,0,0,0)';
      BIDIRECTIONAL='TRUE';
      INPUT_LOAD='(-0.01,0.01)';
      OUTPUT_LOAD='(1.0,-1.0)';
      PINUSE='BI';
    'MBA_DATA1':
      PIN_NUMBER='(0,F62,0,0,0,0,0,0,0,0,0,0,0,0,0,0,0,0,0,0,0,0,0,0,0,0,0,0,0,0~
,0,0,0,0,0,0,0,0,0,0)';
      BIDIRECTIONAL='TRUE';
      INPUT_LOAD='(-0.01,0.01)';
      OUTPUT_LOAD='(1.0,-1.0)';
      PINUSE='BI';
    'MBA_CHECK5':
      PIN_NUMBER='(0,AP62,0,0,0,0,0,0,0,0,0,0,0,0,0,0,0,0,0,0,0,0,0,0,0,0,0,0,0,~
0,0,0,0,0,0,0,0,0,0,0)';
      BIDIRECTIONAL='TRUE';
      INPUT_LOAD='(-0.01,0.01)';
      OUTPUT_LOAD='(1.0,-1.0)';
      PINUSE='BI';
    'MBB_DATA31':
      PIN_NUMBER='(0,DF62,0,0,0,0,0,0,0,0,0,0,0,0,0,0,0,0,0,0,0,0,0,0,0,0,0,0,0,~
0,0,0,0,0,0,0,0,0,0,0)';
      BIDIRECTIONAL='TRUE';
      INPUT_LOAD='(-0.01,0.01)';
      OUTPUT_LOAD='(1.0,-1.0)';
      PINUSE='BI';
    'MBB_DATA1':
      PIN_NUMBER='(0,CC62,0,0,0,0,0,0,0,0,0,0,0,0,0,0,0,0,0,0,0,0,0,0,0,0,0,0,0,~
0,0,0,0,0,0,0,0,0,0,0)';
      BIDIRECTIONAL='TRUE';
      INPUT_LOAD='(-0.01,0.01)';
      OUTPUT_LOAD='(1.0,-1.0)';
      PINUSE='BI';
    'MBB_CHECK0':
      PIN_NUMBER='(0,BY63,0,0,0,0,0,0,0,0,0,0,0,0,0,0,0,0,0,0,0,0,0,0,0,0,0,0,0,~
0,0,0,0,0,0,0,0,0,0,0)';
      BIDIRECTIONAL='TRUE';
      INPUT_LOAD='(-0.01,0.01)';
      OUTPUT_LOAD='(1.0,-1.0)';
      PINUSE='BI';
    'MBB1_CS_L1':
      PIN_NUMBER='(0,BM63,0,0,0,0,0,0,0,0,0,0,0,0,0,0,0,0,0,0,0,0,0,0,0,0,0,0,0,~
0,0,0,0,0,0,0,0,0,0,0)';
      OUTPUT_LOAD='(1.0,-1.0)';
      PINUSE='OUT';
    'MBA_DQS_L2':
      PIN_NUMBER='(0,Y63,0,0,0,0,0,0,0,0,0,0,0,0,0,0,0,0,0,0,0,0,0,0,0,0,0,0,0,0~
,0,0,0,0,0,0,0,0,0,0)';
      BIDIRECTIONAL='TRUE';
      INPUT_LOAD='(-0.01,0.01)';
      OUTPUT_LOAD='(1.0,-1.0)';
      PINUSE='BI';
    'MBA_DATA26':
      PIN_NUMBER='(0,AD63,0,0,0,0,0,0,0,0,0,0,0,0,0,0,0,0,0,0,0,0,0,0,0,0,0,0,0,~
0,0,0,0,0,0,0,0,0,0,0)';
      BIDIRECTIONAL='TRUE';
      INPUT_LOAD='(-0.01,0.01)';
      OUTPUT_LOAD='(1.0,-1.0)';
      PINUSE='BI';
    'MBA_DATA15':
      PIN_NUMBER='(0,U62,0,0,0,0,0,0,0,0,0,0,0,0,0,0,0,0,0,0,0,0,0,0,0,0,0,0,0,0~
,0,0,0,0,0,0,0,0,0,0)';
      BIDIRECTIONAL='TRUE';
      INPUT_LOAD='(-0.01,0.01)';
      OUTPUT_LOAD='(1.0,-1.0)';
      PINUSE='BI';
    'MBA_DATA2':
      PIN_NUMBER='(0,F63,0,0,0,0,0,0,0,0,0,0,0,0,0,0,0,0,0,0,0,0,0,0,0,0,0,0,0,0~
,0,0,0,0,0,0,0,0,0,0)';
      BIDIRECTIONAL='TRUE';
      INPUT_LOAD='(-0.01,0.01)';
      OUTPUT_LOAD='(1.0,-1.0)';
      PINUSE='BI';
    'MBA_CHECK6':
      PIN_NUMBER='(0,AP63,0,0,0,0,0,0,0,0,0,0,0,0,0,0,0,0,0,0,0,0,0,0,0,0,0,0,0,~
0,0,0,0,0,0,0,0,0,0,0)';
      BIDIRECTIONAL='TRUE';
      INPUT_LOAD='(-0.01,0.01)';
      OUTPUT_LOAD='(1.0,-1.0)';
      PINUSE='BI';
    'MBB_DATA21':
      PIN_NUMBER='(0,CW62,0,0,0,0,0,0,0,0,0,0,0,0,0,0,0,0,0,0,0,0,0,0,0,0,0,0,0,~
0,0,0,0,0,0,0,0,0,0,0)';
      BIDIRECTIONAL='TRUE';
      INPUT_LOAD='(-0.01,0.01)';
      OUTPUT_LOAD='(1.0,-1.0)';
      PINUSE='BI';
    'MBB_DATA10':
      PIN_NUMBER='(0,CJ64,0,0,0,0,0,0,0,0,0,0,0,0,0,0,0,0,0,0,0,0,0,0,0,0,0,0,0,~
0,0,0,0,0,0,0,0,0,0,0)';
      BIDIRECTIONAL='TRUE';
      INPUT_LOAD='(-0.01,0.01)';
      OUTPUT_LOAD='(1.0,-1.0)';
      PINUSE='BI';
    'MBB_DATA2':
      PIN_NUMBER='(0,CC64,0,0,0,0,0,0,0,0,0,0,0,0,0,0,0,0,0,0,0,0,0,0,0,0,0,0,0,~
0,0,0,0,0,0,0,0,0,0,0)';
      BIDIRECTIONAL='TRUE';
      INPUT_LOAD='(-0.01,0.01)';
      OUTPUT_LOAD='(1.0,-1.0)';
      PINUSE='BI';
    'MBB_CHECK1':
      PIN_NUMBER='(0,CA62,0,0,0,0,0,0,0,0,0,0,0,0,0,0,0,0,0,0,0,0,0,0,0,0,0,0,0,~
0,0,0,0,0,0,0,0,0,0,0)';
      BIDIRECTIONAL='TRUE';
      INPUT_LOAD='(-0.01,0.01)';
      OUTPUT_LOAD='(1.0,-1.0)';
      PINUSE='BI';
    'MBA_DQS_L3':
      PIN_NUMBER='(0,AF63,0,0,0,0,0,0,0,0,0,0,0,0,0,0,0,0,0,0,0,0,0,0,0,0,0,0,0,~
0,0,0,0,0,0,0,0,0,0,0)';
      BIDIRECTIONAL='TRUE';
      INPUT_LOAD='(-0.01,0.01)';
      OUTPUT_LOAD='(1.0,-1.0)';
      PINUSE='BI';
    'MBA_DATA27':
      PIN_NUMBER='(0,AE62,0,0,0,0,0,0,0,0,0,0,0,0,0,0,0,0,0,0,0,0,0,0,0,0,0,0,0,~
0,0,0,0,0,0,0,0,0,0,0)';
      BIDIRECTIONAL='TRUE';
      INPUT_LOAD='(-0.01,0.01)';
      OUTPUT_LOAD='(1.0,-1.0)';
      PINUSE='BI';
    'MBA_DATA16':
      PIN_NUMBER='(0,U64,0,0,0,0,0,0,0,0,0,0,0,0,0,0,0,0,0,0,0,0,0,0,0,0,0,0,0,0~
,0,0,0,0,0,0,0,0,0,0)';
      BIDIRECTIONAL='TRUE';
      INPUT_LOAD='(-0.01,0.01)';
      OUTPUT_LOAD='(1.0,-1.0)';
      PINUSE='BI';
    'MBA_DATA3':
      PIN_NUMBER='(0,G62,0,0,0,0,0,0,0,0,0,0,0,0,0,0,0,0,0,0,0,0,0,0,0,0,0,0,0,0~
,0,0,0,0,0,0,0,0,0,0)';
      BIDIRECTIONAL='TRUE';
      INPUT_LOAD='(-0.01,0.01)';
      OUTPUT_LOAD='(1.0,-1.0)';
      PINUSE='BI';
    'MBA_CHECK7':
      PIN_NUMBER='(0,AR62,0,0,0,0,0,0,0,0,0,0,0,0,0,0,0,0,0,0,0,0,0,0,0,0,0,0,0,~
0,0,0,0,0,0,0,0,0,0,0)';
      BIDIRECTIONAL='TRUE';
      INPUT_LOAD='(-0.01,0.01)';
      OUTPUT_LOAD='(1.0,-1.0)';
      PINUSE='BI';
    'MBA0_RSP_L':
      PIN_NUMBER='(0,BN62,0,0,0,0,0,0,0,0,0,0,0,0,0,0,0,0,0,0,0,0,0,0,0,0,0,0,0,~
0,0,0,0,0,0,0,0,0,0,0)';
      INPUT_LOAD='(-0.01,0.01)';
      PINUSE='IN';
    'MBB_DATA22':
      PIN_NUMBER='(0,CW64,0,0,0,0,0,0,0,0,0,0,0,0,0,0,0,0,0,0,0,0,0,0,0,0,0,0,0,~
0,0,0,0,0,0,0,0,0,0,0)';
      BIDIRECTIONAL='TRUE';
      INPUT_LOAD='(-0.01,0.01)';
      OUTPUT_LOAD='(1.0,-1.0)';
      PINUSE='BI';
    'MBB_DATA11':
      PIN_NUMBER='(0,CK62,0,0,0,0,0,0,0,0,0,0,0,0,0,0,0,0,0,0,0,0,0,0,0,0,0,0,0,~
0,0,0,0,0,0,0,0,0,0,0)';
      BIDIRECTIONAL='TRUE';
      INPUT_LOAD='(-0.01,0.01)';
      OUTPUT_LOAD='(1.0,-1.0)';
      PINUSE='BI';
    'MBB_DATA3':
      PIN_NUMBER='(0,CD62,0,0,0,0,0,0,0,0,0,0,0,0,0,0,0,0,0,0,0,0,0,0,0,0,0,0,0,~
0,0,0,0,0,0,0,0,0,0,0)';
      BIDIRECTIONAL='TRUE';
      INPUT_LOAD='(-0.01,0.01)';
      OUTPUT_LOAD='(1.0,-1.0)';
      PINUSE='BI';
    'MBB_CHECK2':
      PIN_NUMBER='(0,CA64,0,0,0,0,0,0,0,0,0,0,0,0,0,0,0,0,0,0,0,0,0,0,0,0,0,0,0,~
0,0,0,0,0,0,0,0,0,0,0)';
      BIDIRECTIONAL='TRUE';
      INPUT_LOAD='(-0.01,0.01)';
      OUTPUT_LOAD='(1.0,-1.0)';
      PINUSE='BI';
    'MBA_DQS_L4':
      PIN_NUMBER='(0,AM63,0,0,0,0,0,0,0,0,0,0,0,0,0,0,0,0,0,0,0,0,0,0,0,0,0,0,0,~
0,0,0,0,0,0,0,0,0,0,0)';
      BIDIRECTIONAL='TRUE';
      INPUT_LOAD='(-0.01,0.01)';
      OUTPUT_LOAD='(1.0,-1.0)';
      PINUSE='BI';
    'MBA_DQS_H0':
      PIN_NUMBER='(0,G64,0,0,0,0,0,0,0,0,0,0,0,0,0,0,0,0,0,0,0,0,0,0,0,0,0,0,0,0~
,0,0,0,0,0,0,0,0,0,0)';
      BIDIRECTIONAL='TRUE';
      INPUT_LOAD='(-0.01,0.01)';
      OUTPUT_LOAD='(1.0,-1.0)';
      PINUSE='BI';
    'MBA_DATA28':
      PIN_NUMBER='(0,AG64,0,0,0,0,0,0,0,0,0,0,0,0,0,0,0,0,0,0,0,0,0,0,0,0,0,0,0,~
0,0,0,0,0,0,0,0,0,0,0)';
      BIDIRECTIONAL='TRUE';
      INPUT_LOAD='(-0.01,0.01)';
      OUTPUT_LOAD='(1.0,-1.0)';
      PINUSE='BI';
    'MBA_DATA17':
      PIN_NUMBER='(0,V62,0,0,0,0,0,0,0,0,0,0,0,0,0,0,0,0,0,0,0,0,0,0,0,0,0,0,0,0~
,0,0,0,0,0,0,0,0,0,0)';
      BIDIRECTIONAL='TRUE';
      INPUT_LOAD='(-0.01,0.01)';
      OUTPUT_LOAD='(1.0,-1.0)';
      PINUSE='BI';
    'MBA_DATA4':
      PIN_NUMBER='(0,J64,0,0,0,0,0,0,0,0,0,0,0,0,0,0,0,0,0,0,0,0,0,0,0,0,0,0,0,0~
,0,0,0,0,0,0,0,0,0,0)';
      BIDIRECTIONAL='TRUE';
      INPUT_LOAD='(-0.01,0.01)';
      OUTPUT_LOAD='(1.0,-1.0)';
      PINUSE='BI';
    'MBA1_RSP_L':
      PIN_NUMBER='(0,BP62,0,0,0,0,0,0,0,0,0,0,0,0,0,0,0,0,0,0,0,0,0,0,0,0,0,0,0,~
0,0,0,0,0,0,0,0,0,0,0)';
      INPUT_LOAD='(-0.01,0.01)';
      PINUSE='IN';
    'MBB_DATA23':
      PIN_NUMBER='(0,CY62,0,0,0,0,0,0,0,0,0,0,0,0,0,0,0,0,0,0,0,0,0,0,0,0,0,0,0,~
0,0,0,0,0,0,0,0,0,0,0)';
      BIDIRECTIONAL='TRUE';
      INPUT_LOAD='(-0.01,0.01)';
      OUTPUT_LOAD='(1.0,-1.0)';
      PINUSE='BI';
    'MBB_DATA12':
      PIN_NUMBER='(0,CM63,0,0,0,0,0,0,0,0,0,0,0,0,0,0,0,0,0,0,0,0,0,0,0,0,0,0,0,~
0,0,0,0,0,0,0,0,0,0,0)';
      BIDIRECTIONAL='TRUE';
      INPUT_LOAD='(-0.01,0.01)';
      OUTPUT_LOAD='(1.0,-1.0)';
      PINUSE='BI';
    'MBB_DATA4':
      PIN_NUMBER='(0,CF63,0,0,0,0,0,0,0,0,0,0,0,0,0,0,0,0,0,0,0,0,0,0,0,0,0,0,0,~
0,0,0,0,0,0,0,0,0,0,0)';
      BIDIRECTIONAL='TRUE';
      INPUT_LOAD='(-0.01,0.01)';
      OUTPUT_LOAD='(1.0,-1.0)';
      PINUSE='BI';
    'MBB_CHECK3':
      PIN_NUMBER='(0,CB62,0,0,0,0,0,0,0,0,0,0,0,0,0,0,0,0,0,0,0,0,0,0,0,0,0,0,0,~
0,0,0,0,0,0,0,0,0,0,0)';
      BIDIRECTIONAL='TRUE';
      INPUT_LOAD='(-0.01,0.01)';
      OUTPUT_LOAD='(1.0,-1.0)';
      PINUSE='BI';
    'MBA_DQS_L5':
      PIN_NUMBER='(0,H62,0,0,0,0,0,0,0,0,0,0,0,0,0,0,0,0,0,0,0,0,0,0,0,0,0,0,0,0~
,0,0,0,0,0,0,0,0,0,0)';
      BIDIRECTIONAL='TRUE';
      INPUT_LOAD='(-0.01,0.01)';
      OUTPUT_LOAD='(1.0,-1.0)';
      PINUSE='BI';
    'MBA_DQS_H1':
      PIN_NUMBER='(0,N64,0,0,0,0,0,0,0,0,0,0,0,0,0,0,0,0,0,0,0,0,0,0,0,0,0,0,0,0~
,0,0,0,0,0,0,0,0,0,0)';
      BIDIRECTIONAL='TRUE';
      INPUT_LOAD='(-0.01,0.01)';
      OUTPUT_LOAD='(1.0,-1.0)';
      PINUSE='BI';
    'MBA_DATA29':
      PIN_NUMBER='(0,AH62,0,0,0,0,0,0,0,0,0,0,0,0,0,0,0,0,0,0,0,0,0,0,0,0,0,0,0,~
0,0,0,0,0,0,0,0,0,0,0)';
      BIDIRECTIONAL='TRUE';
      INPUT_LOAD='(-0.01,0.01)';
      OUTPUT_LOAD='(1.0,-1.0)';
      PINUSE='BI';
    'MBA_DATA18':
      PIN_NUMBER='(0,V63,0,0,0,0,0,0,0,0,0,0,0,0,0,0,0,0,0,0,0,0,0,0,0,0,0,0,0,0~
,0,0,0,0,0,0,0,0,0,0)';
      BIDIRECTIONAL='TRUE';
      INPUT_LOAD='(-0.01,0.01)';
      OUTPUT_LOAD='(1.0,-1.0)';
      PINUSE='BI';
    'MBA_DATA5':
      PIN_NUMBER='(0,K62,0,0,0,0,0,0,0,0,0,0,0,0,0,0,0,0,0,0,0,0,0,0,0,0,0,0,0,0~
,0,0,0,0,0,0,0,0,0,0)';
      BIDIRECTIONAL='TRUE';
      INPUT_LOAD='(-0.01,0.01)';
      OUTPUT_LOAD='(1.0,-1.0)';
      PINUSE='BI';
    'MBB_DQS_L0':
      PIN_NUMBER='(0,CE64,0,0,0,0,0,0,0,0,0,0,0,0,0,0,0,0,0,0,0,0,0,0,0,0,0,0,0,~
0,0,0,0,0,0,0,0,0,0,0)';
      BIDIRECTIONAL='TRUE';
      INPUT_LOAD='(-0.01,0.01)';
      OUTPUT_LOAD='(1.0,-1.0)';
      PINUSE='BI';
    'MBB_DATA24':
      PIN_NUMBER='(0,CY63,0,0,0,0,0,0,0,0,0,0,0,0,0,0,0,0,0,0,0,0,0,0,0,0,0,0,0,~
0,0,0,0,0,0,0,0,0,0,0)';
      BIDIRECTIONAL='TRUE';
      INPUT_LOAD='(-0.01,0.01)';
      OUTPUT_LOAD='(1.0,-1.0)';
      PINUSE='BI';
    'MBB_DATA13':
      PIN_NUMBER='(0,CN62,0,0,0,0,0,0,0,0,0,0,0,0,0,0,0,0,0,0,0,0,0,0,0,0,0,0,0,~
0,0,0,0,0,0,0,0,0,0,0)';
      BIDIRECTIONAL='TRUE';
      INPUT_LOAD='(-0.01,0.01)';
      OUTPUT_LOAD='(1.0,-1.0)';
      PINUSE='BI';
    'MBB_DATA5':
      PIN_NUMBER='(0,CG62,0,0,0,0,0,0,0,0,0,0,0,0,0,0,0,0,0,0,0,0,0,0,0,0,0,0,0,~
0,0,0,0,0,0,0,0,0,0,0)';
      BIDIRECTIONAL='TRUE';
      INPUT_LOAD='(-0.01,0.01)';
      OUTPUT_LOAD='(1.0,-1.0)';
      PINUSE='BI';
    'MBB_CHECK4':
      PIN_NUMBER='(0,BT63,0,0,0,0,0,0,0,0,0,0,0,0,0,0,0,0,0,0,0,0,0,0,0,0,0,0,0,~
0,0,0,0,0,0,0,0,0,0,0)';
      BIDIRECTIONAL='TRUE';
      INPUT_LOAD='(-0.01,0.01)';
      OUTPUT_LOAD='(1.0,-1.0)';
      PINUSE='BI';
    'MBA_DQS_L6':
      PIN_NUMBER='(0,P62,0,0,0,0,0,0,0,0,0,0,0,0,0,0,0,0,0,0,0,0,0,0,0,0,0,0,0,0~
,0,0,0,0,0,0,0,0,0,0)';
      BIDIRECTIONAL='TRUE';
      INPUT_LOAD='(-0.01,0.01)';
      OUTPUT_LOAD='(1.0,-1.0)';
      PINUSE='BI';
    'MBA_DQS_H2':
      PIN_NUMBER='(0,W64,0,0,0,0,0,0,0,0,0,0,0,0,0,0,0,0,0,0,0,0,0,0,0,0,0,0,0,0~
,0,0,0,0,0,0,0,0,0,0)';
      BIDIRECTIONAL='TRUE';
      INPUT_LOAD='(-0.01,0.01)';
      OUTPUT_LOAD='(1.0,-1.0)';
      PINUSE='BI';
    'MBA_DATA19':
      PIN_NUMBER='(0,W62,0,0,0,0,0,0,0,0,0,0,0,0,0,0,0,0,0,0,0,0,0,0,0,0,0,0,0,0~
,0,0,0,0,0,0,0,0,0,0)';
      BIDIRECTIONAL='TRUE';
      INPUT_LOAD='(-0.01,0.01)';
      OUTPUT_LOAD='(1.0,-1.0)';
      PINUSE='BI';
    'MBA_DATA6':
      PIN_NUMBER='(0,K63,0,0,0,0,0,0,0,0,0,0,0,0,0,0,0,0,0,0,0,0,0,0,0,0,0,0,0,0~
,0,0,0,0,0,0,0,0,0,0)';
      BIDIRECTIONAL='TRUE';
      INPUT_LOAD='(-0.01,0.01)';
      OUTPUT_LOAD='(1.0,-1.0)';
      PINUSE='BI';
    'MBA_CA0':
      PIN_NUMBER='(0,AW64,0,0,0,0,0,0,0,0,0,0,0,0,0,0,0,0,0,0,0,0,0,0,0,0,0,0,0,~
0,0,0,0,0,0,0,0,0,0,0)';
      OUTPUT_LOAD='(1.0,-1.0)';
      PINUSE='OUT';
    'MBB_DQS_L1':
      PIN_NUMBER='(0,CL64,0,0,0,0,0,0,0,0,0,0,0,0,0,0,0,0,0,0,0,0,0,0,0,0,0,0,0,~
0,0,0,0,0,0,0,0,0,0,0)';
      BIDIRECTIONAL='TRUE';
      INPUT_LOAD='(-0.01,0.01)';
      OUTPUT_LOAD='(1.0,-1.0)';
      PINUSE='BI';
    'MBB_DATA25':
      PIN_NUMBER='(0,DA62,0,0,0,0,0,0,0,0,0,0,0,0,0,0,0,0,0,0,0,0,0,0,0,0,0,0,0,~
0,0,0,0,0,0,0,0,0,0,0)';
      BIDIRECTIONAL='TRUE';
      INPUT_LOAD='(-0.01,0.01)';
      OUTPUT_LOAD='(1.0,-1.0)';
      PINUSE='BI';
    'MBB_DATA14':
      PIN_NUMBER='(0,CN64,0,0,0,0,0,0,0,0,0,0,0,0,0,0,0,0,0,0,0,0,0,0,0,0,0,0,0,~
0,0,0,0,0,0,0,0,0,0,0)';
      BIDIRECTIONAL='TRUE';
      INPUT_LOAD='(-0.01,0.01)';
      OUTPUT_LOAD='(1.0,-1.0)';
      PINUSE='BI';
    'MBB_DATA6':
      PIN_NUMBER='(0,CG64,0,0,0,0,0,0,0,0,0,0,0,0,0,0,0,0,0,0,0,0,0,0,0,0,0,0,0,~
0,0,0,0,0,0,0,0,0,0,0)';
      BIDIRECTIONAL='TRUE';
      INPUT_LOAD='(-0.01,0.01)';
      OUTPUT_LOAD='(1.0,-1.0)';
      PINUSE='BI';
    'MBB_CHECK5':
      PIN_NUMBER='(0,BU62,0,0,0,0,0,0,0,0,0,0,0,0,0,0,0,0,0,0,0,0,0,0,0,0,0,0,0,~
0,0,0,0,0,0,0,0,0,0,0)';
      BIDIRECTIONAL='TRUE';
      INPUT_LOAD='(-0.01,0.01)';
      OUTPUT_LOAD='(1.0,-1.0)';
      PINUSE='BI';
    'MBB_CA0':
      PIN_NUMBER='(0,BG62,0,0,0,0,0,0,0,0,0,0,0,0,0,0,0,0,0,0,0,0,0,0,0,0,0,0,0,~
0,0,0,0,0,0,0,0,0,0,0)';
      OUTPUT_LOAD='(1.0,-1.0)';
      PINUSE='OUT';
    'MBA_DQS_L7':
      PIN_NUMBER='(0,Y62,0,0,0,0,0,0,0,0,0,0,0,0,0,0,0,0,0,0,0,0,0,0,0,0,0,0,0,0~
,0,0,0,0,0,0,0,0,0,0)';
      BIDIRECTIONAL='TRUE';
      INPUT_LOAD='(-0.01,0.01)';
      OUTPUT_LOAD='(1.0,-1.0)';
      PINUSE='BI';
    'MBA_DQS_H3':
      PIN_NUMBER='(0,AE64,0,0,0,0,0,0,0,0,0,0,0,0,0,0,0,0,0,0,0,0,0,0,0,0,0,0,0,~
0,0,0,0,0,0,0,0,0,0,0)';
      BIDIRECTIONAL='TRUE';
      INPUT_LOAD='(-0.01,0.01)';
      OUTPUT_LOAD='(1.0,-1.0)';
      PINUSE='BI';
    'MBA_DATA7':
      PIN_NUMBER='(0,L62,0,0,0,0,0,0,0,0,0,0,0,0,0,0,0,0,0,0,0,0,0,0,0,0,0,0,0,0~
,0,0,0,0,0,0,0,0,0,0)';
      BIDIRECTIONAL='TRUE';
      INPUT_LOAD='(-0.01,0.01)';
      OUTPUT_LOAD='(1.0,-1.0)';
      PINUSE='BI';
    'MBA_CA1':
      PIN_NUMBER='(0,AY63,0,0,0,0,0,0,0,0,0,0,0,0,0,0,0,0,0,0,0,0,0,0,0,0,0,0,0,~
0,0,0,0,0,0,0,0,0,0,0)';
      OUTPUT_LOAD='(1.0,-1.0)';
      PINUSE='OUT';
    'MBB_DQS_L2':
      PIN_NUMBER='(0,CU64,0,0,0,0,0,0,0,0,0,0,0,0,0,0,0,0,0,0,0,0,0,0,0,0,0,0,0,~
0,0,0,0,0,0,0,0,0,0,0)';
      BIDIRECTIONAL='TRUE';
      INPUT_LOAD='(-0.01,0.01)';
      OUTPUT_LOAD='(1.0,-1.0)';
      PINUSE='BI';
    'MBB_DATA26':
      PIN_NUMBER='(0,DA64,0,0,0,0,0,0,0,0,0,0,0,0,0,0,0,0,0,0,0,0,0,0,0,0,0,0,0,~
0,0,0,0,0,0,0,0,0,0,0)';
      BIDIRECTIONAL='TRUE';
      INPUT_LOAD='(-0.01,0.01)';
      OUTPUT_LOAD='(1.0,-1.0)';
      PINUSE='BI';
    'MBB_DATA15':
      PIN_NUMBER='(0,CP62,0,0,0,0,0,0,0,0,0,0,0,0,0,0,0,0,0,0,0,0,0,0,0,0,0,0,0,~
0,0,0,0,0,0,0,0,0,0,0)';
      BIDIRECTIONAL='TRUE';
      INPUT_LOAD='(-0.01,0.01)';
      OUTPUT_LOAD='(1.0,-1.0)';
      PINUSE='BI';
    'MBB_DATA7':
      PIN_NUMBER='(0,CH62,0,0,0,0,0,0,0,0,0,0,0,0,0,0,0,0,0,0,0,0,0,0,0,0,0,0,0,~
0,0,0,0,0,0,0,0,0,0,0)';
      BIDIRECTIONAL='TRUE';
      INPUT_LOAD='(-0.01,0.01)';
      OUTPUT_LOAD='(1.0,-1.0)';
      PINUSE='BI';
    'MBB_CHECK6':
      PIN_NUMBER='(0,BU64,0,0,0,0,0,0,0,0,0,0,0,0,0,0,0,0,0,0,0,0,0,0,0,0,0,0,0,~
0,0,0,0,0,0,0,0,0,0,0)';
      BIDIRECTIONAL='TRUE';
      INPUT_LOAD='(-0.01,0.01)';
      OUTPUT_LOAD='(1.0,-1.0)';
      PINUSE='BI';
    'MBB_CA1':
      PIN_NUMBER='(0,BH62,0,0,0,0,0,0,0,0,0,0,0,0,0,0,0,0,0,0,0,0,0,0,0,0,0,0,0,~
0,0,0,0,0,0,0,0,0,0,0)';
      OUTPUT_LOAD='(1.0,-1.0)';
      PINUSE='OUT';
    'MBA_DQS_L8':
      PIN_NUMBER='(0,AF62,0,0,0,0,0,0,0,0,0,0,0,0,0,0,0,0,0,0,0,0,0,0,0,0,0,0,0,~
0,0,0,0,0,0,0,0,0,0,0)';
      BIDIRECTIONAL='TRUE';
      INPUT_LOAD='(-0.01,0.01)';
      OUTPUT_LOAD='(1.0,-1.0)';
      PINUSE='BI';
    'MBA_DQS_H4':
      PIN_NUMBER='(0,AL64,0,0,0,0,0,0,0,0,0,0,0,0,0,0,0,0,0,0,0,0,0,0,0,0,0,0,0,~
0,0,0,0,0,0,0,0,0,0,0)';
      BIDIRECTIONAL='TRUE';
      INPUT_LOAD='(-0.01,0.01)';
      OUTPUT_LOAD='(1.0,-1.0)';
      PINUSE='BI';
    'MBA_DATA8':
      PIN_NUMBER='(0,L64,0,0,0,0,0,0,0,0,0,0,0,0,0,0,0,0,0,0,0,0,0,0,0,0,0,0,0,0~
,0,0,0,0,0,0,0,0,0,0)';
      BIDIRECTIONAL='TRUE';
      INPUT_LOAD='(-0.01,0.01)';
      OUTPUT_LOAD='(1.0,-1.0)';
      PINUSE='BI';
    'MBA_CA2':
      PIN_NUMBER='(0,AY62,0,0,0,0,0,0,0,0,0,0,0,0,0,0,0,0,0,0,0,0,0,0,0,0,0,0,0,~
0,0,0,0,0,0,0,0,0,0,0)';
      OUTPUT_LOAD='(1.0,-1.0)';
      PINUSE='OUT';
    'MBB_DQS_L3':
      PIN_NUMBER='(0,DC64,0,0,0,0,0,0,0,0,0,0,0,0,0,0,0,0,0,0,0,0,0,0,0,0,0,0,0,~
0,0,0,0,0,0,0,0,0,0,0)';
      BIDIRECTIONAL='TRUE';
      INPUT_LOAD='(-0.01,0.01)';
      OUTPUT_LOAD='(1.0,-1.0)';
      PINUSE='BI';
    'MBB_DATA27':
      PIN_NUMBER='(0,DB62,0,0,0,0,0,0,0,0,0,0,0,0,0,0,0,0,0,0,0,0,0,0,0,0,0,0,0,~
0,0,0,0,0,0,0,0,0,0,0)';
      BIDIRECTIONAL='TRUE';
      INPUT_LOAD='(-0.01,0.01)';
      OUTPUT_LOAD='(1.0,-1.0)';
      PINUSE='BI';
    'MBB_DATA16':
      PIN_NUMBER='(0,CP63,0,0,0,0,0,0,0,0,0,0,0,0,0,0,0,0,0,0,0,0,0,0,0,0,0,0,0,~
0,0,0,0,0,0,0,0,0,0,0)';
      BIDIRECTIONAL='TRUE';
      INPUT_LOAD='(-0.01,0.01)';
      OUTPUT_LOAD='(1.0,-1.0)';
      PINUSE='BI';
    'MBB_DATA8':
      PIN_NUMBER='(0,CH63,0,0,0,0,0,0,0,0,0,0,0,0,0,0,0,0,0,0,0,0,0,0,0,0,0,0,0,~
0,0,0,0,0,0,0,0,0,0,0)';
      BIDIRECTIONAL='TRUE';
      INPUT_LOAD='(-0.01,0.01)';
      OUTPUT_LOAD='(1.0,-1.0)';
      PINUSE='BI';
    'MBB_CHECK7':
      PIN_NUMBER='(0,BV62,0,0,0,0,0,0,0,0,0,0,0,0,0,0,0,0,0,0,0,0,0,0,0,0,0,0,0,~
0,0,0,0,0,0,0,0,0,0,0)';
      BIDIRECTIONAL='TRUE';
      INPUT_LOAD='(-0.01,0.01)';
      OUTPUT_LOAD='(1.0,-1.0)';
      PINUSE='BI';
    'MBB_CA2':
      PIN_NUMBER='(0,BH63,0,0,0,0,0,0,0,0,0,0,0,0,0,0,0,0,0,0,0,0,0,0,0,0,0,0,0,~
0,0,0,0,0,0,0,0,0,0,0)';
      OUTPUT_LOAD='(1.0,-1.0)';
      PINUSE='OUT';
    'MBB0_RSP_L':
      PIN_NUMBER='(0,BP63,0,0,0,0,0,0,0,0,0,0,0,0,0,0,0,0,0,0,0,0,0,0,0,0,0,0,0,~
0,0,0,0,0,0,0,0,0,0,0)';
      INPUT_LOAD='(-0.01,0.01)';
      PINUSE='IN';
    'MBA_DQS_L9':
      PIN_NUMBER='(0,AM62,0,0,0,0,0,0,0,0,0,0,0,0,0,0,0,0,0,0,0,0,0,0,0,0,0,0,0,~
0,0,0,0,0,0,0,0,0,0,0)';
      BIDIRECTIONAL='TRUE';
      INPUT_LOAD='(-0.01,0.01)';
      OUTPUT_LOAD='(1.0,-1.0)';
      PINUSE='BI';
    'MBA_DQS_H5':
      PIN_NUMBER='(0,J62,0,0,0,0,0,0,0,0,0,0,0,0,0,0,0,0,0,0,0,0,0,0,0,0,0,0,0,0~
,0,0,0,0,0,0,0,0,0,0)';
      BIDIRECTIONAL='TRUE';
      INPUT_LOAD='(-0.01,0.01)';
      OUTPUT_LOAD='(1.0,-1.0)';
      PINUSE='BI';
    'MBA_DATA9':
      PIN_NUMBER='(0,M62,0,0,0,0,0,0,0,0,0,0,0,0,0,0,0,0,0,0,0,0,0,0,0,0,0,0,0,0~
,0,0,0,0,0,0,0,0,0,0)';
      BIDIRECTIONAL='TRUE';
      INPUT_LOAD='(-0.01,0.01)';
      OUTPUT_LOAD='(1.0,-1.0)';
      PINUSE='BI';
    'MBA_CA3':
      PIN_NUMBER='(0,BA62,0,0,0,0,0,0,0,0,0,0,0,0,0,0,0,0,0,0,0,0,0,0,0,0,0,0,0,~
0,0,0,0,0,0,0,0,0,0,0)';
      OUTPUT_LOAD='(1.0,-1.0)';
      PINUSE='OUT';
    'MBB_DQS_L4':
      PIN_NUMBER='(0,BW62,0,0,0,0,0,0,0,0,0,0,0,0,0,0,0,0,0,0,0,0,0,0,0,0,0,0,0,~
0,0,0,0,0,0,0,0,0,0,0)';
      BIDIRECTIONAL='TRUE';
      INPUT_LOAD='(-0.01,0.01)';
      OUTPUT_LOAD='(1.0,-1.0)';
      PINUSE='BI';
    'MBB_DQS_H0':
      PIN_NUMBER='(0,CD63,0,0,0,0,0,0,0,0,0,0,0,0,0,0,0,0,0,0,0,0,0,0,0,0,0,0,0,~
0,0,0,0,0,0,0,0,0,0,0)';
      BIDIRECTIONAL='TRUE';
      INPUT_LOAD='(-0.01,0.01)';
      OUTPUT_LOAD='(1.0,-1.0)';
      PINUSE='BI';
    'MBB_DATA28':
      PIN_NUMBER='(0,DD63,0,0,0,0,0,0,0,0,0,0,0,0,0,0,0,0,0,0,0,0,0,0,0,0,0,0,0,~
0,0,0,0,0,0,0,0,0,0,0)';
      BIDIRECTIONAL='TRUE';
      INPUT_LOAD='(-0.01,0.01)';
      OUTPUT_LOAD='(1.0,-1.0)';
      PINUSE='BI';
    'MBB_DATA17':
      PIN_NUMBER='(0,CR62,0,0,0,0,0,0,0,0,0,0,0,0,0,0,0,0,0,0,0,0,0,0,0,0,0,0,0,~
0,0,0,0,0,0,0,0,0,0,0)';
      BIDIRECTIONAL='TRUE';
      INPUT_LOAD='(-0.01,0.01)';
      OUTPUT_LOAD='(1.0,-1.0)';
      PINUSE='BI';
    'MBB_DATA9':
      PIN_NUMBER='(0,CJ62,0,0,0,0,0,0,0,0,0,0,0,0,0,0,0,0,0,0,0,0,0,0,0,0,0,0,0,~
0,0,0,0,0,0,0,0,0,0,0)';
      BIDIRECTIONAL='TRUE';
      INPUT_LOAD='(-0.01,0.01)';
      OUTPUT_LOAD='(1.0,-1.0)';
      PINUSE='BI';
    'MBB_CA3':
      PIN_NUMBER='(0,BJ64,0,0,0,0,0,0,0,0,0,0,0,0,0,0,0,0,0,0,0,0,0,0,0,0,0,0,0,~
0,0,0,0,0,0,0,0,0,0,0)';
      OUTPUT_LOAD='(1.0,-1.0)';
      PINUSE='OUT';
    'MBB1_RSP_L':
      PIN_NUMBER='(0,BR64,0,0,0,0,0,0,0,0,0,0,0,0,0,0,0,0,0,0,0,0,0,0,0,0,0,0,0,~
0,0,0,0,0,0,0,0,0,0,0)';
      INPUT_LOAD='(-0.01,0.01)';
      PINUSE='IN';
    'MBA_DQS_H6':
      PIN_NUMBER='(0,R62,0,0,0,0,0,0,0,0,0,0,0,0,0,0,0,0,0,0,0,0,0,0,0,0,0,0,0,0~
,0,0,0,0,0,0,0,0,0,0)';
      BIDIRECTIONAL='TRUE';
      INPUT_LOAD='(-0.01,0.01)';
      OUTPUT_LOAD='(1.0,-1.0)';
      PINUSE='BI';
    'MBA_CA4':
      PIN_NUMBER='(0,BA64,0,0,0,0,0,0,0,0,0,0,0,0,0,0,0,0,0,0,0,0,0,0,0,0,0,0,0,~
0,0,0,0,0,0,0,0,0,0,0)';
      OUTPUT_LOAD='(1.0,-1.0)';
      PINUSE='OUT';
    'MBB_DQS_L5':
      PIN_NUMBER='(0,CE62,0,0,0,0,0,0,0,0,0,0,0,0,0,0,0,0,0,0,0,0,0,0,0,0,0,0,0,~
0,0,0,0,0,0,0,0,0,0,0)';
      BIDIRECTIONAL='TRUE';
      INPUT_LOAD='(-0.01,0.01)';
      OUTPUT_LOAD='(1.0,-1.0)';
      PINUSE='BI';
    'MBB_DQS_H1':
      PIN_NUMBER='(0,CK63,0,0,0,0,0,0,0,0,0,0,0,0,0,0,0,0,0,0,0,0,0,0,0,0,0,0,0,~
0,0,0,0,0,0,0,0,0,0,0)';
      BIDIRECTIONAL='TRUE';
      INPUT_LOAD='(-0.01,0.01)';
      OUTPUT_LOAD='(1.0,-1.0)';
      PINUSE='BI';
    'MBB_DATA29':
      PIN_NUMBER='(0,DE62,0,0,0,0,0,0,0,0,0,0,0,0,0,0,0,0,0,0,0,0,0,0,0,0,0,0,0,~
0,0,0,0,0,0,0,0,0,0,0)';
      BIDIRECTIONAL='TRUE';
      INPUT_LOAD='(-0.01,0.01)';
      OUTPUT_LOAD='(1.0,-1.0)';
      PINUSE='BI';
    'MBB_DATA18':
      PIN_NUMBER='(0,CR64,0,0,0,0,0,0,0,0,0,0,0,0,0,0,0,0,0,0,0,0,0,0,0,0,0,0,0,~
0,0,0,0,0,0,0,0,0,0,0)';
      BIDIRECTIONAL='TRUE';
      INPUT_LOAD='(-0.01,0.01)';
      OUTPUT_LOAD='(1.0,-1.0)';
      PINUSE='BI';
    'MBB_CA4':
      PIN_NUMBER='(0,BJ62,0,0,0,0,0,0,0,0,0,0,0,0,0,0,0,0,0,0,0,0,0,0,0,0,0,0,0,~
0,0,0,0,0,0,0,0,0,0,0)';
      OUTPUT_LOAD='(1.0,-1.0)';
      PINUSE='OUT';
    'MBA_DQS_H7':
      PIN_NUMBER='(0,AA62,0,0,0,0,0,0,0,0,0,0,0,0,0,0,0,0,0,0,0,0,0,0,0,0,0,0,0,~
0,0,0,0,0,0,0,0,0,0,0)';
      BIDIRECTIONAL='TRUE';
      INPUT_LOAD='(-0.01,0.01)';
      OUTPUT_LOAD='(1.0,-1.0)';
      PINUSE='BI';
    'MBA_CA5':
      PIN_NUMBER='(0,BB63,0,0,0,0,0,0,0,0,0,0,0,0,0,0,0,0,0,0,0,0,0,0,0,0,0,0,0,~
0,0,0,0,0,0,0,0,0,0,0)';
      OUTPUT_LOAD='(1.0,-1.0)';
      PINUSE='OUT';
    'MBA0_CS_L0':
      PIN_NUMBER='(0,AV63,0,0,0,0,0,0,0,0,0,0,0,0,0,0,0,0,0,0,0,0,0,0,0,0,0,0,0,~
0,0,0,0,0,0,0,0,0,0,0)';
      OUTPUT_LOAD='(1.0,-1.0)';
      PINUSE='OUT';
    'MBB_DQS_L6':
      PIN_NUMBER='(0,CL62,0,0,0,0,0,0,0,0,0,0,0,0,0,0,0,0,0,0,0,0,0,0,0,0,0,0,0,~
0,0,0,0,0,0,0,0,0,0,0)';
      BIDIRECTIONAL='TRUE';
      INPUT_LOAD='(-0.01,0.01)';
      OUTPUT_LOAD='(1.0,-1.0)';
      PINUSE='BI';
    'MBB_DQS_H2':
      PIN_NUMBER='(0,CT63,0,0,0,0,0,0,0,0,0,0,0,0,0,0,0,0,0,0,0,0,0,0,0,0,0,0,0,~
0,0,0,0,0,0,0,0,0,0,0)';
      BIDIRECTIONAL='TRUE';
      INPUT_LOAD='(-0.01,0.01)';
      OUTPUT_LOAD='(1.0,-1.0)';
      PINUSE='BI';
    'MBB_CA5':
      PIN_NUMBER='(0,BK62,0,0,0,0,0,0,0,0,0,0,0,0,0,0,0,0,0,0,0,0,0,0,0,0,0,0,0,~
0,0,0,0,0,0,0,0,0,0,0)';
      OUTPUT_LOAD='(1.0,-1.0)';
      PINUSE='OUT';
    'MBA_DQS_H8':
      PIN_NUMBER='(0,AG62,0,0,0,0,0,0,0,0,0,0,0,0,0,0,0,0,0,0,0,0,0,0,0,0,0,0,0,~
0,0,0,0,0,0,0,0,0,0,0)';
      BIDIRECTIONAL='TRUE';
      INPUT_LOAD='(-0.01,0.01)';
      OUTPUT_LOAD='(1.0,-1.0)';
      PINUSE='BI';
    'MBA_DATA30':
      PIN_NUMBER='(0,AH63,0,0,0,0,0,0,0,0,0,0,0,0,0,0,0,0,0,0,0,0,0,0,0,0,0,0,0,~
0,0,0,0,0,0,0,0,0,0,0)';
      BIDIRECTIONAL='TRUE';
      INPUT_LOAD='(-0.01,0.01)';
      OUTPUT_LOAD='(1.0,-1.0)';
      PINUSE='BI';
    'MBA_CA6':
      PIN_NUMBER='(0,BB62,0,0,0,0,0,0,0,0,0,0,0,0,0,0,0,0,0,0,0,0,0,0,0,0,0,0,0,~
0,0,0,0,0,0,0,0,0,0,0)';
      OUTPUT_LOAD='(1.0,-1.0)';
      PINUSE='OUT';
    'MBA1_CS_L0':
      PIN_NUMBER='(0,AU64,0,0,0,0,0,0,0,0,0,0,0,0,0,0,0,0,0,0,0,0,0,0,0,0,0,0,0,~
0,0,0,0,0,0,0,0,0,0,0)';
      OUTPUT_LOAD='(1.0,-1.0)';
      PINUSE='OUT';
    'MBA0_CS_L1':
      PIN_NUMBER='(0,AW62,0,0,0,0,0,0,0,0,0,0,0,0,0,0,0,0,0,0,0,0,0,0,0,0,0,0,0,~
0,0,0,0,0,0,0,0,0,0,0)';
      OUTPUT_LOAD='(1.0,-1.0)';
      PINUSE='OUT';
    'MBB_DQS_L7':
      PIN_NUMBER='(0,CU62,0,0,0,0,0,0,0,0,0,0,0,0,0,0,0,0,0,0,0,0,0,0,0,0,0,0,0,~
0,0,0,0,0,0,0,0,0,0,0)';
      BIDIRECTIONAL='TRUE';
      INPUT_LOAD='(-0.01,0.01)';
      OUTPUT_LOAD='(1.0,-1.0)';
      PINUSE='BI';
    'MBB_DQS_H3':
      PIN_NUMBER='(0,DB63,0,0,0,0,0,0,0,0,0,0,0,0,0,0,0,0,0,0,0,0,0,0,0,0,0,0,0,~
0,0,0,0,0,0,0,0,0,0,0)';
      BIDIRECTIONAL='TRUE';
      INPUT_LOAD='(-0.01,0.01)';
      OUTPUT_LOAD='(1.0,-1.0)';
      PINUSE='BI';
    'MBB_CA6':
      PIN_NUMBER='(0,BK63,0,0,0,0,0,0,0,0,0,0,0,0,0,0,0,0,0,0,0,0,0,0,0,0,0,0,0,~
0,0,0,0,0,0,0,0,0,0,0)';
      OUTPUT_LOAD='(1.0,-1.0)';
      PINUSE='OUT';
    'MBA_DQS_H9':
      PIN_NUMBER='(0,AN62,0,0,0,0,0,0,0,0,0,0,0,0,0,0,0,0,0,0,0,0,0,0,0,0,0,0,0,~
0,0,0,0,0,0,0,0,0,0,0)';
      BIDIRECTIONAL='TRUE';
      INPUT_LOAD='(-0.01,0.01)';
      OUTPUT_LOAD='(1.0,-1.0)';
      PINUSE='BI';
    'MBA_DATA31':
      PIN_NUMBER='(0,AJ62,0,0,0,0,0,0,0,0,0,0,0,0,0,0,0,0,0,0,0,0,0,0,0,0,0,0,0,~
0,0,0,0,0,0,0,0,0,0,0)';
      BIDIRECTIONAL='TRUE';
      INPUT_LOAD='(-0.01,0.01)';
      OUTPUT_LOAD='(1.0,-1.0)';
      PINUSE='BI';
    'MBA_DATA20':
      PIN_NUMBER='(0,AA64,0,0,0,0,0,0,0,0,0,0,0,0,0,0,0,0,0,0,0,0,0,0,0,0,0,0,0,~
0,0,0,0,0,0,0,0,0,0,0)';
      BIDIRECTIONAL='TRUE';
      INPUT_LOAD='(-0.01,0.01)';
      OUTPUT_LOAD='(1.0,-1.0)';
      PINUSE='BI';
    'MBA_CHECK0':
      PIN_NUMBER='(0,AJ64,0,0,0,0,0,0,0,0,0,0,0,0,0,0,0,0,0,0,0,0,0,0,0,0,0,0,0,~
0,0,0,0,0,0,0,0,0,0,0)';
      BIDIRECTIONAL='TRUE';
      INPUT_LOAD='(-0.01,0.01)';
      OUTPUT_LOAD='(1.0,-1.0)';
      PINUSE='BI';
    'MBA1_CS_L1':
      PIN_NUMBER='(0,AV62,0,0,0,0,0,0,0,0,0,0,0,0,0,0,0,0,0,0,0,0,0,0,0,0,0,0,0,~
0,0,0,0,0,0,0,0,0,0,0)';
      OUTPUT_LOAD='(1.0,-1.0)';
      PINUSE='OUT';
    'MBB_DQS_L8':
      PIN_NUMBER='(0,DC62,0,0,0,0,0,0,0,0,0,0,0,0,0,0,0,0,0,0,0,0,0,0,0,0,0,0,0,~
0,0,0,0,0,0,0,0,0,0,0)';
      BIDIRECTIONAL='TRUE';
      INPUT_LOAD='(-0.01,0.01)';
      OUTPUT_LOAD='(1.0,-1.0)';
      PINUSE='BI';
    'MBB_DQS_H4':
      PIN_NUMBER='(0,BY62,0,0,0,0,0,0,0,0,0,0,0,0,0,0,0,0,0,0,0,0,0,0,0,0,0,0,0,~
0,0,0,0,0,0,0,0,0,0,0)';
      BIDIRECTIONAL='TRUE';
      INPUT_LOAD='(-0.01,0.01)';
      OUTPUT_LOAD='(1.0,-1.0)';
      PINUSE='BI';
    'MBA_DATA21':
      PIN_NUMBER='(0,AB62,0,0,0,0,0,0,0,0,0,0,0,0,0,0,0,0,0,0,0,0,0,0,0,0,0,0,0,~
0,0,0,0,0,0,0,0,0,0,0)';
      BIDIRECTIONAL='TRUE';
      INPUT_LOAD='(-0.01,0.01)';
      OUTPUT_LOAD='(1.0,-1.0)';
      PINUSE='BI';
    'MBA_DATA10':
      PIN_NUMBER='(0,M63,0,0,0,0,0,0,0,0,0,0,0,0,0,0,0,0,0,0,0,0,0,0,0,0,0,0,0,0~
,0,0,0,0,0,0,0,0,0,0)';
      BIDIRECTIONAL='TRUE';
      INPUT_LOAD='(-0.01,0.01)';
      OUTPUT_LOAD='(1.0,-1.0)';
      PINUSE='BI';
    'MBA_CHECK1':
      PIN_NUMBER='(0,AK62,0,0,0,0,0,0,0,0,0,0,0,0,0,0,0,0,0,0,0,0,0,0,0,0,0,0,0,~
0,0,0,0,0,0,0,0,0,0,0)';
      BIDIRECTIONAL='TRUE';
      INPUT_LOAD='(-0.01,0.01)';
      OUTPUT_LOAD='(1.0,-1.0)';
      PINUSE='BI';
    'MBB_DQS_H9':
      PIN_NUMBER='(0,BV63,0,0,0,0,0,0,0,0,0,0,0,0,0,0,0,0,0,0,0,0,0,0,0,0,0,0,0,~
0,0,0,0,0,0,0,0,0,0,0)';
      BIDIRECTIONAL='TRUE';
      INPUT_LOAD='(-0.01,0.01)';
      OUTPUT_LOAD='(1.0,-1.0)';
      PINUSE='BI';
    'MBA_PAR':
      PIN_NUMBER='(0,BC62,0,0,0,0,0,0,0,0,0,0,0,0,0,0,0,0,0,0,0,0,0,0,0,0,0,0,0,~
0,0,0,0,0,0,0,0,0,0,0)';
      OUTPUT_LOAD='(1.0,-1.0)';
      PINUSE='OUT';
    'MBB_PAR':
      PIN_NUMBER='(0,BL64,0,0,0,0,0,0,0,0,0,0,0,0,0,0,0,0,0,0,0,0,0,0,0,0,0,0,0,~
0,0,0,0,0,0,0,0,0,0,0)';
      OUTPUT_LOAD='(1.0,-1.0)';
      PINUSE='OUT';
    'MB0_CLK_H':
      PIN_NUMBER='(0,BC64,0,0,0,0,0,0,0,0,0,0,0,0,0,0,0,0,0,0,0,0,0,0,0,0,0,0,0,~
0,0,0,0,0,0,0,0,0,0,0)';
      OUTPUT_LOAD='(1.0,-1.0)';
      PINUSE='OUT';
    'MB0_CLK_L':
      PIN_NUMBER='(0,BD63,0,0,0,0,0,0,0,0,0,0,0,0,0,0,0,0,0,0,0,0,0,0,0,0,0,0,0,~
0,0,0,0,0,0,0,0,0,0,0)';
      OUTPUT_LOAD='(1.0,-1.0)';
      PINUSE='OUT';
    'MB1_CLK_H':
      PIN_NUMBER='(0,BF63,0,0,0,0,0,0,0,0,0,0,0,0,0,0,0,0,0,0,0,0,0,0,0,0,0,0,0,~
0,0,0,0,0,0,0,0,0,0,0)';
      OUTPUT_LOAD='(1.0,-1.0)';
      PINUSE='OUT';
    'MB1_CLK_L':
      PIN_NUMBER='(0,BG64,0,0,0,0,0,0,0,0,0,0,0,0,0,0,0,0,0,0,0,0,0,0,0,0,0,0,0,~
0,0,0,0,0,0,0,0,0,0,0)';
      OUTPUT_LOAD='(1.0,-1.0)';
      PINUSE='OUT';
    'MBB_DATA19':
      PIN_NUMBER='(0,CT62,0,0,0,0,0,0,0,0,0,0,0,0,0,0,0,0,0,0,0,0,0,0,0,0,0,0,0,~
0,0,0,0,0,0,0,0,0,0,0)';
      BIDIRECTIONAL='TRUE';
      INPUT_LOAD='(-0.01,0.01)';
      OUTPUT_LOAD='(1.0,-1.0)';
      PINUSE='BI';
    'MBA_DATA24':
      PIN_NUMBER='(0,AC64,0,0,0,0,0,0,0,0,0,0,0,0,0,0,0,0,0,0,0,0,0,0,0,0,0,0,0,~
0,0,0,0,0,0,0,0,0,0,0)';
      BIDIRECTIONAL='TRUE';
      INPUT_LOAD='(-0.01,0.01)';
      OUTPUT_LOAD='(1.0,-1.0)';
      PINUSE='BI';
    'MBB_DATA20':
      PIN_NUMBER='(0,CV63,0,0,0,0,0,0,0,0,0,0,0,0,0,0,0,0,0,0,0,0,0,0,0,0,0,0,0,~
0,0,0,0,0,0,0,0,0,0,0)';
      BIDIRECTIONAL='TRUE';
      INPUT_LOAD='(-0.01,0.01)';
      OUTPUT_LOAD='(1.0,-1.0)';
      PINUSE='BI';
    'TEST39B':
      PIN_NUMBER='(0,BF62,0,0,0,0,0,0,0,0,0,0,0,0,0,0,0,0,0,0,0,0,0,0,0,0,0,0,0,~
0,0,0,0,0,0,0,0,0,0,0)';
      OUTPUT_LOAD='(1.0,-1.0)';
      PINUSE='OUT';
    'MC_ALERT_L':
      PIN_NUMBER='(0,0,AT55,0,0,0,0,0,0,0,0,0,0,0,0,0,0,0,0,0,0,0,0,0,0,0,0,0,0,~
0,0,0,0,0,0,0,0,0,0,0)';
      INPUT_LOAD='(-0.01,0.01)';
      PINUSE='IN';
    'MC_RESET_L':
      PIN_NUMBER='(0,0,AU55,0,0,0,0,0,0,0,0,0,0,0,0,0,0,0,0,0,0,0,0,0,0,0,0,0,0,~
0,0,0,0,0,0,0,0,0,0,0)';
      OUTPUT_LOAD='(1.0,-1.0)';
      PINUSE='OUT';
    'MCB_DQS_H8':
      PIN_NUMBER='(0,0,DD55,0,0,0,0,0,0,0,0,0,0,0,0,0,0,0,0,0,0,0,0,0,0,0,0,0,0,~
0,0,0,0,0,0,0,0,0,0,0)';
      BIDIRECTIONAL='TRUE';
      INPUT_LOAD='(-0.01,0.01)';
      OUTPUT_LOAD='(1.0,-1.0)';
      PINUSE='BI';
    'MCB_DATA30':
      PIN_NUMBER='(0,0,DE57,0,0,0,0,0,0,0,0,0,0,0,0,0,0,0,0,0,0,0,0,0,0,0,0,0,0,~
0,0,0,0,0,0,0,0,0,0,0)';
      BIDIRECTIONAL='TRUE';
      INPUT_LOAD='(-0.01,0.01)';
      OUTPUT_LOAD='(1.0,-1.0)';
      PINUSE='BI';
    'MCB_DATA8':
      PIN_NUMBER='(0,0,CH56,0,0,0,0,0,0,0,0,0,0,0,0,0,0,0,0,0,0,0,0,0,0,0,0,0,0,~
0,0,0,0,0,0,0,0,0,0,0)';
      BIDIRECTIONAL='TRUE';
      INPUT_LOAD='(-0.01,0.01)';
      OUTPUT_LOAD='(1.0,-1.0)';
      PINUSE='BI';
    'MCB1_CS_L1':
      PIN_NUMBER='(0,0,BM56,0,0,0,0,0,0,0,0,0,0,0,0,0,0,0,0,0,0,0,0,0,0,0,0,0,0,~
0,0,0,0,0,0,0,0,0,0,0)';
      OUTPUT_LOAD='(1.0,-1.0)';
      PINUSE='OUT';
    'MCB0_CS_L1':
      PIN_NUMBER='(0,0,BN57,0,0,0,0,0,0,0,0,0,0,0,0,0,0,0,0,0,0,0,0,0,0,0,0,0,0,~
0,0,0,0,0,0,0,0,0,0,0)';
      OUTPUT_LOAD='(1.0,-1.0)';
      PINUSE='OUT';
    'MCA_DQS_L1':
      PIN_NUMBER='(0,0,P56,0,0,0,0,0,0,0,0,0,0,0,0,0,0,0,0,0,0,0,0,0,0,0,0,0,0,0~
,0,0,0,0,0,0,0,0,0,0)';
      BIDIRECTIONAL='TRUE';
      INPUT_LOAD='(-0.01,0.01)';
      OUTPUT_LOAD='(1.0,-1.0)';
      PINUSE='BI';
    'MCA_DATA25':
      PIN_NUMBER='(0,0,AD55,0,0,0,0,0,0,0,0,0,0,0,0,0,0,0,0,0,0,0,0,0,0,0,0,0,0,~
0,0,0,0,0,0,0,0,0,0,0)';
      BIDIRECTIONAL='TRUE';
      INPUT_LOAD='(-0.01,0.01)';
      OUTPUT_LOAD='(1.0,-1.0)';
      PINUSE='BI';
    'MCA_DATA14':
      PIN_NUMBER='(0,0,T56,0,0,0,0,0,0,0,0,0,0,0,0,0,0,0,0,0,0,0,0,0,0,0,0,0,0,0~
,0,0,0,0,0,0,0,0,0,0)';
      BIDIRECTIONAL='TRUE';
      INPUT_LOAD='(-0.01,0.01)';
      OUTPUT_LOAD='(1.0,-1.0)';
      PINUSE='BI';
    'MCA_DATA9':
      PIN_NUMBER='(0,0,M55,0,0,0,0,0,0,0,0,0,0,0,0,0,0,0,0,0,0,0,0,0,0,0,0,0,0,0~
,0,0,0,0,0,0,0,0,0,0)';
      BIDIRECTIONAL='TRUE';
      INPUT_LOAD='(-0.01,0.01)';
      OUTPUT_LOAD='(1.0,-1.0)';
      PINUSE='BI';
    'MCA_CHECK5':
      PIN_NUMBER='(0,0,AP55,0,0,0,0,0,0,0,0,0,0,0,0,0,0,0,0,0,0,0,0,0,0,0,0,0,0,~
0,0,0,0,0,0,0,0,0,0,0)';
      BIDIRECTIONAL='TRUE';
      INPUT_LOAD='(-0.01,0.01)';
      OUTPUT_LOAD='(1.0,-1.0)';
      PINUSE='BI';
    'MCB_DATA31':
      PIN_NUMBER='(0,0,DF55,0,0,0,0,0,0,0,0,0,0,0,0,0,0,0,0,0,0,0,0,0,0,0,0,0,0,~
0,0,0,0,0,0,0,0,0,0,0)';
      BIDIRECTIONAL='TRUE';
      INPUT_LOAD='(-0.01,0.01)';
      OUTPUT_LOAD='(1.0,-1.0)';
      PINUSE='BI';
    'MCB_DATA20':
      PIN_NUMBER='(0,0,CV56,0,0,0,0,0,0,0,0,0,0,0,0,0,0,0,0,0,0,0,0,0,0,0,0,0,0,~
0,0,0,0,0,0,0,0,0,0,0)';
      BIDIRECTIONAL='TRUE';
      INPUT_LOAD='(-0.01,0.01)';
      OUTPUT_LOAD='(1.0,-1.0)';
      PINUSE='BI';
    'MCB_DATA9':
      PIN_NUMBER='(0,0,CJ55,0,0,0,0,0,0,0,0,0,0,0,0,0,0,0,0,0,0,0,0,0,0,0,0,0,0,~
0,0,0,0,0,0,0,0,0,0,0)';
      BIDIRECTIONAL='TRUE';
      INPUT_LOAD='(-0.01,0.01)';
      OUTPUT_LOAD='(1.0,-1.0)';
      PINUSE='BI';
    'MCB_CHECK0':
      PIN_NUMBER='(0,0,BY56,0,0,0,0,0,0,0,0,0,0,0,0,0,0,0,0,0,0,0,0,0,0,0,0,0,0,~
0,0,0,0,0,0,0,0,0,0,0)';
      BIDIRECTIONAL='TRUE';
      INPUT_LOAD='(-0.01,0.01)';
      OUTPUT_LOAD='(1.0,-1.0)';
      PINUSE='BI';
    'MCA_DQS_L2':
      PIN_NUMBER='(0,0,Y56,0,0,0,0,0,0,0,0,0,0,0,0,0,0,0,0,0,0,0,0,0,0,0,0,0,0,0~
,0,0,0,0,0,0,0,0,0,0)';
      BIDIRECTIONAL='TRUE';
      INPUT_LOAD='(-0.01,0.01)';
      OUTPUT_LOAD='(1.0,-1.0)';
      PINUSE='BI';
    'MCA_DATA26':
      PIN_NUMBER='(0,0,AD56,0,0,0,0,0,0,0,0,0,0,0,0,0,0,0,0,0,0,0,0,0,0,0,0,0,0,~
0,0,0,0,0,0,0,0,0,0,0)';
      BIDIRECTIONAL='TRUE';
      INPUT_LOAD='(-0.01,0.01)';
      OUTPUT_LOAD='(1.0,-1.0)';
      PINUSE='BI';
    'MCA_DATA15':
      PIN_NUMBER='(0,0,U55,0,0,0,0,0,0,0,0,0,0,0,0,0,0,0,0,0,0,0,0,0,0,0,0,0,0,0~
,0,0,0,0,0,0,0,0,0,0)';
      BIDIRECTIONAL='TRUE';
      INPUT_LOAD='(-0.01,0.01)';
      OUTPUT_LOAD='(1.0,-1.0)';
      PINUSE='BI';
    'MCA_CHECK6':
      PIN_NUMBER='(0,0,AP56,0,0,0,0,0,0,0,0,0,0,0,0,0,0,0,0,0,0,0,0,0,0,0,0,0,0,~
0,0,0,0,0,0,0,0,0,0,0)';
      BIDIRECTIONAL='TRUE';
      INPUT_LOAD='(-0.01,0.01)';
      OUTPUT_LOAD='(1.0,-1.0)';
      PINUSE='BI';
    'MCA0_RSP_L':
      PIN_NUMBER='(0,0,BN55,0,0,0,0,0,0,0,0,0,0,0,0,0,0,0,0,0,0,0,0,0,0,0,0,0,0,~
0,0,0,0,0,0,0,0,0,0,0)';
      INPUT_LOAD='(-0.01,0.01)';
      PINUSE='IN';
    'MCB_DATA21':
      PIN_NUMBER='(0,0,CW55,0,0,0,0,0,0,0,0,0,0,0,0,0,0,0,0,0,0,0,0,0,0,0,0,0,0,~
0,0,0,0,0,0,0,0,0,0,0)';
      BIDIRECTIONAL='TRUE';
      INPUT_LOAD='(-0.01,0.01)';
      OUTPUT_LOAD='(1.0,-1.0)';
      PINUSE='BI';
    'MCB_DATA10':
      PIN_NUMBER='(0,0,CJ57,0,0,0,0,0,0,0,0,0,0,0,0,0,0,0,0,0,0,0,0,0,0,0,0,0,0,~
0,0,0,0,0,0,0,0,0,0,0)';
      BIDIRECTIONAL='TRUE';
      INPUT_LOAD='(-0.01,0.01)';
      OUTPUT_LOAD='(1.0,-1.0)';
      PINUSE='BI';
    'MCB_CHECK1':
      PIN_NUMBER='(0,0,CA55,0,0,0,0,0,0,0,0,0,0,0,0,0,0,0,0,0,0,0,0,0,0,0,0,0,0,~
0,0,0,0,0,0,0,0,0,0,0)';
      BIDIRECTIONAL='TRUE';
      INPUT_LOAD='(-0.01,0.01)';
      OUTPUT_LOAD='(1.0,-1.0)';
      PINUSE='BI';
    'MCA_DQS_L3':
      PIN_NUMBER='(0,0,AF56,0,0,0,0,0,0,0,0,0,0,0,0,0,0,0,0,0,0,0,0,0,0,0,0,0,0,~
0,0,0,0,0,0,0,0,0,0,0)';
      BIDIRECTIONAL='TRUE';
      INPUT_LOAD='(-0.01,0.01)';
      OUTPUT_LOAD='(1.0,-1.0)';
      PINUSE='BI';
    'MCA_DATA27':
      PIN_NUMBER='(0,0,AE55,0,0,0,0,0,0,0,0,0,0,0,0,0,0,0,0,0,0,0,0,0,0,0,0,0,0,~
0,0,0,0,0,0,0,0,0,0,0)';
      BIDIRECTIONAL='TRUE';
      INPUT_LOAD='(-0.01,0.01)';
      OUTPUT_LOAD='(1.0,-1.0)';
      PINUSE='BI';
    'MCA_DATA16':
      PIN_NUMBER='(0,0,U57,0,0,0,0,0,0,0,0,0,0,0,0,0,0,0,0,0,0,0,0,0,0,0,0,0,0,0~
,0,0,0,0,0,0,0,0,0,0)';
      BIDIRECTIONAL='TRUE';
      INPUT_LOAD='(-0.01,0.01)';
      OUTPUT_LOAD='(1.0,-1.0)';
      PINUSE='BI';
    'MCA_CHECK7':
      PIN_NUMBER='(0,0,AR55,0,0,0,0,0,0,0,0,0,0,0,0,0,0,0,0,0,0,0,0,0,0,0,0,0,0,~
0,0,0,0,0,0,0,0,0,0,0)';
      BIDIRECTIONAL='TRUE';
      INPUT_LOAD='(-0.01,0.01)';
      OUTPUT_LOAD='(1.0,-1.0)';
      PINUSE='BI';
    'MCA1_RSP_L':
      PIN_NUMBER='(0,0,BP55,0,0,0,0,0,0,0,0,0,0,0,0,0,0,0,0,0,0,0,0,0,0,0,0,0,0,~
0,0,0,0,0,0,0,0,0,0,0)';
      INPUT_LOAD='(-0.01,0.01)';
      PINUSE='IN';
    'MCB_DATA22':
      PIN_NUMBER='(0,0,CW57,0,0,0,0,0,0,0,0,0,0,0,0,0,0,0,0,0,0,0,0,0,0,0,0,0,0,~
0,0,0,0,0,0,0,0,0,0,0)';
      BIDIRECTIONAL='TRUE';
      INPUT_LOAD='(-0.01,0.01)';
      OUTPUT_LOAD='(1.0,-1.0)';
      PINUSE='BI';
    'MCB_DATA11':
      PIN_NUMBER='(0,0,CK55,0,0,0,0,0,0,0,0,0,0,0,0,0,0,0,0,0,0,0,0,0,0,0,0,0,0,~
0,0,0,0,0,0,0,0,0,0,0)';
      BIDIRECTIONAL='TRUE';
      INPUT_LOAD='(-0.01,0.01)';
      OUTPUT_LOAD='(1.0,-1.0)';
      PINUSE='BI';
    'MCB_CHECK2':
      PIN_NUMBER='(0,0,CA57,0,0,0,0,0,0,0,0,0,0,0,0,0,0,0,0,0,0,0,0,0,0,0,0,0,0,~
0,0,0,0,0,0,0,0,0,0,0)';
      BIDIRECTIONAL='TRUE';
      INPUT_LOAD='(-0.01,0.01)';
      OUTPUT_LOAD='(1.0,-1.0)';
      PINUSE='BI';
    'MCA_DQS_L4':
      PIN_NUMBER='(0,0,AM56,0,0,0,0,0,0,0,0,0,0,0,0,0,0,0,0,0,0,0,0,0,0,0,0,0,0,~
0,0,0,0,0,0,0,0,0,0,0)';
      BIDIRECTIONAL='TRUE';
      INPUT_LOAD='(-0.01,0.01)';
      OUTPUT_LOAD='(1.0,-1.0)';
      PINUSE='BI';
    'MCA_DQS_H0':
      PIN_NUMBER='(0,0,G57,0,0,0,0,0,0,0,0,0,0,0,0,0,0,0,0,0,0,0,0,0,0,0,0,0,0,0~
,0,0,0,0,0,0,0,0,0,0)';
      BIDIRECTIONAL='TRUE';
      INPUT_LOAD='(-0.01,0.01)';
      OUTPUT_LOAD='(1.0,-1.0)';
      PINUSE='BI';
    'MCA_DATA28':
      PIN_NUMBER='(0,0,AG57,0,0,0,0,0,0,0,0,0,0,0,0,0,0,0,0,0,0,0,0,0,0,0,0,0,0,~
0,0,0,0,0,0,0,0,0,0,0)';
      BIDIRECTIONAL='TRUE';
      INPUT_LOAD='(-0.01,0.01)';
      OUTPUT_LOAD='(1.0,-1.0)';
      PINUSE='BI';
    'MCA_DATA17':
      PIN_NUMBER='(0,0,V55,0,0,0,0,0,0,0,0,0,0,0,0,0,0,0,0,0,0,0,0,0,0,0,0,0,0,0~
,0,0,0,0,0,0,0,0,0,0)';
      BIDIRECTIONAL='TRUE';
      INPUT_LOAD='(-0.01,0.01)';
      OUTPUT_LOAD='(1.0,-1.0)';
      PINUSE='BI';
    'MCB_DATA23':
      PIN_NUMBER='(0,0,CY55,0,0,0,0,0,0,0,0,0,0,0,0,0,0,0,0,0,0,0,0,0,0,0,0,0,0,~
0,0,0,0,0,0,0,0,0,0,0)';
      BIDIRECTIONAL='TRUE';
      INPUT_LOAD='(-0.01,0.01)';
      OUTPUT_LOAD='(1.0,-1.0)';
      PINUSE='BI';
    'MCB_DATA12':
      PIN_NUMBER='(0,0,CM56,0,0,0,0,0,0,0,0,0,0,0,0,0,0,0,0,0,0,0,0,0,0,0,0,0,0,~
0,0,0,0,0,0,0,0,0,0,0)';
      BIDIRECTIONAL='TRUE';
      INPUT_LOAD='(-0.01,0.01)';
      OUTPUT_LOAD='(1.0,-1.0)';
      PINUSE='BI';
    'MCB_CHECK3':
      PIN_NUMBER='(0,0,CB55,0,0,0,0,0,0,0,0,0,0,0,0,0,0,0,0,0,0,0,0,0,0,0,0,0,0,~
0,0,0,0,0,0,0,0,0,0,0)';
      BIDIRECTIONAL='TRUE';
      INPUT_LOAD='(-0.01,0.01)';
      OUTPUT_LOAD='(1.0,-1.0)';
      PINUSE='BI';
    'MCA_DQS_L5':
      PIN_NUMBER='(0,0,H55,0,0,0,0,0,0,0,0,0,0,0,0,0,0,0,0,0,0,0,0,0,0,0,0,0,0,0~
,0,0,0,0,0,0,0,0,0,0)';
      BIDIRECTIONAL='TRUE';
      INPUT_LOAD='(-0.01,0.01)';
      OUTPUT_LOAD='(1.0,-1.0)';
      PINUSE='BI';
    'MCA_DQS_H1':
      PIN_NUMBER='(0,0,N57,0,0,0,0,0,0,0,0,0,0,0,0,0,0,0,0,0,0,0,0,0,0,0,0,0,0,0~
,0,0,0,0,0,0,0,0,0,0)';
      BIDIRECTIONAL='TRUE';
      INPUT_LOAD='(-0.01,0.01)';
      OUTPUT_LOAD='(1.0,-1.0)';
      PINUSE='BI';
    'MCA_DATA29':
      PIN_NUMBER='(0,0,AH55,0,0,0,0,0,0,0,0,0,0,0,0,0,0,0,0,0,0,0,0,0,0,0,0,0,0,~
0,0,0,0,0,0,0,0,0,0,0)';
      BIDIRECTIONAL='TRUE';
      INPUT_LOAD='(-0.01,0.01)';
      OUTPUT_LOAD='(1.0,-1.0)';
      PINUSE='BI';
    'MCA_DATA18':
      PIN_NUMBER='(0,0,V56,0,0,0,0,0,0,0,0,0,0,0,0,0,0,0,0,0,0,0,0,0,0,0,0,0,0,0~
,0,0,0,0,0,0,0,0,0,0)';
      BIDIRECTIONAL='TRUE';
      INPUT_LOAD='(-0.01,0.01)';
      OUTPUT_LOAD='(1.0,-1.0)';
      PINUSE='BI';
    'MCB_DQS_L0':
      PIN_NUMBER='(0,0,CE57,0,0,0,0,0,0,0,0,0,0,0,0,0,0,0,0,0,0,0,0,0,0,0,0,0,0,~
0,0,0,0,0,0,0,0,0,0,0)';
      BIDIRECTIONAL='TRUE';
      INPUT_LOAD='(-0.01,0.01)';
      OUTPUT_LOAD='(1.0,-1.0)';
      PINUSE='BI';
    'MCB_DATA24':
      PIN_NUMBER='(0,0,CY56,0,0,0,0,0,0,0,0,0,0,0,0,0,0,0,0,0,0,0,0,0,0,0,0,0,0,~
0,0,0,0,0,0,0,0,0,0,0)';
      BIDIRECTIONAL='TRUE';
      INPUT_LOAD='(-0.01,0.01)';
      OUTPUT_LOAD='(1.0,-1.0)';
      PINUSE='BI';
    'MCB_DATA13':
      PIN_NUMBER='(0,0,CN55,0,0,0,0,0,0,0,0,0,0,0,0,0,0,0,0,0,0,0,0,0,0,0,0,0,0,~
0,0,0,0,0,0,0,0,0,0,0)';
      BIDIRECTIONAL='TRUE';
      INPUT_LOAD='(-0.01,0.01)';
      OUTPUT_LOAD='(1.0,-1.0)';
      PINUSE='BI';
    'MCB_CHECK4':
      PIN_NUMBER='(0,0,BT56,0,0,0,0,0,0,0,0,0,0,0,0,0,0,0,0,0,0,0,0,0,0,0,0,0,0,~
0,0,0,0,0,0,0,0,0,0,0)';
      BIDIRECTIONAL='TRUE';
      INPUT_LOAD='(-0.01,0.01)';
      OUTPUT_LOAD='(1.0,-1.0)';
      PINUSE='BI';
    'MCA_DQS_L6':
      PIN_NUMBER='(0,0,P55,0,0,0,0,0,0,0,0,0,0,0,0,0,0,0,0,0,0,0,0,0,0,0,0,0,0,0~
,0,0,0,0,0,0,0,0,0,0)';
      BIDIRECTIONAL='TRUE';
      INPUT_LOAD='(-0.01,0.01)';
      OUTPUT_LOAD='(1.0,-1.0)';
      PINUSE='BI';
    'MCA_DQS_H2':
      PIN_NUMBER='(0,0,W57,0,0,0,0,0,0,0,0,0,0,0,0,0,0,0,0,0,0,0,0,0,0,0,0,0,0,0~
,0,0,0,0,0,0,0,0,0,0)';
      BIDIRECTIONAL='TRUE';
      INPUT_LOAD='(-0.01,0.01)';
      OUTPUT_LOAD='(1.0,-1.0)';
      PINUSE='BI';
    'MCA_DATA19':
      PIN_NUMBER='(0,0,W55,0,0,0,0,0,0,0,0,0,0,0,0,0,0,0,0,0,0,0,0,0,0,0,0,0,0,0~
,0,0,0,0,0,0,0,0,0,0)';
      BIDIRECTIONAL='TRUE';
      INPUT_LOAD='(-0.01,0.01)';
      OUTPUT_LOAD='(1.0,-1.0)';
      PINUSE='BI';
    'MCB_DQS_L1':
      PIN_NUMBER='(0,0,CL57,0,0,0,0,0,0,0,0,0,0,0,0,0,0,0,0,0,0,0,0,0,0,0,0,0,0,~
0,0,0,0,0,0,0,0,0,0,0)';
      BIDIRECTIONAL='TRUE';
      INPUT_LOAD='(-0.01,0.01)';
      OUTPUT_LOAD='(1.0,-1.0)';
      PINUSE='BI';
    'MCB_DATA25':
      PIN_NUMBER='(0,0,DA55,0,0,0,0,0,0,0,0,0,0,0,0,0,0,0,0,0,0,0,0,0,0,0,0,0,0,~
0,0,0,0,0,0,0,0,0,0,0)';
      BIDIRECTIONAL='TRUE';
      INPUT_LOAD='(-0.01,0.01)';
      OUTPUT_LOAD='(1.0,-1.0)';
      PINUSE='BI';
    'MCB_DATA14':
      PIN_NUMBER='(0,0,CN57,0,0,0,0,0,0,0,0,0,0,0,0,0,0,0,0,0,0,0,0,0,0,0,0,0,0,~
0,0,0,0,0,0,0,0,0,0,0)';
      BIDIRECTIONAL='TRUE';
      INPUT_LOAD='(-0.01,0.01)';
      OUTPUT_LOAD='(1.0,-1.0)';
      PINUSE='BI';
    'MCB_CHECK5':
      PIN_NUMBER='(0,0,BU55,0,0,0,0,0,0,0,0,0,0,0,0,0,0,0,0,0,0,0,0,0,0,0,0,0,0,~
0,0,0,0,0,0,0,0,0,0,0)';
      BIDIRECTIONAL='TRUE';
      INPUT_LOAD='(-0.01,0.01)';
      OUTPUT_LOAD='(1.0,-1.0)';
      PINUSE='BI';
    'MCA_DQS_L7':
      PIN_NUMBER='(0,0,Y55,0,0,0,0,0,0,0,0,0,0,0,0,0,0,0,0,0,0,0,0,0,0,0,0,0,0,0~
,0,0,0,0,0,0,0,0,0,0)';
      BIDIRECTIONAL='TRUE';
      INPUT_LOAD='(-0.01,0.01)';
      OUTPUT_LOAD='(1.0,-1.0)';
      PINUSE='BI';
    'MCA_DQS_H3':
      PIN_NUMBER='(0,0,AE57,0,0,0,0,0,0,0,0,0,0,0,0,0,0,0,0,0,0,0,0,0,0,0,0,0,0,~
0,0,0,0,0,0,0,0,0,0,0)';
      BIDIRECTIONAL='TRUE';
      INPUT_LOAD='(-0.01,0.01)';
      OUTPUT_LOAD='(1.0,-1.0)';
      PINUSE='BI';
    'MCB_DQS_L2':
      PIN_NUMBER='(0,0,CU57,0,0,0,0,0,0,0,0,0,0,0,0,0,0,0,0,0,0,0,0,0,0,0,0,0,0,~
0,0,0,0,0,0,0,0,0,0,0)';
      BIDIRECTIONAL='TRUE';
      INPUT_LOAD='(-0.01,0.01)';
      OUTPUT_LOAD='(1.0,-1.0)';
      PINUSE='BI';
    'MCB_DATA26':
      PIN_NUMBER='(0,0,DA57,0,0,0,0,0,0,0,0,0,0,0,0,0,0,0,0,0,0,0,0,0,0,0,0,0,0,~
0,0,0,0,0,0,0,0,0,0,0)';
      BIDIRECTIONAL='TRUE';
      INPUT_LOAD='(-0.01,0.01)';
      OUTPUT_LOAD='(1.0,-1.0)';
      PINUSE='BI';
    'MCB_DATA15':
      PIN_NUMBER='(0,0,CP55,0,0,0,0,0,0,0,0,0,0,0,0,0,0,0,0,0,0,0,0,0,0,0,0,0,0,~
0,0,0,0,0,0,0,0,0,0,0)';
      BIDIRECTIONAL='TRUE';
      INPUT_LOAD='(-0.01,0.01)';
      OUTPUT_LOAD='(1.0,-1.0)';
      PINUSE='BI';
    'MCB_CHECK6':
      PIN_NUMBER='(0,0,BU57,0,0,0,0,0,0,0,0,0,0,0,0,0,0,0,0,0,0,0,0,0,0,0,0,0,0,~
0,0,0,0,0,0,0,0,0,0,0)';
      BIDIRECTIONAL='TRUE';
      INPUT_LOAD='(-0.01,0.01)';
      OUTPUT_LOAD='(1.0,-1.0)';
      PINUSE='BI';
    'MCA_DQS_L8':
      PIN_NUMBER='(0,0,AF55,0,0,0,0,0,0,0,0,0,0,0,0,0,0,0,0,0,0,0,0,0,0,0,0,0,0,~
0,0,0,0,0,0,0,0,0,0,0)';
      BIDIRECTIONAL='TRUE';
      INPUT_LOAD='(-0.01,0.01)';
      OUTPUT_LOAD='(1.0,-1.0)';
      PINUSE='BI';
    'MCA_DQS_H4':
      PIN_NUMBER='(0,0,AL57,0,0,0,0,0,0,0,0,0,0,0,0,0,0,0,0,0,0,0,0,0,0,0,0,0,0,~
0,0,0,0,0,0,0,0,0,0,0)';
      BIDIRECTIONAL='TRUE';
      INPUT_LOAD='(-0.01,0.01)';
      OUTPUT_LOAD='(1.0,-1.0)';
      PINUSE='BI';
    'MCA_CA0':
      PIN_NUMBER='(0,0,AW57,0,0,0,0,0,0,0,0,0,0,0,0,0,0,0,0,0,0,0,0,0,0,0,0,0,0,~
0,0,0,0,0,0,0,0,0,0,0)';
      OUTPUT_LOAD='(1.0,-1.0)';
      PINUSE='OUT';
    'MCB_DQS_L3':
      PIN_NUMBER='(0,0,DC57,0,0,0,0,0,0,0,0,0,0,0,0,0,0,0,0,0,0,0,0,0,0,0,0,0,0,~
0,0,0,0,0,0,0,0,0,0,0)';
      BIDIRECTIONAL='TRUE';
      INPUT_LOAD='(-0.01,0.01)';
      OUTPUT_LOAD='(1.0,-1.0)';
      PINUSE='BI';
    'MCB_DATA27':
      PIN_NUMBER='(0,0,DB55,0,0,0,0,0,0,0,0,0,0,0,0,0,0,0,0,0,0,0,0,0,0,0,0,0,0,~
0,0,0,0,0,0,0,0,0,0,0)';
      BIDIRECTIONAL='TRUE';
      INPUT_LOAD='(-0.01,0.01)';
      OUTPUT_LOAD='(1.0,-1.0)';
      PINUSE='BI';
    'MCB_DATA16':
      PIN_NUMBER='(0,0,CP56,0,0,0,0,0,0,0,0,0,0,0,0,0,0,0,0,0,0,0,0,0,0,0,0,0,0,~
0,0,0,0,0,0,0,0,0,0,0)';
      BIDIRECTIONAL='TRUE';
      INPUT_LOAD='(-0.01,0.01)';
      OUTPUT_LOAD='(1.0,-1.0)';
      PINUSE='BI';
    'MCB_CHECK7':
      PIN_NUMBER='(0,0,BV55,0,0,0,0,0,0,0,0,0,0,0,0,0,0,0,0,0,0,0,0,0,0,0,0,0,0,~
0,0,0,0,0,0,0,0,0,0,0)';
      BIDIRECTIONAL='TRUE';
      INPUT_LOAD='(-0.01,0.01)';
      OUTPUT_LOAD='(1.0,-1.0)';
      PINUSE='BI';
    'MCB_CA0':
      PIN_NUMBER='(0,0,BG55,0,0,0,0,0,0,0,0,0,0,0,0,0,0,0,0,0,0,0,0,0,0,0,0,0,0,~
0,0,0,0,0,0,0,0,0,0,0)';
      OUTPUT_LOAD='(1.0,-1.0)';
      PINUSE='OUT';
    'MCB1_RSP_L':
      PIN_NUMBER='(0,0,BR57,0,0,0,0,0,0,0,0,0,0,0,0,0,0,0,0,0,0,0,0,0,0,0,0,0,0,~
0,0,0,0,0,0,0,0,0,0,0)';
      INPUT_LOAD='(-0.01,0.01)';
      PINUSE='IN';
    'MCB0_RSP_L':
      PIN_NUMBER='(0,0,BP56,0,0,0,0,0,0,0,0,0,0,0,0,0,0,0,0,0,0,0,0,0,0,0,0,0,0,~
0,0,0,0,0,0,0,0,0,0,0)';
      INPUT_LOAD='(-0.01,0.01)';
      PINUSE='IN';
    'MCA_DQS_L9':
      PIN_NUMBER='(0,0,AM55,0,0,0,0,0,0,0,0,0,0,0,0,0,0,0,0,0,0,0,0,0,0,0,0,0,0,~
0,0,0,0,0,0,0,0,0,0,0)';
      BIDIRECTIONAL='TRUE';
      INPUT_LOAD='(-0.01,0.01)';
      OUTPUT_LOAD='(1.0,-1.0)';
      PINUSE='BI';
    'MCA_DQS_H5':
      PIN_NUMBER='(0,0,J55,0,0,0,0,0,0,0,0,0,0,0,0,0,0,0,0,0,0,0,0,0,0,0,0,0,0,0~
,0,0,0,0,0,0,0,0,0,0)';
      BIDIRECTIONAL='TRUE';
      INPUT_LOAD='(-0.01,0.01)';
      OUTPUT_LOAD='(1.0,-1.0)';
      PINUSE='BI';
    'MCA_DATA0':
      PIN_NUMBER='(0,0,E57,0,0,0,0,0,0,0,0,0,0,0,0,0,0,0,0,0,0,0,0,0,0,0,0,0,0,0~
,0,0,0,0,0,0,0,0,0,0)';
      BIDIRECTIONAL='TRUE';
      INPUT_LOAD='(-0.01,0.01)';
      OUTPUT_LOAD='(1.0,-1.0)';
      PINUSE='BI';
    'MCA_CA1':
      PIN_NUMBER='(0,0,AY56,0,0,0,0,0,0,0,0,0,0,0,0,0,0,0,0,0,0,0,0,0,0,0,0,0,0,~
0,0,0,0,0,0,0,0,0,0,0)';
      OUTPUT_LOAD='(1.0,-1.0)';
      PINUSE='OUT';
    'MCB_DQS_L4':
      PIN_NUMBER='(0,0,BW55,0,0,0,0,0,0,0,0,0,0,0,0,0,0,0,0,0,0,0,0,0,0,0,0,0,0,~
0,0,0,0,0,0,0,0,0,0,0)';
      BIDIRECTIONAL='TRUE';
      INPUT_LOAD='(-0.01,0.01)';
      OUTPUT_LOAD='(1.0,-1.0)';
      PINUSE='BI';
    'MCB_DQS_H0':
      PIN_NUMBER='(0,0,CD56,0,0,0,0,0,0,0,0,0,0,0,0,0,0,0,0,0,0,0,0,0,0,0,0,0,0,~
0,0,0,0,0,0,0,0,0,0,0)';
      BIDIRECTIONAL='TRUE';
      INPUT_LOAD='(-0.01,0.01)';
      OUTPUT_LOAD='(1.0,-1.0)';
      PINUSE='BI';
    'MCB_DATA28':
      PIN_NUMBER='(0,0,DD56,0,0,0,0,0,0,0,0,0,0,0,0,0,0,0,0,0,0,0,0,0,0,0,0,0,0,~
0,0,0,0,0,0,0,0,0,0,0)';
      BIDIRECTIONAL='TRUE';
      INPUT_LOAD='(-0.01,0.01)';
      OUTPUT_LOAD='(1.0,-1.0)';
      PINUSE='BI';
    'MCB_DATA17':
      PIN_NUMBER='(0,0,CR55,0,0,0,0,0,0,0,0,0,0,0,0,0,0,0,0,0,0,0,0,0,0,0,0,0,0,~
0,0,0,0,0,0,0,0,0,0,0)';
      BIDIRECTIONAL='TRUE';
      INPUT_LOAD='(-0.01,0.01)';
      OUTPUT_LOAD='(1.0,-1.0)';
      PINUSE='BI';
    'MCB_DATA0':
      PIN_NUMBER='(0,0,CB56,0,0,0,0,0,0,0,0,0,0,0,0,0,0,0,0,0,0,0,0,0,0,0,0,0,0,~
0,0,0,0,0,0,0,0,0,0,0)';
      BIDIRECTIONAL='TRUE';
      INPUT_LOAD='(-0.01,0.01)';
      OUTPUT_LOAD='(1.0,-1.0)';
      PINUSE='BI';
    'MCB_CA1':
      PIN_NUMBER='(0,0,BH55,0,0,0,0,0,0,0,0,0,0,0,0,0,0,0,0,0,0,0,0,0,0,0,0,0,0,~
0,0,0,0,0,0,0,0,0,0,0)';
      OUTPUT_LOAD='(1.0,-1.0)';
      PINUSE='OUT';
    'MCA_DQS_H6':
      PIN_NUMBER='(0,0,R55,0,0,0,0,0,0,0,0,0,0,0,0,0,0,0,0,0,0,0,0,0,0,0,0,0,0,0~
,0,0,0,0,0,0,0,0,0,0)';
      BIDIRECTIONAL='TRUE';
      INPUT_LOAD='(-0.01,0.01)';
      OUTPUT_LOAD='(1.0,-1.0)';
      PINUSE='BI';
    'MCA_DATA1':
      PIN_NUMBER='(0,0,F55,0,0,0,0,0,0,0,0,0,0,0,0,0,0,0,0,0,0,0,0,0,0,0,0,0,0,0~
,0,0,0,0,0,0,0,0,0,0)';
      BIDIRECTIONAL='TRUE';
      INPUT_LOAD='(-0.01,0.01)';
      OUTPUT_LOAD='(1.0,-1.0)';
      PINUSE='BI';
    'MCA_CA2':
      PIN_NUMBER='(0,0,AY55,0,0,0,0,0,0,0,0,0,0,0,0,0,0,0,0,0,0,0,0,0,0,0,0,0,0,~
0,0,0,0,0,0,0,0,0,0,0)';
      OUTPUT_LOAD='(1.0,-1.0)';
      PINUSE='OUT';
    'MCA0_CS_L0':
      PIN_NUMBER='(0,0,AV56,0,0,0,0,0,0,0,0,0,0,0,0,0,0,0,0,0,0,0,0,0,0,0,0,0,0,~
0,0,0,0,0,0,0,0,0,0,0)';
      OUTPUT_LOAD='(1.0,-1.0)';
      PINUSE='OUT';
    'MCB_DQS_L5':
      PIN_NUMBER='(0,0,CE55,0,0,0,0,0,0,0,0,0,0,0,0,0,0,0,0,0,0,0,0,0,0,0,0,0,0,~
0,0,0,0,0,0,0,0,0,0,0)';
      BIDIRECTIONAL='TRUE';
      INPUT_LOAD='(-0.01,0.01)';
      OUTPUT_LOAD='(1.0,-1.0)';
      PINUSE='BI';
    'MCB_DQS_H1':
      PIN_NUMBER='(0,0,CK56,0,0,0,0,0,0,0,0,0,0,0,0,0,0,0,0,0,0,0,0,0,0,0,0,0,0,~
0,0,0,0,0,0,0,0,0,0,0)';
      BIDIRECTIONAL='TRUE';
      INPUT_LOAD='(-0.01,0.01)';
      OUTPUT_LOAD='(1.0,-1.0)';
      PINUSE='BI';
    'MCB_DATA29':
      PIN_NUMBER='(0,0,DE55,0,0,0,0,0,0,0,0,0,0,0,0,0,0,0,0,0,0,0,0,0,0,0,0,0,0,~
0,0,0,0,0,0,0,0,0,0,0)';
      BIDIRECTIONAL='TRUE';
      INPUT_LOAD='(-0.01,0.01)';
      OUTPUT_LOAD='(1.0,-1.0)';
      PINUSE='BI';
    'MCB_DATA18':
      PIN_NUMBER='(0,0,CR57,0,0,0,0,0,0,0,0,0,0,0,0,0,0,0,0,0,0,0,0,0,0,0,0,0,0,~
0,0,0,0,0,0,0,0,0,0,0)';
      BIDIRECTIONAL='TRUE';
      INPUT_LOAD='(-0.01,0.01)';
      OUTPUT_LOAD='(1.0,-1.0)';
      PINUSE='BI';
    'MCB_DATA1':
      PIN_NUMBER='(0,0,CC55,0,0,0,0,0,0,0,0,0,0,0,0,0,0,0,0,0,0,0,0,0,0,0,0,0,0,~
0,0,0,0,0,0,0,0,0,0,0)';
      BIDIRECTIONAL='TRUE';
      INPUT_LOAD='(-0.01,0.01)';
      OUTPUT_LOAD='(1.0,-1.0)';
      PINUSE='BI';
    'MCB_CA2':
      PIN_NUMBER='(0,0,BH56,0,0,0,0,0,0,0,0,0,0,0,0,0,0,0,0,0,0,0,0,0,0,0,0,0,0,~
0,0,0,0,0,0,0,0,0,0,0)';
      OUTPUT_LOAD='(1.0,-1.0)';
      PINUSE='OUT';
    'MCA_DQS_H7':
      PIN_NUMBER='(0,0,AA55,0,0,0,0,0,0,0,0,0,0,0,0,0,0,0,0,0,0,0,0,0,0,0,0,0,0,~
0,0,0,0,0,0,0,0,0,0,0)';
      BIDIRECTIONAL='TRUE';
      INPUT_LOAD='(-0.01,0.01)';
      OUTPUT_LOAD='(1.0,-1.0)';
      PINUSE='BI';
    'MCA_DATA2':
      PIN_NUMBER='(0,0,F56,0,0,0,0,0,0,0,0,0,0,0,0,0,0,0,0,0,0,0,0,0,0,0,0,0,0,0~
,0,0,0,0,0,0,0,0,0,0)';
      BIDIRECTIONAL='TRUE';
      INPUT_LOAD='(-0.01,0.01)';
      OUTPUT_LOAD='(1.0,-1.0)';
      PINUSE='BI';
    'MCA_CA3':
      PIN_NUMBER='(0,0,BA55,0,0,0,0,0,0,0,0,0,0,0,0,0,0,0,0,0,0,0,0,0,0,0,0,0,0,~
0,0,0,0,0,0,0,0,0,0,0)';
      OUTPUT_LOAD='(1.0,-1.0)';
      PINUSE='OUT';
    'MCA1_CS_L0':
      PIN_NUMBER='(0,0,AU57,0,0,0,0,0,0,0,0,0,0,0,0,0,0,0,0,0,0,0,0,0,0,0,0,0,0,~
0,0,0,0,0,0,0,0,0,0,0)';
      OUTPUT_LOAD='(1.0,-1.0)';
      PINUSE='OUT';
    'MCA0_CS_L1':
      PIN_NUMBER='(0,0,AW55,0,0,0,0,0,0,0,0,0,0,0,0,0,0,0,0,0,0,0,0,0,0,0,0,0,0,~
0,0,0,0,0,0,0,0,0,0,0)';
      OUTPUT_LOAD='(1.0,-1.0)';
      PINUSE='OUT';
    'MCB_DQS_L6':
      PIN_NUMBER='(0,0,CL55,0,0,0,0,0,0,0,0,0,0,0,0,0,0,0,0,0,0,0,0,0,0,0,0,0,0,~
0,0,0,0,0,0,0,0,0,0,0)';
      BIDIRECTIONAL='TRUE';
      INPUT_LOAD='(-0.01,0.01)';
      OUTPUT_LOAD='(1.0,-1.0)';
      PINUSE='BI';
    'MCB_DQS_H2':
      PIN_NUMBER='(0,0,CT56,0,0,0,0,0,0,0,0,0,0,0,0,0,0,0,0,0,0,0,0,0,0,0,0,0,0,~
0,0,0,0,0,0,0,0,0,0,0)';
      BIDIRECTIONAL='TRUE';
      INPUT_LOAD='(-0.01,0.01)';
      OUTPUT_LOAD='(1.0,-1.0)';
      PINUSE='BI';
    'MCB_DATA19':
      PIN_NUMBER='(0,0,CT55,0,0,0,0,0,0,0,0,0,0,0,0,0,0,0,0,0,0,0,0,0,0,0,0,0,0,~
0,0,0,0,0,0,0,0,0,0,0)';
      BIDIRECTIONAL='TRUE';
      INPUT_LOAD='(-0.01,0.01)';
      OUTPUT_LOAD='(1.0,-1.0)';
      PINUSE='BI';
    'MCB_DATA2':
      PIN_NUMBER='(0,0,CC57,0,0,0,0,0,0,0,0,0,0,0,0,0,0,0,0,0,0,0,0,0,0,0,0,0,0,~
0,0,0,0,0,0,0,0,0,0,0)';
      BIDIRECTIONAL='TRUE';
      INPUT_LOAD='(-0.01,0.01)';
      OUTPUT_LOAD='(1.0,-1.0)';
      PINUSE='BI';
    'MCB_CA3':
      PIN_NUMBER='(0,0,BJ57,0,0,0,0,0,0,0,0,0,0,0,0,0,0,0,0,0,0,0,0,0,0,0,0,0,0,~
0,0,0,0,0,0,0,0,0,0,0)';
      OUTPUT_LOAD='(1.0,-1.0)';
      PINUSE='OUT';
    'MCA_DQS_H8':
      PIN_NUMBER='(0,0,AG55,0,0,0,0,0,0,0,0,0,0,0,0,0,0,0,0,0,0,0,0,0,0,0,0,0,0,~
0,0,0,0,0,0,0,0,0,0,0)';
      BIDIRECTIONAL='TRUE';
      INPUT_LOAD='(-0.01,0.01)';
      OUTPUT_LOAD='(1.0,-1.0)';
      PINUSE='BI';
    'MCA_DATA30':
      PIN_NUMBER='(0,0,AH56,0,0,0,0,0,0,0,0,0,0,0,0,0,0,0,0,0,0,0,0,0,0,0,0,0,0,~
0,0,0,0,0,0,0,0,0,0,0)';
      BIDIRECTIONAL='TRUE';
      INPUT_LOAD='(-0.01,0.01)';
      OUTPUT_LOAD='(1.0,-1.0)';
      PINUSE='BI';
    'MCA_DATA3':
      PIN_NUMBER='(0,0,G55,0,0,0,0,0,0,0,0,0,0,0,0,0,0,0,0,0,0,0,0,0,0,0,0,0,0,0~
,0,0,0,0,0,0,0,0,0,0)';
      BIDIRECTIONAL='TRUE';
      INPUT_LOAD='(-0.01,0.01)';
      OUTPUT_LOAD='(1.0,-1.0)';
      PINUSE='BI';
    'MCA_CA4':
      PIN_NUMBER='(0,0,BA57,0,0,0,0,0,0,0,0,0,0,0,0,0,0,0,0,0,0,0,0,0,0,0,0,0,0,~
0,0,0,0,0,0,0,0,0,0,0)';
      OUTPUT_LOAD='(1.0,-1.0)';
      PINUSE='OUT';
    'MCA1_CS_L1':
      PIN_NUMBER='(0,0,AV55,0,0,0,0,0,0,0,0,0,0,0,0,0,0,0,0,0,0,0,0,0,0,0,0,0,0,~
0,0,0,0,0,0,0,0,0,0,0)';
      OUTPUT_LOAD='(1.0,-1.0)';
      PINUSE='OUT';
    'MCB_DQS_L7':
      PIN_NUMBER='(0,0,CU55,0,0,0,0,0,0,0,0,0,0,0,0,0,0,0,0,0,0,0,0,0,0,0,0,0,0,~
0,0,0,0,0,0,0,0,0,0,0)';
      BIDIRECTIONAL='TRUE';
      INPUT_LOAD='(-0.01,0.01)';
      OUTPUT_LOAD='(1.0,-1.0)';
      PINUSE='BI';
    'MCB_DQS_H3':
      PIN_NUMBER='(0,0,DB56,0,0,0,0,0,0,0,0,0,0,0,0,0,0,0,0,0,0,0,0,0,0,0,0,0,0,~
0,0,0,0,0,0,0,0,0,0,0)';
      BIDIRECTIONAL='TRUE';
      INPUT_LOAD='(-0.01,0.01)';
      OUTPUT_LOAD='(1.0,-1.0)';
      PINUSE='BI';
    'MCB_DATA3':
      PIN_NUMBER='(0,0,CD55,0,0,0,0,0,0,0,0,0,0,0,0,0,0,0,0,0,0,0,0,0,0,0,0,0,0,~
0,0,0,0,0,0,0,0,0,0,0)';
      BIDIRECTIONAL='TRUE';
      INPUT_LOAD='(-0.01,0.01)';
      OUTPUT_LOAD='(1.0,-1.0)';
      PINUSE='BI';
    'MCB_CA4':
      PIN_NUMBER='(0,0,BJ55,0,0,0,0,0,0,0,0,0,0,0,0,0,0,0,0,0,0,0,0,0,0,0,0,0,0,~
0,0,0,0,0,0,0,0,0,0,0)';
      OUTPUT_LOAD='(1.0,-1.0)';
      PINUSE='OUT';
    'MCA_DQS_H9':
      PIN_NUMBER='(0,0,AN55,0,0,0,0,0,0,0,0,0,0,0,0,0,0,0,0,0,0,0,0,0,0,0,0,0,0,~
0,0,0,0,0,0,0,0,0,0,0)';
      BIDIRECTIONAL='TRUE';
      INPUT_LOAD='(-0.01,0.01)';
      OUTPUT_LOAD='(1.0,-1.0)';
      PINUSE='BI';
    'MCA_DATA31':
      PIN_NUMBER='(0,0,AJ55,0,0,0,0,0,0,0,0,0,0,0,0,0,0,0,0,0,0,0,0,0,0,0,0,0,0,~
0,0,0,0,0,0,0,0,0,0,0)';
      BIDIRECTIONAL='TRUE';
      INPUT_LOAD='(-0.01,0.01)';
      OUTPUT_LOAD='(1.0,-1.0)';
      PINUSE='BI';
    'MCA_DATA20':
      PIN_NUMBER='(0,0,AA57,0,0,0,0,0,0,0,0,0,0,0,0,0,0,0,0,0,0,0,0,0,0,0,0,0,0,~
0,0,0,0,0,0,0,0,0,0,0)';
      BIDIRECTIONAL='TRUE';
      INPUT_LOAD='(-0.01,0.01)';
      OUTPUT_LOAD='(1.0,-1.0)';
      PINUSE='BI';
    'MCA_DATA4':
      PIN_NUMBER='(0,0,J57,0,0,0,0,0,0,0,0,0,0,0,0,0,0,0,0,0,0,0,0,0,0,0,0,0,0,0~
,0,0,0,0,0,0,0,0,0,0)';
      BIDIRECTIONAL='TRUE';
      INPUT_LOAD='(-0.01,0.01)';
      OUTPUT_LOAD='(1.0,-1.0)';
      PINUSE='BI';
    'MCA_CHECK0':
      PIN_NUMBER='(0,0,AJ57,0,0,0,0,0,0,0,0,0,0,0,0,0,0,0,0,0,0,0,0,0,0,0,0,0,0,~
0,0,0,0,0,0,0,0,0,0,0)';
      BIDIRECTIONAL='TRUE';
      INPUT_LOAD='(-0.01,0.01)';
      OUTPUT_LOAD='(1.0,-1.0)';
      PINUSE='BI';
    'MCA_CA5':
      PIN_NUMBER='(0,0,BB56,0,0,0,0,0,0,0,0,0,0,0,0,0,0,0,0,0,0,0,0,0,0,0,0,0,0,~
0,0,0,0,0,0,0,0,0,0,0)';
      OUTPUT_LOAD='(1.0,-1.0)';
      PINUSE='OUT';
    'MCB_DQS_L8':
      PIN_NUMBER='(0,0,DC55,0,0,0,0,0,0,0,0,0,0,0,0,0,0,0,0,0,0,0,0,0,0,0,0,0,0,~
0,0,0,0,0,0,0,0,0,0,0)';
      BIDIRECTIONAL='TRUE';
      INPUT_LOAD='(-0.01,0.01)';
      OUTPUT_LOAD='(1.0,-1.0)';
      PINUSE='BI';
    'MCB_DQS_H4':
      PIN_NUMBER='(0,0,BY55,0,0,0,0,0,0,0,0,0,0,0,0,0,0,0,0,0,0,0,0,0,0,0,0,0,0,~
0,0,0,0,0,0,0,0,0,0,0)';
      BIDIRECTIONAL='TRUE';
      INPUT_LOAD='(-0.01,0.01)';
      OUTPUT_LOAD='(1.0,-1.0)';
      PINUSE='BI';
    'MCB_DATA4':
      PIN_NUMBER='(0,0,CF56,0,0,0,0,0,0,0,0,0,0,0,0,0,0,0,0,0,0,0,0,0,0,0,0,0,0,~
0,0,0,0,0,0,0,0,0,0,0)';
      BIDIRECTIONAL='TRUE';
      INPUT_LOAD='(-0.01,0.01)';
      OUTPUT_LOAD='(1.0,-1.0)';
      PINUSE='BI';
    'MCB_CA5':
      PIN_NUMBER='(0,0,BK55,0,0,0,0,0,0,0,0,0,0,0,0,0,0,0,0,0,0,0,0,0,0,0,0,0,0,~
0,0,0,0,0,0,0,0,0,0,0)';
      OUTPUT_LOAD='(1.0,-1.0)';
      PINUSE='OUT';
    'MCA_DATA21':
      PIN_NUMBER='(0,0,AB55,0,0,0,0,0,0,0,0,0,0,0,0,0,0,0,0,0,0,0,0,0,0,0,0,0,0,~
0,0,0,0,0,0,0,0,0,0,0)';
      BIDIRECTIONAL='TRUE';
      INPUT_LOAD='(-0.01,0.01)';
      OUTPUT_LOAD='(1.0,-1.0)';
      PINUSE='BI';
    'MCA_DATA10':
      PIN_NUMBER='(0,0,M56,0,0,0,0,0,0,0,0,0,0,0,0,0,0,0,0,0,0,0,0,0,0,0,0,0,0,0~
,0,0,0,0,0,0,0,0,0,0)';
      BIDIRECTIONAL='TRUE';
      INPUT_LOAD='(-0.01,0.01)';
      OUTPUT_LOAD='(1.0,-1.0)';
      PINUSE='BI';
    'MCA_DATA5':
      PIN_NUMBER='(0,0,K55,0,0,0,0,0,0,0,0,0,0,0,0,0,0,0,0,0,0,0,0,0,0,0,0,0,0,0~
,0,0,0,0,0,0,0,0,0,0)';
      BIDIRECTIONAL='TRUE';
      INPUT_LOAD='(-0.01,0.01)';
      OUTPUT_LOAD='(1.0,-1.0)';
      PINUSE='BI';
    'MCA_CHECK1':
      PIN_NUMBER='(0,0,AK55,0,0,0,0,0,0,0,0,0,0,0,0,0,0,0,0,0,0,0,0,0,0,0,0,0,0,~
0,0,0,0,0,0,0,0,0,0,0)';
      BIDIRECTIONAL='TRUE';
      INPUT_LOAD='(-0.01,0.01)';
      OUTPUT_LOAD='(1.0,-1.0)';
      PINUSE='BI';
    'MCA_CA6':
      PIN_NUMBER='(0,0,BB55,0,0,0,0,0,0,0,0,0,0,0,0,0,0,0,0,0,0,0,0,0,0,0,0,0,0,~
0,0,0,0,0,0,0,0,0,0,0)';
      OUTPUT_LOAD='(1.0,-1.0)';
      PINUSE='OUT';
    'MCB_DQS_L9':
      PIN_NUMBER='(0,0,BW57,0,0,0,0,0,0,0,0,0,0,0,0,0,0,0,0,0,0,0,0,0,0,0,0,0,0,~
0,0,0,0,0,0,0,0,0,0,0)';
      BIDIRECTIONAL='TRUE';
      INPUT_LOAD='(-0.01,0.01)';
      OUTPUT_LOAD='(1.0,-1.0)';
      PINUSE='BI';
    'MCB_DQS_H5':
      PIN_NUMBER='(0,0,CF55,0,0,0,0,0,0,0,0,0,0,0,0,0,0,0,0,0,0,0,0,0,0,0,0,0,0,~
0,0,0,0,0,0,0,0,0,0,0)';
      BIDIRECTIONAL='TRUE';
      INPUT_LOAD='(-0.01,0.01)';
      OUTPUT_LOAD='(1.0,-1.0)';
      PINUSE='BI';
    'MCB_DATA5':
      PIN_NUMBER='(0,0,CG55,0,0,0,0,0,0,0,0,0,0,0,0,0,0,0,0,0,0,0,0,0,0,0,0,0,0,~
0,0,0,0,0,0,0,0,0,0,0)';
      BIDIRECTIONAL='TRUE';
      INPUT_LOAD='(-0.01,0.01)';
      OUTPUT_LOAD='(1.0,-1.0)';
      PINUSE='BI';
    'MCB_CA6':
      PIN_NUMBER='(0,0,BK56,0,0,0,0,0,0,0,0,0,0,0,0,0,0,0,0,0,0,0,0,0,0,0,0,0,0,~
0,0,0,0,0,0,0,0,0,0,0)';
      OUTPUT_LOAD='(1.0,-1.0)';
      PINUSE='OUT';
    'MCA_DATA22':
      PIN_NUMBER='(0,0,AB56,0,0,0,0,0,0,0,0,0,0,0,0,0,0,0,0,0,0,0,0,0,0,0,0,0,0,~
0,0,0,0,0,0,0,0,0,0,0)';
      BIDIRECTIONAL='TRUE';
      INPUT_LOAD='(-0.01,0.01)';
      OUTPUT_LOAD='(1.0,-1.0)';
      PINUSE='BI';
    'MCA_DATA11':
      PIN_NUMBER='(0,0,N55,0,0,0,0,0,0,0,0,0,0,0,0,0,0,0,0,0,0,0,0,0,0,0,0,0,0,0~
,0,0,0,0,0,0,0,0,0,0)';
      BIDIRECTIONAL='TRUE';
      INPUT_LOAD='(-0.01,0.01)';
      OUTPUT_LOAD='(1.0,-1.0)';
      PINUSE='BI';
    'MCA_DATA6':
      PIN_NUMBER='(0,0,K56,0,0,0,0,0,0,0,0,0,0,0,0,0,0,0,0,0,0,0,0,0,0,0,0,0,0,0~
,0,0,0,0,0,0,0,0,0,0)';
      BIDIRECTIONAL='TRUE';
      INPUT_LOAD='(-0.01,0.01)';
      OUTPUT_LOAD='(1.0,-1.0)';
      PINUSE='BI';
    'MCA_CHECK2':
      PIN_NUMBER='(0,0,AK56,0,0,0,0,0,0,0,0,0,0,0,0,0,0,0,0,0,0,0,0,0,0,0,0,0,0,~
0,0,0,0,0,0,0,0,0,0,0)';
      BIDIRECTIONAL='TRUE';
      INPUT_LOAD='(-0.01,0.01)';
      OUTPUT_LOAD='(1.0,-1.0)';
      PINUSE='BI';
    'MCB_DQS_H6':
      PIN_NUMBER='(0,0,CM55,0,0,0,0,0,0,0,0,0,0,0,0,0,0,0,0,0,0,0,0,0,0,0,0,0,0,~
0,0,0,0,0,0,0,0,0,0,0)';
      BIDIRECTIONAL='TRUE';
      INPUT_LOAD='(-0.01,0.01)';
      OUTPUT_LOAD='(1.0,-1.0)';
      PINUSE='BI';
    'MCB_DATA6':
      PIN_NUMBER='(0,0,CG57,0,0,0,0,0,0,0,0,0,0,0,0,0,0,0,0,0,0,0,0,0,0,0,0,0,0,~
0,0,0,0,0,0,0,0,0,0,0)';
      BIDIRECTIONAL='TRUE';
      INPUT_LOAD='(-0.01,0.01)';
      OUTPUT_LOAD='(1.0,-1.0)';
      PINUSE='BI';
    'MCA_DATA23':
      PIN_NUMBER='(0,0,AC55,0,0,0,0,0,0,0,0,0,0,0,0,0,0,0,0,0,0,0,0,0,0,0,0,0,0,~
0,0,0,0,0,0,0,0,0,0,0)';
      BIDIRECTIONAL='TRUE';
      INPUT_LOAD='(-0.01,0.01)';
      OUTPUT_LOAD='(1.0,-1.0)';
      PINUSE='BI';
    'MCA_DATA12':
      PIN_NUMBER='(0,0,R57,0,0,0,0,0,0,0,0,0,0,0,0,0,0,0,0,0,0,0,0,0,0,0,0,0,0,0~
,0,0,0,0,0,0,0,0,0,0)';
      BIDIRECTIONAL='TRUE';
      INPUT_LOAD='(-0.01,0.01)';
      OUTPUT_LOAD='(1.0,-1.0)';
      PINUSE='BI';
    'MCA_DATA7':
      PIN_NUMBER='(0,0,L55,0,0,0,0,0,0,0,0,0,0,0,0,0,0,0,0,0,0,0,0,0,0,0,0,0,0,0~
,0,0,0,0,0,0,0,0,0,0)';
      BIDIRECTIONAL='TRUE';
      INPUT_LOAD='(-0.01,0.01)';
      OUTPUT_LOAD='(1.0,-1.0)';
      PINUSE='BI';
    'MCA_CHECK3':
      PIN_NUMBER='(0,0,AL55,0,0,0,0,0,0,0,0,0,0,0,0,0,0,0,0,0,0,0,0,0,0,0,0,0,0,~
0,0,0,0,0,0,0,0,0,0,0)';
      BIDIRECTIONAL='TRUE';
      INPUT_LOAD='(-0.01,0.01)';
      OUTPUT_LOAD='(1.0,-1.0)';
      PINUSE='BI';
    'MCB_DQS_H7':
      PIN_NUMBER='(0,0,CV55,0,0,0,0,0,0,0,0,0,0,0,0,0,0,0,0,0,0,0,0,0,0,0,0,0,0,~
0,0,0,0,0,0,0,0,0,0,0)';
      BIDIRECTIONAL='TRUE';
      INPUT_LOAD='(-0.01,0.01)';
      OUTPUT_LOAD='(1.0,-1.0)';
      PINUSE='BI';
    'MCB_DATA7':
      PIN_NUMBER='(0,0,CH55,0,0,0,0,0,0,0,0,0,0,0,0,0,0,0,0,0,0,0,0,0,0,0,0,0,0,~
0,0,0,0,0,0,0,0,0,0,0)';
      BIDIRECTIONAL='TRUE';
      INPUT_LOAD='(-0.01,0.01)';
      OUTPUT_LOAD='(1.0,-1.0)';
      PINUSE='BI';
    'MCB1_CS_L0':
      PIN_NUMBER='(0,0,BL55,0,0,0,0,0,0,0,0,0,0,0,0,0,0,0,0,0,0,0,0,0,0,0,0,0,0,~
0,0,0,0,0,0,0,0,0,0,0)';
      OUTPUT_LOAD='(1.0,-1.0)';
      PINUSE='OUT';
    'MCB0_CS_L0':
      PIN_NUMBER='(0,0,BM55,0,0,0,0,0,0,0,0,0,0,0,0,0,0,0,0,0,0,0,0,0,0,0,0,0,0,~
0,0,0,0,0,0,0,0,0,0,0)';
      OUTPUT_LOAD='(1.0,-1.0)';
      PINUSE='OUT';
    'MCA_DQS_L0':
      PIN_NUMBER='(0,0,H56,0,0,0,0,0,0,0,0,0,0,0,0,0,0,0,0,0,0,0,0,0,0,0,0,0,0,0~
,0,0,0,0,0,0,0,0,0,0)';
      BIDIRECTIONAL='TRUE';
      INPUT_LOAD='(-0.01,0.01)';
      OUTPUT_LOAD='(1.0,-1.0)';
      PINUSE='BI';
    'MCA_DATA24':
      PIN_NUMBER='(0,0,AC57,0,0,0,0,0,0,0,0,0,0,0,0,0,0,0,0,0,0,0,0,0,0,0,0,0,0,~
0,0,0,0,0,0,0,0,0,0,0)';
      BIDIRECTIONAL='TRUE';
      INPUT_LOAD='(-0.01,0.01)';
      OUTPUT_LOAD='(1.0,-1.0)';
      PINUSE='BI';
    'MCA_DATA13':
      PIN_NUMBER='(0,0,T55,0,0,0,0,0,0,0,0,0,0,0,0,0,0,0,0,0,0,0,0,0,0,0,0,0,0,0~
,0,0,0,0,0,0,0,0,0,0)';
      BIDIRECTIONAL='TRUE';
      INPUT_LOAD='(-0.01,0.01)';
      OUTPUT_LOAD='(1.0,-1.0)';
      PINUSE='BI';
    'MCA_DATA8':
      PIN_NUMBER='(0,0,L57,0,0,0,0,0,0,0,0,0,0,0,0,0,0,0,0,0,0,0,0,0,0,0,0,0,0,0~
,0,0,0,0,0,0,0,0,0,0)';
      BIDIRECTIONAL='TRUE';
      INPUT_LOAD='(-0.01,0.01)';
      OUTPUT_LOAD='(1.0,-1.0)';
      PINUSE='BI';
    'MCA_CHECK4':
      PIN_NUMBER='(0,0,AN57,0,0,0,0,0,0,0,0,0,0,0,0,0,0,0,0,0,0,0,0,0,0,0,0,0,0,~
0,0,0,0,0,0,0,0,0,0,0)';
      BIDIRECTIONAL='TRUE';
      INPUT_LOAD='(-0.01,0.01)';
      OUTPUT_LOAD='(1.0,-1.0)';
      PINUSE='BI';
    'MCB_DQS_H9':
      PIN_NUMBER='(0,0,BV56,0,0,0,0,0,0,0,0,0,0,0,0,0,0,0,0,0,0,0,0,0,0,0,0,0,0,~
0,0,0,0,0,0,0,0,0,0,0)';
      BIDIRECTIONAL='TRUE';
      INPUT_LOAD='(-0.01,0.01)';
      OUTPUT_LOAD='(1.0,-1.0)';
      PINUSE='BI';
    'MCA_PAR':
      PIN_NUMBER='(0,0,BC55,0,0,0,0,0,0,0,0,0,0,0,0,0,0,0,0,0,0,0,0,0,0,0,0,0,0,~
0,0,0,0,0,0,0,0,0,0,0)';
      OUTPUT_LOAD='(1.0,-1.0)';
      PINUSE='OUT';
    'MCB_PAR':
      PIN_NUMBER='(0,0,BL57,0,0,0,0,0,0,0,0,0,0,0,0,0,0,0,0,0,0,0,0,0,0,0,0,0,0,~
0,0,0,0,0,0,0,0,0,0,0)';
      OUTPUT_LOAD='(1.0,-1.0)';
      PINUSE='OUT';
    'MC0_CLK_H':
      PIN_NUMBER='(0,0,BC57,0,0,0,0,0,0,0,0,0,0,0,0,0,0,0,0,0,0,0,0,0,0,0,0,0,0,~
0,0,0,0,0,0,0,0,0,0,0)';
      OUTPUT_LOAD='(1.0,-1.0)';
      PINUSE='OUT';
    'MC0_CLK_L':
      PIN_NUMBER='(0,0,BD56,0,0,0,0,0,0,0,0,0,0,0,0,0,0,0,0,0,0,0,0,0,0,0,0,0,0,~
0,0,0,0,0,0,0,0,0,0,0)';
      OUTPUT_LOAD='(1.0,-1.0)';
      PINUSE='OUT';
    'MC1_CLK_H':
      PIN_NUMBER='(0,0,BF56,0,0,0,0,0,0,0,0,0,0,0,0,0,0,0,0,0,0,0,0,0,0,0,0,0,0,~
0,0,0,0,0,0,0,0,0,0,0)';
      OUTPUT_LOAD='(1.0,-1.0)';
      PINUSE='OUT';
    'MC1_CLK_L':
      PIN_NUMBER='(0,0,BG57,0,0,0,0,0,0,0,0,0,0,0,0,0,0,0,0,0,0,0,0,0,0,0,0,0,0,~
0,0,0,0,0,0,0,0,0,0,0)';
      OUTPUT_LOAD='(1.0,-1.0)';
      PINUSE='OUT';
    'TEST39C':
      PIN_NUMBER='(0,0,BF55,0,0,0,0,0,0,0,0,0,0,0,0,0,0,0,0,0,0,0,0,0,0,0,0,0,0,~
0,0,0,0,0,0,0,0,0,0,0)';
      OUTPUT_LOAD='(1.0,-1.0)';
      PINUSE='OUT';
    'MD_ALERT_L':
      PIN_NUMBER='(0,0,0,AT58,0,0,0,0,0,0,0,0,0,0,0,0,0,0,0,0,0,0,0,0,0,0,0,0,0,~
0,0,0,0,0,0,0,0,0,0,0)';
      INPUT_LOAD='(-0.01,0.01)';
      PINUSE='IN';
    'MD_RESET_L':
      PIN_NUMBER='(0,0,0,AU59,0,0,0,0,0,0,0,0,0,0,0,0,0,0,0,0,0,0,0,0,0,0,0,0,0,~
0,0,0,0,0,0,0,0,0,0,0)';
      OUTPUT_LOAD='(1.0,-1.0)';
      PINUSE='OUT';
    'MDB_DATA23':
      PIN_NUMBER='(0,0,0,CY58,0,0,0,0,0,0,0,0,0,0,0,0,0,0,0,0,0,0,0,0,0,0,0,0,0,~
0,0,0,0,0,0,0,0,0,0,0)';
      BIDIRECTIONAL='TRUE';
      INPUT_LOAD='(-0.01,0.01)';
      OUTPUT_LOAD='(1.0,-1.0)';
      PINUSE='BI';
    'MDB_DATA12':
      PIN_NUMBER='(0,0,0,CM60,0,0,0,0,0,0,0,0,0,0,0,0,0,0,0,0,0,0,0,0,0,0,0,0,0,~
0,0,0,0,0,0,0,0,0,0,0)';
      BIDIRECTIONAL='TRUE';
      INPUT_LOAD='(-0.01,0.01)';
      OUTPUT_LOAD='(1.0,-1.0)';
      PINUSE='BI';
    'MDB_DATA2':
      PIN_NUMBER='(0,0,0,CC60,0,0,0,0,0,0,0,0,0,0,0,0,0,0,0,0,0,0,0,0,0,0,0,0,0,~
0,0,0,0,0,0,0,0,0,0,0)';
      BIDIRECTIONAL='TRUE';
      INPUT_LOAD='(-0.01,0.01)';
      OUTPUT_LOAD='(1.0,-1.0)';
      PINUSE='BI';
    'MDB_CHECK3':
      PIN_NUMBER='(0,0,0,CB58,0,0,0,0,0,0,0,0,0,0,0,0,0,0,0,0,0,0,0,0,0,0,0,0,0,~
0,0,0,0,0,0,0,0,0,0,0)';
      BIDIRECTIONAL='TRUE';
      INPUT_LOAD='(-0.01,0.01)';
      OUTPUT_LOAD='(1.0,-1.0)';
      PINUSE='BI';
    'MDA_DQS_L5':
      PIN_NUMBER='(0,0,0,H58,0,0,0,0,0,0,0,0,0,0,0,0,0,0,0,0,0,0,0,0,0,0,0,0,0,0~
,0,0,0,0,0,0,0,0,0,0)';
      BIDIRECTIONAL='TRUE';
      INPUT_LOAD='(-0.01,0.01)';
      OUTPUT_LOAD='(1.0,-1.0)';
      PINUSE='BI';
    'MDA_DQS_H1':
      PIN_NUMBER='(0,0,0,N60,0,0,0,0,0,0,0,0,0,0,0,0,0,0,0,0,0,0,0,0,0,0,0,0,0,0~
,0,0,0,0,0,0,0,0,0,0)';
      BIDIRECTIONAL='TRUE';
      INPUT_LOAD='(-0.01,0.01)';
      OUTPUT_LOAD='(1.0,-1.0)';
      PINUSE='BI';
    'MDA_DATA29':
      PIN_NUMBER='(0,0,0,AH58,0,0,0,0,0,0,0,0,0,0,0,0,0,0,0,0,0,0,0,0,0,0,0,0,0,~
0,0,0,0,0,0,0,0,0,0,0)';
      BIDIRECTIONAL='TRUE';
      INPUT_LOAD='(-0.01,0.01)';
      OUTPUT_LOAD='(1.0,-1.0)';
      PINUSE='BI';
    'MDA_DATA18':
      PIN_NUMBER='(0,0,0,V60,0,0,0,0,0,0,0,0,0,0,0,0,0,0,0,0,0,0,0,0,0,0,0,0,0,0~
,0,0,0,0,0,0,0,0,0,0)';
      BIDIRECTIONAL='TRUE';
      INPUT_LOAD='(-0.01,0.01)';
      OUTPUT_LOAD='(1.0,-1.0)';
      PINUSE='BI';
    'MDA_DATA3':
      PIN_NUMBER='(0,0,0,G59,0,0,0,0,0,0,0,0,0,0,0,0,0,0,0,0,0,0,0,0,0,0,0,0,0,0~
,0,0,0,0,0,0,0,0,0,0)';
      BIDIRECTIONAL='TRUE';
      INPUT_LOAD='(-0.01,0.01)';
      OUTPUT_LOAD='(1.0,-1.0)';
      PINUSE='BI';
    'MDB_DQS_L0':
      PIN_NUMBER='(0,0,0,CE60,0,0,0,0,0,0,0,0,0,0,0,0,0,0,0,0,0,0,0,0,0,0,0,0,0,~
0,0,0,0,0,0,0,0,0,0,0)';
      BIDIRECTIONAL='TRUE';
      INPUT_LOAD='(-0.01,0.01)';
      OUTPUT_LOAD='(1.0,-1.0)';
      PINUSE='BI';
    'MDB_DATA24':
      PIN_NUMBER='(0,0,0,CY60,0,0,0,0,0,0,0,0,0,0,0,0,0,0,0,0,0,0,0,0,0,0,0,0,0,~
0,0,0,0,0,0,0,0,0,0,0)';
      BIDIRECTIONAL='TRUE';
      INPUT_LOAD='(-0.01,0.01)';
      OUTPUT_LOAD='(1.0,-1.0)';
      PINUSE='BI';
    'MDB_DATA13':
      PIN_NUMBER='(0,0,0,CN59,0,0,0,0,0,0,0,0,0,0,0,0,0,0,0,0,0,0,0,0,0,0,0,0,0,~
0,0,0,0,0,0,0,0,0,0,0)';
      BIDIRECTIONAL='TRUE';
      INPUT_LOAD='(-0.01,0.01)';
      OUTPUT_LOAD='(1.0,-1.0)';
      PINUSE='BI';
    'MDB_DATA3':
      PIN_NUMBER='(0,0,0,CD58,0,0,0,0,0,0,0,0,0,0,0,0,0,0,0,0,0,0,0,0,0,0,0,0,0,~
0,0,0,0,0,0,0,0,0,0,0)';
      BIDIRECTIONAL='TRUE';
      INPUT_LOAD='(-0.01,0.01)';
      OUTPUT_LOAD='(1.0,-1.0)';
      PINUSE='BI';
    'MDB_CHECK4':
      PIN_NUMBER='(0,0,0,BT60,0,0,0,0,0,0,0,0,0,0,0,0,0,0,0,0,0,0,0,0,0,0,0,0,0,~
0,0,0,0,0,0,0,0,0,0,0)';
      BIDIRECTIONAL='TRUE';
      INPUT_LOAD='(-0.01,0.01)';
      OUTPUT_LOAD='(1.0,-1.0)';
      PINUSE='BI';
    'MDA_DQS_L6':
      PIN_NUMBER='(0,0,0,P58,0,0,0,0,0,0,0,0,0,0,0,0,0,0,0,0,0,0,0,0,0,0,0,0,0,0~
,0,0,0,0,0,0,0,0,0,0)';
      BIDIRECTIONAL='TRUE';
      INPUT_LOAD='(-0.01,0.01)';
      OUTPUT_LOAD='(1.0,-1.0)';
      PINUSE='BI';
    'MDA_DQS_H2':
      PIN_NUMBER='(0,0,0,W60,0,0,0,0,0,0,0,0,0,0,0,0,0,0,0,0,0,0,0,0,0,0,0,0,0,0~
,0,0,0,0,0,0,0,0,0,0)';
      BIDIRECTIONAL='TRUE';
      INPUT_LOAD='(-0.01,0.01)';
      OUTPUT_LOAD='(1.0,-1.0)';
      PINUSE='BI';
    'MDA_DATA19':
      PIN_NUMBER='(0,0,0,W59,0,0,0,0,0,0,0,0,0,0,0,0,0,0,0,0,0,0,0,0,0,0,0,0,0,0~
,0,0,0,0,0,0,0,0,0,0)';
      BIDIRECTIONAL='TRUE';
      INPUT_LOAD='(-0.01,0.01)';
      OUTPUT_LOAD='(1.0,-1.0)';
      PINUSE='BI';
    'MDA_DATA4':
      PIN_NUMBER='(0,0,0,J60,0,0,0,0,0,0,0,0,0,0,0,0,0,0,0,0,0,0,0,0,0,0,0,0,0,0~
,0,0,0,0,0,0,0,0,0,0)';
      BIDIRECTIONAL='TRUE';
      INPUT_LOAD='(-0.01,0.01)';
      OUTPUT_LOAD='(1.0,-1.0)';
      PINUSE='BI';
    'MDB_DQS_L1':
      PIN_NUMBER='(0,0,0,CL60,0,0,0,0,0,0,0,0,0,0,0,0,0,0,0,0,0,0,0,0,0,0,0,0,0,~
0,0,0,0,0,0,0,0,0,0,0)';
      BIDIRECTIONAL='TRUE';
      INPUT_LOAD='(-0.01,0.01)';
      OUTPUT_LOAD='(1.0,-1.0)';
      PINUSE='BI';
    'MDB_DATA25':
      PIN_NUMBER='(0,0,0,DA59,0,0,0,0,0,0,0,0,0,0,0,0,0,0,0,0,0,0,0,0,0,0,0,0,0,~
0,0,0,0,0,0,0,0,0,0,0)';
      BIDIRECTIONAL='TRUE';
      INPUT_LOAD='(-0.01,0.01)';
      OUTPUT_LOAD='(1.0,-1.0)';
      PINUSE='BI';
    'MDB_DATA14':
      PIN_NUMBER='(0,0,0,CN60,0,0,0,0,0,0,0,0,0,0,0,0,0,0,0,0,0,0,0,0,0,0,0,0,0,~
0,0,0,0,0,0,0,0,0,0,0)';
      BIDIRECTIONAL='TRUE';
      INPUT_LOAD='(-0.01,0.01)';
      OUTPUT_LOAD='(1.0,-1.0)';
      PINUSE='BI';
    'MDB_DATA4':
      PIN_NUMBER='(0,0,0,CF60,0,0,0,0,0,0,0,0,0,0,0,0,0,0,0,0,0,0,0,0,0,0,0,0,0,~
0,0,0,0,0,0,0,0,0,0,0)';
      BIDIRECTIONAL='TRUE';
      INPUT_LOAD='(-0.01,0.01)';
      OUTPUT_LOAD='(1.0,-1.0)';
      PINUSE='BI';
    'MDB_CHECK5':
      PIN_NUMBER='(0,0,0,BU59,0,0,0,0,0,0,0,0,0,0,0,0,0,0,0,0,0,0,0,0,0,0,0,0,0,~
0,0,0,0,0,0,0,0,0,0,0)';
      BIDIRECTIONAL='TRUE';
      INPUT_LOAD='(-0.01,0.01)';
      OUTPUT_LOAD='(1.0,-1.0)';
      PINUSE='BI';
    'MDA_DQS_L7':
      PIN_NUMBER='(0,0,0,Y58,0,0,0,0,0,0,0,0,0,0,0,0,0,0,0,0,0,0,0,0,0,0,0,0,0,0~
,0,0,0,0,0,0,0,0,0,0)';
      BIDIRECTIONAL='TRUE';
      INPUT_LOAD='(-0.01,0.01)';
      OUTPUT_LOAD='(1.0,-1.0)';
      PINUSE='BI';
    'MDA_DQS_H3':
      PIN_NUMBER='(0,0,0,AE60,0,0,0,0,0,0,0,0,0,0,0,0,0,0,0,0,0,0,0,0,0,0,0,0,0,~
0,0,0,0,0,0,0,0,0,0,0)';
      BIDIRECTIONAL='TRUE';
      INPUT_LOAD='(-0.01,0.01)';
      OUTPUT_LOAD='(1.0,-1.0)';
      PINUSE='BI';
    'MDA_DATA5':
      PIN_NUMBER='(0,0,0,K58,0,0,0,0,0,0,0,0,0,0,0,0,0,0,0,0,0,0,0,0,0,0,0,0,0,0~
,0,0,0,0,0,0,0,0,0,0)';
      BIDIRECTIONAL='TRUE';
      INPUT_LOAD='(-0.01,0.01)';
      OUTPUT_LOAD='(1.0,-1.0)';
      PINUSE='BI';
    'MDB_DQS_L2':
      PIN_NUMBER='(0,0,0,CU60,0,0,0,0,0,0,0,0,0,0,0,0,0,0,0,0,0,0,0,0,0,0,0,0,0,~
0,0,0,0,0,0,0,0,0,0,0)';
      BIDIRECTIONAL='TRUE';
      INPUT_LOAD='(-0.01,0.01)';
      OUTPUT_LOAD='(1.0,-1.0)';
      PINUSE='BI';
    'MDB_DATA26':
      PIN_NUMBER='(0,0,0,DA60,0,0,0,0,0,0,0,0,0,0,0,0,0,0,0,0,0,0,0,0,0,0,0,0,0,~
0,0,0,0,0,0,0,0,0,0,0)';
      BIDIRECTIONAL='TRUE';
      INPUT_LOAD='(-0.01,0.01)';
      OUTPUT_LOAD='(1.0,-1.0)';
      PINUSE='BI';
    'MDB_DATA15':
      PIN_NUMBER='(0,0,0,CP58,0,0,0,0,0,0,0,0,0,0,0,0,0,0,0,0,0,0,0,0,0,0,0,0,0,~
0,0,0,0,0,0,0,0,0,0,0)';
      BIDIRECTIONAL='TRUE';
      INPUT_LOAD='(-0.01,0.01)';
      OUTPUT_LOAD='(1.0,-1.0)';
      PINUSE='BI';
    'MDB_DATA5':
      PIN_NUMBER='(0,0,0,CG59,0,0,0,0,0,0,0,0,0,0,0,0,0,0,0,0,0,0,0,0,0,0,0,0,0,~
0,0,0,0,0,0,0,0,0,0,0)';
      BIDIRECTIONAL='TRUE';
      INPUT_LOAD='(-0.01,0.01)';
      OUTPUT_LOAD='(1.0,-1.0)';
      PINUSE='BI';
    'MDB_CHECK6':
      PIN_NUMBER='(0,0,0,BU60,0,0,0,0,0,0,0,0,0,0,0,0,0,0,0,0,0,0,0,0,0,0,0,0,0,~
0,0,0,0,0,0,0,0,0,0,0)';
      BIDIRECTIONAL='TRUE';
      INPUT_LOAD='(-0.01,0.01)';
      OUTPUT_LOAD='(1.0,-1.0)';
      PINUSE='BI';
    'MDA_DQS_L8':
      PIN_NUMBER='(0,0,0,AF58,0,0,0,0,0,0,0,0,0,0,0,0,0,0,0,0,0,0,0,0,0,0,0,0,0,~
0,0,0,0,0,0,0,0,0,0,0)';
      BIDIRECTIONAL='TRUE';
      INPUT_LOAD='(-0.01,0.01)';
      OUTPUT_LOAD='(1.0,-1.0)';
      PINUSE='BI';
    'MDA_DQS_H4':
      PIN_NUMBER='(0,0,0,AL60,0,0,0,0,0,0,0,0,0,0,0,0,0,0,0,0,0,0,0,0,0,0,0,0,0,~
0,0,0,0,0,0,0,0,0,0,0)';
      BIDIRECTIONAL='TRUE';
      INPUT_LOAD='(-0.01,0.01)';
      OUTPUT_LOAD='(1.0,-1.0)';
      PINUSE='BI';
    'MDA_DATA6':
      PIN_NUMBER='(0,0,0,K60,0,0,0,0,0,0,0,0,0,0,0,0,0,0,0,0,0,0,0,0,0,0,0,0,0,0~
,0,0,0,0,0,0,0,0,0,0)';
      BIDIRECTIONAL='TRUE';
      INPUT_LOAD='(-0.01,0.01)';
      OUTPUT_LOAD='(1.0,-1.0)';
      PINUSE='BI';
    'MDB_DQS_L3':
      PIN_NUMBER='(0,0,0,DC60,0,0,0,0,0,0,0,0,0,0,0,0,0,0,0,0,0,0,0,0,0,0,0,0,0,~
0,0,0,0,0,0,0,0,0,0,0)';
      BIDIRECTIONAL='TRUE';
      INPUT_LOAD='(-0.01,0.01)';
      OUTPUT_LOAD='(1.0,-1.0)';
      PINUSE='BI';
    'MDB_DATA27':
      PIN_NUMBER='(0,0,0,DB58,0,0,0,0,0,0,0,0,0,0,0,0,0,0,0,0,0,0,0,0,0,0,0,0,0,~
0,0,0,0,0,0,0,0,0,0,0)';
      BIDIRECTIONAL='TRUE';
      INPUT_LOAD='(-0.01,0.01)';
      OUTPUT_LOAD='(1.0,-1.0)';
      PINUSE='BI';
    'MDB_DATA16':
      PIN_NUMBER='(0,0,0,CP60,0,0,0,0,0,0,0,0,0,0,0,0,0,0,0,0,0,0,0,0,0,0,0,0,0,~
0,0,0,0,0,0,0,0,0,0,0)';
      BIDIRECTIONAL='TRUE';
      INPUT_LOAD='(-0.01,0.01)';
      OUTPUT_LOAD='(1.0,-1.0)';
      PINUSE='BI';
    'MDB_DATA6':
      PIN_NUMBER='(0,0,0,CG60,0,0,0,0,0,0,0,0,0,0,0,0,0,0,0,0,0,0,0,0,0,0,0,0,0,~
0,0,0,0,0,0,0,0,0,0,0)';
      BIDIRECTIONAL='TRUE';
      INPUT_LOAD='(-0.01,0.01)';
      OUTPUT_LOAD='(1.0,-1.0)';
      PINUSE='BI';
    'MDB_CHECK7':
      PIN_NUMBER='(0,0,0,BV58,0,0,0,0,0,0,0,0,0,0,0,0,0,0,0,0,0,0,0,0,0,0,0,0,0,~
0,0,0,0,0,0,0,0,0,0,0)';
      BIDIRECTIONAL='TRUE';
      INPUT_LOAD='(-0.01,0.01)';
      OUTPUT_LOAD='(1.0,-1.0)';
      PINUSE='BI';
    'MDB0_RSP_L':
      PIN_NUMBER='(0,0,0,BP60,0,0,0,0,0,0,0,0,0,0,0,0,0,0,0,0,0,0,0,0,0,0,0,0,0,~
0,0,0,0,0,0,0,0,0,0,0)';
      INPUT_LOAD='(-0.01,0.01)';
      PINUSE='IN';
    'MDA_DQS_L9':
      PIN_NUMBER='(0,0,0,AM58,0,0,0,0,0,0,0,0,0,0,0,0,0,0,0,0,0,0,0,0,0,0,0,0,0,~
0,0,0,0,0,0,0,0,0,0,0)';
      BIDIRECTIONAL='TRUE';
      INPUT_LOAD='(-0.01,0.01)';
      OUTPUT_LOAD='(1.0,-1.0)';
      PINUSE='BI';
    'MDA_DQS_H5':
      PIN_NUMBER='(0,0,0,J59,0,0,0,0,0,0,0,0,0,0,0,0,0,0,0,0,0,0,0,0,0,0,0,0,0,0~
,0,0,0,0,0,0,0,0,0,0)';
      BIDIRECTIONAL='TRUE';
      INPUT_LOAD='(-0.01,0.01)';
      OUTPUT_LOAD='(1.0,-1.0)';
      PINUSE='BI';
    'MDA_DATA7':
      PIN_NUMBER='(0,0,0,L59,0,0,0,0,0,0,0,0,0,0,0,0,0,0,0,0,0,0,0,0,0,0,0,0,0,0~
,0,0,0,0,0,0,0,0,0,0)';
      BIDIRECTIONAL='TRUE';
      INPUT_LOAD='(-0.01,0.01)';
      OUTPUT_LOAD='(1.0,-1.0)';
      PINUSE='BI';
    'MDB_DQS_L4':
      PIN_NUMBER='(0,0,0,BW59,0,0,0,0,0,0,0,0,0,0,0,0,0,0,0,0,0,0,0,0,0,0,0,0,0,~
0,0,0,0,0,0,0,0,0,0,0)';
      BIDIRECTIONAL='TRUE';
      INPUT_LOAD='(-0.01,0.01)';
      OUTPUT_LOAD='(1.0,-1.0)';
      PINUSE='BI';
    'MDB_DQS_H0':
      PIN_NUMBER='(0,0,0,CD60,0,0,0,0,0,0,0,0,0,0,0,0,0,0,0,0,0,0,0,0,0,0,0,0,0,~
0,0,0,0,0,0,0,0,0,0,0)';
      BIDIRECTIONAL='TRUE';
      INPUT_LOAD='(-0.01,0.01)';
      OUTPUT_LOAD='(1.0,-1.0)';
      PINUSE='BI';
    'MDB_DATA28':
      PIN_NUMBER='(0,0,0,DD60,0,0,0,0,0,0,0,0,0,0,0,0,0,0,0,0,0,0,0,0,0,0,0,0,0,~
0,0,0,0,0,0,0,0,0,0,0)';
      BIDIRECTIONAL='TRUE';
      INPUT_LOAD='(-0.01,0.01)';
      OUTPUT_LOAD='(1.0,-1.0)';
      PINUSE='BI';
    'MDB_DATA17':
      PIN_NUMBER='(0,0,0,CR59,0,0,0,0,0,0,0,0,0,0,0,0,0,0,0,0,0,0,0,0,0,0,0,0,0,~
0,0,0,0,0,0,0,0,0,0,0)';
      BIDIRECTIONAL='TRUE';
      INPUT_LOAD='(-0.01,0.01)';
      OUTPUT_LOAD='(1.0,-1.0)';
      PINUSE='BI';
    'MDB_DATA7':
      PIN_NUMBER='(0,0,0,CH58,0,0,0,0,0,0,0,0,0,0,0,0,0,0,0,0,0,0,0,0,0,0,0,0,0,~
0,0,0,0,0,0,0,0,0,0,0)';
      BIDIRECTIONAL='TRUE';
      INPUT_LOAD='(-0.01,0.01)';
      OUTPUT_LOAD='(1.0,-1.0)';
      PINUSE='BI';
    'MDB1_RSP_L':
      PIN_NUMBER='(0,0,0,BR60,0,0,0,0,0,0,0,0,0,0,0,0,0,0,0,0,0,0,0,0,0,0,0,0,0,~
0,0,0,0,0,0,0,0,0,0,0)';
      INPUT_LOAD='(-0.01,0.01)';
      PINUSE='IN';
    'MDA_DQS_H6':
      PIN_NUMBER='(0,0,0,R59,0,0,0,0,0,0,0,0,0,0,0,0,0,0,0,0,0,0,0,0,0,0,0,0,0,0~
,0,0,0,0,0,0,0,0,0,0)';
      BIDIRECTIONAL='TRUE';
      INPUT_LOAD='(-0.01,0.01)';
      OUTPUT_LOAD='(1.0,-1.0)';
      PINUSE='BI';
    'MDA_DATA8':
      PIN_NUMBER='(0,0,0,L60,0,0,0,0,0,0,0,0,0,0,0,0,0,0,0,0,0,0,0,0,0,0,0,0,0,0~
,0,0,0,0,0,0,0,0,0,0)';
      BIDIRECTIONAL='TRUE';
      INPUT_LOAD='(-0.01,0.01)';
      OUTPUT_LOAD='(1.0,-1.0)';
      PINUSE='BI';
    'MDB_DQS_L5':
      PIN_NUMBER='(0,0,0,CE59,0,0,0,0,0,0,0,0,0,0,0,0,0,0,0,0,0,0,0,0,0,0,0,0,0,~
0,0,0,0,0,0,0,0,0,0,0)';
      BIDIRECTIONAL='TRUE';
      INPUT_LOAD='(-0.01,0.01)';
      OUTPUT_LOAD='(1.0,-1.0)';
      PINUSE='BI';
    'MDB_DQS_H1':
      PIN_NUMBER='(0,0,0,CK60,0,0,0,0,0,0,0,0,0,0,0,0,0,0,0,0,0,0,0,0,0,0,0,0,0,~
0,0,0,0,0,0,0,0,0,0,0)';
      BIDIRECTIONAL='TRUE';
      INPUT_LOAD='(-0.01,0.01)';
      OUTPUT_LOAD='(1.0,-1.0)';
      PINUSE='BI';
    'MDB_DATA29':
      PIN_NUMBER='(0,0,0,DE59,0,0,0,0,0,0,0,0,0,0,0,0,0,0,0,0,0,0,0,0,0,0,0,0,0,~
0,0,0,0,0,0,0,0,0,0,0)';
      BIDIRECTIONAL='TRUE';
      INPUT_LOAD='(-0.01,0.01)';
      OUTPUT_LOAD='(1.0,-1.0)';
      PINUSE='BI';
    'MDB_DATA18':
      PIN_NUMBER='(0,0,0,CR60,0,0,0,0,0,0,0,0,0,0,0,0,0,0,0,0,0,0,0,0,0,0,0,0,0,~
0,0,0,0,0,0,0,0,0,0,0)';
      BIDIRECTIONAL='TRUE';
      INPUT_LOAD='(-0.01,0.01)';
      OUTPUT_LOAD='(1.0,-1.0)';
      PINUSE='BI';
    'MDB_DATA8':
      PIN_NUMBER='(0,0,0,CH60,0,0,0,0,0,0,0,0,0,0,0,0,0,0,0,0,0,0,0,0,0,0,0,0,0,~
0,0,0,0,0,0,0,0,0,0,0)';
      BIDIRECTIONAL='TRUE';
      INPUT_LOAD='(-0.01,0.01)';
      OUTPUT_LOAD='(1.0,-1.0)';
      PINUSE='BI';
    'MDA_DQS_H7':
      PIN_NUMBER='(0,0,0,AA59,0,0,0,0,0,0,0,0,0,0,0,0,0,0,0,0,0,0,0,0,0,0,0,0,0,~
0,0,0,0,0,0,0,0,0,0,0)';
      BIDIRECTIONAL='TRUE';
      INPUT_LOAD='(-0.01,0.01)';
      OUTPUT_LOAD='(1.0,-1.0)';
      PINUSE='BI';
    'MDA_DATA9':
      PIN_NUMBER='(0,0,0,M58,0,0,0,0,0,0,0,0,0,0,0,0,0,0,0,0,0,0,0,0,0,0,0,0,0,0~
,0,0,0,0,0,0,0,0,0,0)';
      BIDIRECTIONAL='TRUE';
      INPUT_LOAD='(-0.01,0.01)';
      OUTPUT_LOAD='(1.0,-1.0)';
      PINUSE='BI';
    'MDA_CA0':
      PIN_NUMBER='(0,0,0,AW60,0,0,0,0,0,0,0,0,0,0,0,0,0,0,0,0,0,0,0,0,0,0,0,0,0,~
0,0,0,0,0,0,0,0,0,0,0)';
      OUTPUT_LOAD='(1.0,-1.0)';
      PINUSE='OUT';
    'MDA0_CS_L0':
      PIN_NUMBER='(0,0,0,AV60,0,0,0,0,0,0,0,0,0,0,0,0,0,0,0,0,0,0,0,0,0,0,0,0,0,~
0,0,0,0,0,0,0,0,0,0,0)';
      OUTPUT_LOAD='(1.0,-1.0)';
      PINUSE='OUT';
    'MDB_DQS_L6':
      PIN_NUMBER='(0,0,0,CL59,0,0,0,0,0,0,0,0,0,0,0,0,0,0,0,0,0,0,0,0,0,0,0,0,0,~
0,0,0,0,0,0,0,0,0,0,0)';
      BIDIRECTIONAL='TRUE';
      INPUT_LOAD='(-0.01,0.01)';
      OUTPUT_LOAD='(1.0,-1.0)';
      PINUSE='BI';
    'MDB_DQS_H2':
      PIN_NUMBER='(0,0,0,CT60,0,0,0,0,0,0,0,0,0,0,0,0,0,0,0,0,0,0,0,0,0,0,0,0,0,~
0,0,0,0,0,0,0,0,0,0,0)';
      BIDIRECTIONAL='TRUE';
      INPUT_LOAD='(-0.01,0.01)';
      OUTPUT_LOAD='(1.0,-1.0)';
      PINUSE='BI';
    'MDB_DATA19':
      PIN_NUMBER='(0,0,0,CT58,0,0,0,0,0,0,0,0,0,0,0,0,0,0,0,0,0,0,0,0,0,0,0,0,0,~
0,0,0,0,0,0,0,0,0,0,0)';
      BIDIRECTIONAL='TRUE';
      INPUT_LOAD='(-0.01,0.01)';
      OUTPUT_LOAD='(1.0,-1.0)';
      PINUSE='BI';
    'MDB_DATA9':
      PIN_NUMBER='(0,0,0,CJ59,0,0,0,0,0,0,0,0,0,0,0,0,0,0,0,0,0,0,0,0,0,0,0,0,0,~
0,0,0,0,0,0,0,0,0,0,0)';
      BIDIRECTIONAL='TRUE';
      INPUT_LOAD='(-0.01,0.01)';
      OUTPUT_LOAD='(1.0,-1.0)';
      PINUSE='BI';
    'MDB_CA0':
      PIN_NUMBER='(0,0,0,BG59,0,0,0,0,0,0,0,0,0,0,0,0,0,0,0,0,0,0,0,0,0,0,0,0,0,~
0,0,0,0,0,0,0,0,0,0,0)';
      OUTPUT_LOAD='(1.0,-1.0)';
      PINUSE='OUT';
    'MDA_DQS_H8':
      PIN_NUMBER='(0,0,0,AG59,0,0,0,0,0,0,0,0,0,0,0,0,0,0,0,0,0,0,0,0,0,0,0,0,0,~
0,0,0,0,0,0,0,0,0,0,0)';
      BIDIRECTIONAL='TRUE';
      INPUT_LOAD='(-0.01,0.01)';
      OUTPUT_LOAD='(1.0,-1.0)';
      PINUSE='BI';
    'MDA_DATA30':
      PIN_NUMBER='(0,0,0,AH60,0,0,0,0,0,0,0,0,0,0,0,0,0,0,0,0,0,0,0,0,0,0,0,0,0,~
0,0,0,0,0,0,0,0,0,0,0)';
      BIDIRECTIONAL='TRUE';
      INPUT_LOAD='(-0.01,0.01)';
      OUTPUT_LOAD='(1.0,-1.0)';
      PINUSE='BI';
    'MDA_CA1':
      PIN_NUMBER='(0,0,0,AY60,0,0,0,0,0,0,0,0,0,0,0,0,0,0,0,0,0,0,0,0,0,0,0,0,0,~
0,0,0,0,0,0,0,0,0,0,0)';
      OUTPUT_LOAD='(1.0,-1.0)';
      PINUSE='OUT';
    'MDA1_CS_L0':
      PIN_NUMBER='(0,0,0,AU60,0,0,0,0,0,0,0,0,0,0,0,0,0,0,0,0,0,0,0,0,0,0,0,0,0,~
0,0,0,0,0,0,0,0,0,0,0)';
      OUTPUT_LOAD='(1.0,-1.0)';
      PINUSE='OUT';
    'MDA0_CS_L1':
      PIN_NUMBER='(0,0,0,AW59,0,0,0,0,0,0,0,0,0,0,0,0,0,0,0,0,0,0,0,0,0,0,0,0,0,~
0,0,0,0,0,0,0,0,0,0,0)';
      OUTPUT_LOAD='(1.0,-1.0)';
      PINUSE='OUT';
    'MDB_DQS_L7':
      PIN_NUMBER='(0,0,0,CU59,0,0,0,0,0,0,0,0,0,0,0,0,0,0,0,0,0,0,0,0,0,0,0,0,0,~
0,0,0,0,0,0,0,0,0,0,0)';
      BIDIRECTIONAL='TRUE';
      INPUT_LOAD='(-0.01,0.01)';
      OUTPUT_LOAD='(1.0,-1.0)';
      PINUSE='BI';
    'MDB_DQS_H3':
      PIN_NUMBER='(0,0,0,DB60,0,0,0,0,0,0,0,0,0,0,0,0,0,0,0,0,0,0,0,0,0,0,0,0,0,~
0,0,0,0,0,0,0,0,0,0,0)';
      BIDIRECTIONAL='TRUE';
      INPUT_LOAD='(-0.01,0.01)';
      OUTPUT_LOAD='(1.0,-1.0)';
      PINUSE='BI';
    'MDB_CA1':
      PIN_NUMBER='(0,0,0,BH58,0,0,0,0,0,0,0,0,0,0,0,0,0,0,0,0,0,0,0,0,0,0,0,0,0,~
0,0,0,0,0,0,0,0,0,0,0)';
      OUTPUT_LOAD='(1.0,-1.0)';
      PINUSE='OUT';
    'MDA_DQS_H9':
      PIN_NUMBER='(0,0,0,AN59,0,0,0,0,0,0,0,0,0,0,0,0,0,0,0,0,0,0,0,0,0,0,0,0,0,~
0,0,0,0,0,0,0,0,0,0,0)';
      BIDIRECTIONAL='TRUE';
      INPUT_LOAD='(-0.01,0.01)';
      OUTPUT_LOAD='(1.0,-1.0)';
      PINUSE='BI';
    'MDA_DATA31':
      PIN_NUMBER='(0,0,0,AJ59,0,0,0,0,0,0,0,0,0,0,0,0,0,0,0,0,0,0,0,0,0,0,0,0,0,~
0,0,0,0,0,0,0,0,0,0,0)';
      BIDIRECTIONAL='TRUE';
      INPUT_LOAD='(-0.01,0.01)';
      OUTPUT_LOAD='(1.0,-1.0)';
      PINUSE='BI';
    'MDA_DATA20':
      PIN_NUMBER='(0,0,0,AA60,0,0,0,0,0,0,0,0,0,0,0,0,0,0,0,0,0,0,0,0,0,0,0,0,0,~
0,0,0,0,0,0,0,0,0,0,0)';
      BIDIRECTIONAL='TRUE';
      INPUT_LOAD='(-0.01,0.01)';
      OUTPUT_LOAD='(1.0,-1.0)';
      PINUSE='BI';
    'MDA_CHECK0':
      PIN_NUMBER='(0,0,0,AJ60,0,0,0,0,0,0,0,0,0,0,0,0,0,0,0,0,0,0,0,0,0,0,0,0,0,~
0,0,0,0,0,0,0,0,0,0,0)';
      BIDIRECTIONAL='TRUE';
      INPUT_LOAD='(-0.01,0.01)';
      OUTPUT_LOAD='(1.0,-1.0)';
      PINUSE='BI';
    'MDA_CA2':
      PIN_NUMBER='(0,0,0,AY58,0,0,0,0,0,0,0,0,0,0,0,0,0,0,0,0,0,0,0,0,0,0,0,0,0,~
0,0,0,0,0,0,0,0,0,0,0)';
      OUTPUT_LOAD='(1.0,-1.0)';
      PINUSE='OUT';
    'MDA1_CS_L1':
      PIN_NUMBER='(0,0,0,AV58,0,0,0,0,0,0,0,0,0,0,0,0,0,0,0,0,0,0,0,0,0,0,0,0,0,~
0,0,0,0,0,0,0,0,0,0,0)';
      OUTPUT_LOAD='(1.0,-1.0)';
      PINUSE='OUT';
    'MDB_DQS_L8':
      PIN_NUMBER='(0,0,0,DC59,0,0,0,0,0,0,0,0,0,0,0,0,0,0,0,0,0,0,0,0,0,0,0,0,0,~
0,0,0,0,0,0,0,0,0,0,0)';
      BIDIRECTIONAL='TRUE';
      INPUT_LOAD='(-0.01,0.01)';
      OUTPUT_LOAD='(1.0,-1.0)';
      PINUSE='BI';
    'MDB_DQS_H4':
      PIN_NUMBER='(0,0,0,BY58,0,0,0,0,0,0,0,0,0,0,0,0,0,0,0,0,0,0,0,0,0,0,0,0,0,~
0,0,0,0,0,0,0,0,0,0,0)';
      BIDIRECTIONAL='TRUE';
      INPUT_LOAD='(-0.01,0.01)';
      OUTPUT_LOAD='(1.0,-1.0)';
      PINUSE='BI';
    'MDB_CA2':
      PIN_NUMBER='(0,0,0,BH60,0,0,0,0,0,0,0,0,0,0,0,0,0,0,0,0,0,0,0,0,0,0,0,0,0,~
0,0,0,0,0,0,0,0,0,0,0)';
      OUTPUT_LOAD='(1.0,-1.0)';
      PINUSE='OUT';
    'MDA_DATA21':
      PIN_NUMBER='(0,0,0,AB58,0,0,0,0,0,0,0,0,0,0,0,0,0,0,0,0,0,0,0,0,0,0,0,0,0,~
0,0,0,0,0,0,0,0,0,0,0)';
      BIDIRECTIONAL='TRUE';
      INPUT_LOAD='(-0.01,0.01)';
      OUTPUT_LOAD='(1.0,-1.0)';
      PINUSE='BI';
    'MDA_DATA10':
      PIN_NUMBER='(0,0,0,M60,0,0,0,0,0,0,0,0,0,0,0,0,0,0,0,0,0,0,0,0,0,0,0,0,0,0~
,0,0,0,0,0,0,0,0,0,0)';
      BIDIRECTIONAL='TRUE';
      INPUT_LOAD='(-0.01,0.01)';
      OUTPUT_LOAD='(1.0,-1.0)';
      PINUSE='BI';
    'MDA_CHECK1':
      PIN_NUMBER='(0,0,0,AK58,0,0,0,0,0,0,0,0,0,0,0,0,0,0,0,0,0,0,0,0,0,0,0,0,0,~
0,0,0,0,0,0,0,0,0,0,0)';
      BIDIRECTIONAL='TRUE';
      INPUT_LOAD='(-0.01,0.01)';
      OUTPUT_LOAD='(1.0,-1.0)';
      PINUSE='BI';
    'MDA_CA3':
      PIN_NUMBER='(0,0,0,BA59,0,0,0,0,0,0,0,0,0,0,0,0,0,0,0,0,0,0,0,0,0,0,0,0,0,~
0,0,0,0,0,0,0,0,0,0,0)';
      OUTPUT_LOAD='(1.0,-1.0)';
      PINUSE='OUT';
    'MDB_DQS_L9':
      PIN_NUMBER='(0,0,0,BW60,0,0,0,0,0,0,0,0,0,0,0,0,0,0,0,0,0,0,0,0,0,0,0,0,0,~
0,0,0,0,0,0,0,0,0,0,0)';
      BIDIRECTIONAL='TRUE';
      INPUT_LOAD='(-0.01,0.01)';
      OUTPUT_LOAD='(1.0,-1.0)';
      PINUSE='BI';
    'MDB_DQS_H5':
      PIN_NUMBER='(0,0,0,CF58,0,0,0,0,0,0,0,0,0,0,0,0,0,0,0,0,0,0,0,0,0,0,0,0,0,~
0,0,0,0,0,0,0,0,0,0,0)';
      BIDIRECTIONAL='TRUE';
      INPUT_LOAD='(-0.01,0.01)';
      OUTPUT_LOAD='(1.0,-1.0)';
      PINUSE='BI';
    'MDA_DATA22':
      PIN_NUMBER='(0,0,0,AB60,0,0,0,0,0,0,0,0,0,0,0,0,0,0,0,0,0,0,0,0,0,0,0,0,0,~
0,0,0,0,0,0,0,0,0,0,0)';
      BIDIRECTIONAL='TRUE';
      INPUT_LOAD='(-0.01,0.01)';
      OUTPUT_LOAD='(1.0,-1.0)';
      PINUSE='BI';
    'MDA_DATA11':
      PIN_NUMBER='(0,0,0,N59,0,0,0,0,0,0,0,0,0,0,0,0,0,0,0,0,0,0,0,0,0,0,0,0,0,0~
,0,0,0,0,0,0,0,0,0,0)';
      BIDIRECTIONAL='TRUE';
      INPUT_LOAD='(-0.01,0.01)';
      OUTPUT_LOAD='(1.0,-1.0)';
      PINUSE='BI';
    'MDA_CHECK2':
      PIN_NUMBER='(0,0,0,AK60,0,0,0,0,0,0,0,0,0,0,0,0,0,0,0,0,0,0,0,0,0,0,0,0,0,~
0,0,0,0,0,0,0,0,0,0,0)';
      BIDIRECTIONAL='TRUE';
      INPUT_LOAD='(-0.01,0.01)';
      OUTPUT_LOAD='(1.0,-1.0)';
      PINUSE='BI';
    'MDA_CA4':
      PIN_NUMBER='(0,0,0,BA60,0,0,0,0,0,0,0,0,0,0,0,0,0,0,0,0,0,0,0,0,0,0,0,0,0,~
0,0,0,0,0,0,0,0,0,0,0)';
      OUTPUT_LOAD='(1.0,-1.0)';
      PINUSE='OUT';
    'MDB_DQS_H6':
      PIN_NUMBER='(0,0,0,CM58,0,0,0,0,0,0,0,0,0,0,0,0,0,0,0,0,0,0,0,0,0,0,0,0,0,~
0,0,0,0,0,0,0,0,0,0,0)';
      BIDIRECTIONAL='TRUE';
      INPUT_LOAD='(-0.01,0.01)';
      OUTPUT_LOAD='(1.0,-1.0)';
      PINUSE='BI';
    'MDB_CA4':
      PIN_NUMBER='(0,0,0,BJ59,0,0,0,0,0,0,0,0,0,0,0,0,0,0,0,0,0,0,0,0,0,0,0,0,0,~
0,0,0,0,0,0,0,0,0,0,0)';
      OUTPUT_LOAD='(1.0,-1.0)';
      PINUSE='OUT';
    'MDA_DATA23':
      PIN_NUMBER='(0,0,0,AC59,0,0,0,0,0,0,0,0,0,0,0,0,0,0,0,0,0,0,0,0,0,0,0,0,0,~
0,0,0,0,0,0,0,0,0,0,0)';
      BIDIRECTIONAL='TRUE';
      INPUT_LOAD='(-0.01,0.01)';
      OUTPUT_LOAD='(1.0,-1.0)';
      PINUSE='BI';
    'MDA_DATA12':
      PIN_NUMBER='(0,0,0,R60,0,0,0,0,0,0,0,0,0,0,0,0,0,0,0,0,0,0,0,0,0,0,0,0,0,0~
,0,0,0,0,0,0,0,0,0,0)';
      BIDIRECTIONAL='TRUE';
      INPUT_LOAD='(-0.01,0.01)';
      OUTPUT_LOAD='(1.0,-1.0)';
      PINUSE='BI';
    'MDA_CHECK3':
      PIN_NUMBER='(0,0,0,AL59,0,0,0,0,0,0,0,0,0,0,0,0,0,0,0,0,0,0,0,0,0,0,0,0,0,~
0,0,0,0,0,0,0,0,0,0,0)';
      BIDIRECTIONAL='TRUE';
      INPUT_LOAD='(-0.01,0.01)';
      OUTPUT_LOAD='(1.0,-1.0)';
      PINUSE='BI';
    'MDA_CA5':
      PIN_NUMBER='(0,0,0,BB60,0,0,0,0,0,0,0,0,0,0,0,0,0,0,0,0,0,0,0,0,0,0,0,0,0,~
0,0,0,0,0,0,0,0,0,0,0)';
      OUTPUT_LOAD='(1.0,-1.0)';
      PINUSE='OUT';
    'MDB_DQS_H7':
      PIN_NUMBER='(0,0,0,CV58,0,0,0,0,0,0,0,0,0,0,0,0,0,0,0,0,0,0,0,0,0,0,0,0,0,~
0,0,0,0,0,0,0,0,0,0,0)';
      BIDIRECTIONAL='TRUE';
      INPUT_LOAD='(-0.01,0.01)';
      OUTPUT_LOAD='(1.0,-1.0)';
      PINUSE='BI';
    'MDB_CA5':
      PIN_NUMBER='(0,0,0,BK58,0,0,0,0,0,0,0,0,0,0,0,0,0,0,0,0,0,0,0,0,0,0,0,0,0,~
0,0,0,0,0,0,0,0,0,0,0)';
      OUTPUT_LOAD='(1.0,-1.0)';
      PINUSE='OUT';
    'MDB0_CS_L0':
      PIN_NUMBER='(0,0,0,BM58,0,0,0,0,0,0,0,0,0,0,0,0,0,0,0,0,0,0,0,0,0,0,0,0,0,~
0,0,0,0,0,0,0,0,0,0,0)';
      OUTPUT_LOAD='(1.0,-1.0)';
      PINUSE='OUT';
    'MDA_DQS_L0':
      PIN_NUMBER='(0,0,0,H60,0,0,0,0,0,0,0,0,0,0,0,0,0,0,0,0,0,0,0,0,0,0,0,0,0,0~
,0,0,0,0,0,0,0,0,0,0)';
      BIDIRECTIONAL='TRUE';
      INPUT_LOAD='(-0.01,0.01)';
      OUTPUT_LOAD='(1.0,-1.0)';
      PINUSE='BI';
    'MDA_DATA24':
      PIN_NUMBER='(0,0,0,AC60,0,0,0,0,0,0,0,0,0,0,0,0,0,0,0,0,0,0,0,0,0,0,0,0,0,~
0,0,0,0,0,0,0,0,0,0,0)';
      BIDIRECTIONAL='TRUE';
      INPUT_LOAD='(-0.01,0.01)';
      OUTPUT_LOAD='(1.0,-1.0)';
      PINUSE='BI';
    'MDA_DATA13':
      PIN_NUMBER='(0,0,0,T58,0,0,0,0,0,0,0,0,0,0,0,0,0,0,0,0,0,0,0,0,0,0,0,0,0,0~
,0,0,0,0,0,0,0,0,0,0)';
      BIDIRECTIONAL='TRUE';
      INPUT_LOAD='(-0.01,0.01)';
      OUTPUT_LOAD='(1.0,-1.0)';
      PINUSE='BI';
    'MDA_CHECK4':
      PIN_NUMBER='(0,0,0,AN60,0,0,0,0,0,0,0,0,0,0,0,0,0,0,0,0,0,0,0,0,0,0,0,0,0,~
0,0,0,0,0,0,0,0,0,0,0)';
      BIDIRECTIONAL='TRUE';
      INPUT_LOAD='(-0.01,0.01)';
      OUTPUT_LOAD='(1.0,-1.0)';
      PINUSE='BI';
    'MDA_CA6':
      PIN_NUMBER='(0,0,0,BB58,0,0,0,0,0,0,0,0,0,0,0,0,0,0,0,0,0,0,0,0,0,0,0,0,0,~
0,0,0,0,0,0,0,0,0,0,0)';
      OUTPUT_LOAD='(1.0,-1.0)';
      PINUSE='OUT';
    'MDB_DQS_H8':
      PIN_NUMBER='(0,0,0,DD58,0,0,0,0,0,0,0,0,0,0,0,0,0,0,0,0,0,0,0,0,0,0,0,0,0,~
0,0,0,0,0,0,0,0,0,0,0)';
      BIDIRECTIONAL='TRUE';
      INPUT_LOAD='(-0.01,0.01)';
      OUTPUT_LOAD='(1.0,-1.0)';
      PINUSE='BI';
    'MDB_DATA30':
      PIN_NUMBER='(0,0,0,DE60,0,0,0,0,0,0,0,0,0,0,0,0,0,0,0,0,0,0,0,0,0,0,0,0,0,~
0,0,0,0,0,0,0,0,0,0,0)';
      BIDIRECTIONAL='TRUE';
      INPUT_LOAD='(-0.01,0.01)';
      OUTPUT_LOAD='(1.0,-1.0)';
      PINUSE='BI';
    'MDB_CA6':
      PIN_NUMBER='(0,0,0,BK60,0,0,0,0,0,0,0,0,0,0,0,0,0,0,0,0,0,0,0,0,0,0,0,0,0,~
0,0,0,0,0,0,0,0,0,0,0)';
      OUTPUT_LOAD='(1.0,-1.0)';
      PINUSE='OUT';
    'MDB1_CS_L0':
      PIN_NUMBER='(0,0,0,BL59,0,0,0,0,0,0,0,0,0,0,0,0,0,0,0,0,0,0,0,0,0,0,0,0,0,~
0,0,0,0,0,0,0,0,0,0,0)';
      OUTPUT_LOAD='(1.0,-1.0)';
      PINUSE='OUT';
    'MDB0_CS_L1':
      PIN_NUMBER='(0,0,0,BN60,0,0,0,0,0,0,0,0,0,0,0,0,0,0,0,0,0,0,0,0,0,0,0,0,0,~
0,0,0,0,0,0,0,0,0,0,0)';
      OUTPUT_LOAD='(1.0,-1.0)';
      PINUSE='OUT';
    'MDA_DQS_L1':
      PIN_NUMBER='(0,0,0,P60,0,0,0,0,0,0,0,0,0,0,0,0,0,0,0,0,0,0,0,0,0,0,0,0,0,0~
,0,0,0,0,0,0,0,0,0,0)';
      BIDIRECTIONAL='TRUE';
      INPUT_LOAD='(-0.01,0.01)';
      OUTPUT_LOAD='(1.0,-1.0)';
      PINUSE='BI';
    'MDA_DATA25':
      PIN_NUMBER='(0,0,0,AD58,0,0,0,0,0,0,0,0,0,0,0,0,0,0,0,0,0,0,0,0,0,0,0,0,0,~
0,0,0,0,0,0,0,0,0,0,0)';
      BIDIRECTIONAL='TRUE';
      INPUT_LOAD='(-0.01,0.01)';
      OUTPUT_LOAD='(1.0,-1.0)';
      PINUSE='BI';
    'MDA_DATA14':
      PIN_NUMBER='(0,0,0,T60,0,0,0,0,0,0,0,0,0,0,0,0,0,0,0,0,0,0,0,0,0,0,0,0,0,0~
,0,0,0,0,0,0,0,0,0,0)';
      BIDIRECTIONAL='TRUE';
      INPUT_LOAD='(-0.01,0.01)';
      OUTPUT_LOAD='(1.0,-1.0)';
      PINUSE='BI';
    'MDA_CHECK5':
      PIN_NUMBER='(0,0,0,AP58,0,0,0,0,0,0,0,0,0,0,0,0,0,0,0,0,0,0,0,0,0,0,0,0,0,~
0,0,0,0,0,0,0,0,0,0,0)';
      BIDIRECTIONAL='TRUE';
      INPUT_LOAD='(-0.01,0.01)';
      OUTPUT_LOAD='(1.0,-1.0)';
      PINUSE='BI';
    'MDB_DATA31':
      PIN_NUMBER='(0,0,0,DF60,0,0,0,0,0,0,0,0,0,0,0,0,0,0,0,0,0,0,0,0,0,0,0,0,0,~
0,0,0,0,0,0,0,0,0,0,0)';
      BIDIRECTIONAL='TRUE';
      INPUT_LOAD='(-0.01,0.01)';
      OUTPUT_LOAD='(1.0,-1.0)';
      PINUSE='BI';
    'MDB_DATA20':
      PIN_NUMBER='(0,0,0,CV60,0,0,0,0,0,0,0,0,0,0,0,0,0,0,0,0,0,0,0,0,0,0,0,0,0,~
0,0,0,0,0,0,0,0,0,0,0)';
      BIDIRECTIONAL='TRUE';
      INPUT_LOAD='(-0.01,0.01)';
      OUTPUT_LOAD='(1.0,-1.0)';
      PINUSE='BI';
    'MDB_CHECK0':
      PIN_NUMBER='(0,0,0,BY60,0,0,0,0,0,0,0,0,0,0,0,0,0,0,0,0,0,0,0,0,0,0,0,0,0,~
0,0,0,0,0,0,0,0,0,0,0)';
      BIDIRECTIONAL='TRUE';
      INPUT_LOAD='(-0.01,0.01)';
      OUTPUT_LOAD='(1.0,-1.0)';
      PINUSE='BI';
    'MDB1_CS_L1':
      PIN_NUMBER='(0,0,0,BM60,0,0,0,0,0,0,0,0,0,0,0,0,0,0,0,0,0,0,0,0,0,0,0,0,0,~
0,0,0,0,0,0,0,0,0,0,0)';
      OUTPUT_LOAD='(1.0,-1.0)';
      PINUSE='OUT';
    'MDA_DQS_L2':
      PIN_NUMBER='(0,0,0,Y60,0,0,0,0,0,0,0,0,0,0,0,0,0,0,0,0,0,0,0,0,0,0,0,0,0,0~
,0,0,0,0,0,0,0,0,0,0)';
      BIDIRECTIONAL='TRUE';
      INPUT_LOAD='(-0.01,0.01)';
      OUTPUT_LOAD='(1.0,-1.0)';
      PINUSE='BI';
    'MDA_DATA26':
      PIN_NUMBER='(0,0,0,AD60,0,0,0,0,0,0,0,0,0,0,0,0,0,0,0,0,0,0,0,0,0,0,0,0,0,~
0,0,0,0,0,0,0,0,0,0,0)';
      BIDIRECTIONAL='TRUE';
      INPUT_LOAD='(-0.01,0.01)';
      OUTPUT_LOAD='(1.0,-1.0)';
      PINUSE='BI';
    'MDA_DATA15':
      PIN_NUMBER='(0,0,0,U59,0,0,0,0,0,0,0,0,0,0,0,0,0,0,0,0,0,0,0,0,0,0,0,0,0,0~
,0,0,0,0,0,0,0,0,0,0)';
      BIDIRECTIONAL='TRUE';
      INPUT_LOAD='(-0.01,0.01)';
      OUTPUT_LOAD='(1.0,-1.0)';
      PINUSE='BI';
    'MDA_DATA0':
      PIN_NUMBER='(0,0,0,E60,0,0,0,0,0,0,0,0,0,0,0,0,0,0,0,0,0,0,0,0,0,0,0,0,0,0~
,0,0,0,0,0,0,0,0,0,0)';
      BIDIRECTIONAL='TRUE';
      INPUT_LOAD='(-0.01,0.01)';
      OUTPUT_LOAD='(1.0,-1.0)';
      PINUSE='BI';
    'MDA_CHECK6':
      PIN_NUMBER='(0,0,0,AP60,0,0,0,0,0,0,0,0,0,0,0,0,0,0,0,0,0,0,0,0,0,0,0,0,0,~
0,0,0,0,0,0,0,0,0,0,0)';
      BIDIRECTIONAL='TRUE';
      INPUT_LOAD='(-0.01,0.01)';
      OUTPUT_LOAD='(1.0,-1.0)';
      PINUSE='BI';
    'MDB_DATA21':
      PIN_NUMBER='(0,0,0,CW59,0,0,0,0,0,0,0,0,0,0,0,0,0,0,0,0,0,0,0,0,0,0,0,0,0,~
0,0,0,0,0,0,0,0,0,0,0)';
      BIDIRECTIONAL='TRUE';
      INPUT_LOAD='(-0.01,0.01)';
      OUTPUT_LOAD='(1.0,-1.0)';
      PINUSE='BI';
    'MDB_DATA10':
      PIN_NUMBER='(0,0,0,CJ60,0,0,0,0,0,0,0,0,0,0,0,0,0,0,0,0,0,0,0,0,0,0,0,0,0,~
0,0,0,0,0,0,0,0,0,0,0)';
      BIDIRECTIONAL='TRUE';
      INPUT_LOAD='(-0.01,0.01)';
      OUTPUT_LOAD='(1.0,-1.0)';
      PINUSE='BI';
    'MDB_DATA0':
      PIN_NUMBER='(0,0,0,CB60,0,0,0,0,0,0,0,0,0,0,0,0,0,0,0,0,0,0,0,0,0,0,0,0,0,~
0,0,0,0,0,0,0,0,0,0,0)';
      BIDIRECTIONAL='TRUE';
      INPUT_LOAD='(-0.01,0.01)';
      OUTPUT_LOAD='(1.0,-1.0)';
      PINUSE='BI';
    'MDB_CHECK1':
      PIN_NUMBER='(0,0,0,CA59,0,0,0,0,0,0,0,0,0,0,0,0,0,0,0,0,0,0,0,0,0,0,0,0,0,~
0,0,0,0,0,0,0,0,0,0,0)';
      BIDIRECTIONAL='TRUE';
      INPUT_LOAD='(-0.01,0.01)';
      OUTPUT_LOAD='(1.0,-1.0)';
      PINUSE='BI';
    'MDA_DQS_L3':
      PIN_NUMBER='(0,0,0,AF60,0,0,0,0,0,0,0,0,0,0,0,0,0,0,0,0,0,0,0,0,0,0,0,0,0,~
0,0,0,0,0,0,0,0,0,0,0)';
      BIDIRECTIONAL='TRUE';
      INPUT_LOAD='(-0.01,0.01)';
      OUTPUT_LOAD='(1.0,-1.0)';
      PINUSE='BI';
    'MDA_DATA27':
      PIN_NUMBER='(0,0,0,AE59,0,0,0,0,0,0,0,0,0,0,0,0,0,0,0,0,0,0,0,0,0,0,0,0,0,~
0,0,0,0,0,0,0,0,0,0,0)';
      BIDIRECTIONAL='TRUE';
      INPUT_LOAD='(-0.01,0.01)';
      OUTPUT_LOAD='(1.0,-1.0)';
      PINUSE='BI';
    'MDA_DATA16':
      PIN_NUMBER='(0,0,0,U60,0,0,0,0,0,0,0,0,0,0,0,0,0,0,0,0,0,0,0,0,0,0,0,0,0,0~
,0,0,0,0,0,0,0,0,0,0)';
      BIDIRECTIONAL='TRUE';
      INPUT_LOAD='(-0.01,0.01)';
      OUTPUT_LOAD='(1.0,-1.0)';
      PINUSE='BI';
    'MDA_DATA1':
      PIN_NUMBER='(0,0,0,F58,0,0,0,0,0,0,0,0,0,0,0,0,0,0,0,0,0,0,0,0,0,0,0,0,0,0~
,0,0,0,0,0,0,0,0,0,0)';
      BIDIRECTIONAL='TRUE';
      INPUT_LOAD='(-0.01,0.01)';
      OUTPUT_LOAD='(1.0,-1.0)';
      PINUSE='BI';
    'MDA_CHECK7':
      PIN_NUMBER='(0,0,0,AR59,0,0,0,0,0,0,0,0,0,0,0,0,0,0,0,0,0,0,0,0,0,0,0,0,0,~
0,0,0,0,0,0,0,0,0,0,0)';
      BIDIRECTIONAL='TRUE';
      INPUT_LOAD='(-0.01,0.01)';
      OUTPUT_LOAD='(1.0,-1.0)';
      PINUSE='BI';
    'MDA0_RSP_L':
      PIN_NUMBER='(0,0,0,BN59,0,0,0,0,0,0,0,0,0,0,0,0,0,0,0,0,0,0,0,0,0,0,0,0,0,~
0,0,0,0,0,0,0,0,0,0,0)';
      INPUT_LOAD='(-0.01,0.01)';
      PINUSE='IN';
    'MDB_DATA22':
      PIN_NUMBER='(0,0,0,CW60,0,0,0,0,0,0,0,0,0,0,0,0,0,0,0,0,0,0,0,0,0,0,0,0,0,~
0,0,0,0,0,0,0,0,0,0,0)';
      BIDIRECTIONAL='TRUE';
      INPUT_LOAD='(-0.01,0.01)';
      OUTPUT_LOAD='(1.0,-1.0)';
      PINUSE='BI';
    'MDB_DATA11':
      PIN_NUMBER='(0,0,0,CK58,0,0,0,0,0,0,0,0,0,0,0,0,0,0,0,0,0,0,0,0,0,0,0,0,0,~
0,0,0,0,0,0,0,0,0,0,0)';
      BIDIRECTIONAL='TRUE';
      INPUT_LOAD='(-0.01,0.01)';
      OUTPUT_LOAD='(1.0,-1.0)';
      PINUSE='BI';
    'MDB_DATA1':
      PIN_NUMBER='(0,0,0,CC59,0,0,0,0,0,0,0,0,0,0,0,0,0,0,0,0,0,0,0,0,0,0,0,0,0,~
0,0,0,0,0,0,0,0,0,0,0)';
      BIDIRECTIONAL='TRUE';
      INPUT_LOAD='(-0.01,0.01)';
      OUTPUT_LOAD='(1.0,-1.0)';
      PINUSE='BI';
    'MDB_CHECK2':
      PIN_NUMBER='(0,0,0,CA60,0,0,0,0,0,0,0,0,0,0,0,0,0,0,0,0,0,0,0,0,0,0,0,0,0,~
0,0,0,0,0,0,0,0,0,0,0)';
      BIDIRECTIONAL='TRUE';
      INPUT_LOAD='(-0.01,0.01)';
      OUTPUT_LOAD='(1.0,-1.0)';
      PINUSE='BI';
    'MDA_DQS_L4':
      PIN_NUMBER='(0,0,0,AM60,0,0,0,0,0,0,0,0,0,0,0,0,0,0,0,0,0,0,0,0,0,0,0,0,0,~
0,0,0,0,0,0,0,0,0,0,0)';
      BIDIRECTIONAL='TRUE';
      INPUT_LOAD='(-0.01,0.01)';
      OUTPUT_LOAD='(1.0,-1.0)';
      PINUSE='BI';
    'MDA_DQS_H0':
      PIN_NUMBER='(0,0,0,G60,0,0,0,0,0,0,0,0,0,0,0,0,0,0,0,0,0,0,0,0,0,0,0,0,0,0~
,0,0,0,0,0,0,0,0,0,0)';
      BIDIRECTIONAL='TRUE';
      INPUT_LOAD='(-0.01,0.01)';
      OUTPUT_LOAD='(1.0,-1.0)';
      PINUSE='BI';
    'MDA_DATA28':
      PIN_NUMBER='(0,0,0,AG60,0,0,0,0,0,0,0,0,0,0,0,0,0,0,0,0,0,0,0,0,0,0,0,0,0,~
0,0,0,0,0,0,0,0,0,0,0)';
      BIDIRECTIONAL='TRUE';
      INPUT_LOAD='(-0.01,0.01)';
      OUTPUT_LOAD='(1.0,-1.0)';
      PINUSE='BI';
    'MDA_DATA17':
      PIN_NUMBER='(0,0,0,V58,0,0,0,0,0,0,0,0,0,0,0,0,0,0,0,0,0,0,0,0,0,0,0,0,0,0~
,0,0,0,0,0,0,0,0,0,0)';
      BIDIRECTIONAL='TRUE';
      INPUT_LOAD='(-0.01,0.01)';
      OUTPUT_LOAD='(1.0,-1.0)';
      PINUSE='BI';
    'MDA_DATA2':
      PIN_NUMBER='(0,0,0,F60,0,0,0,0,0,0,0,0,0,0,0,0,0,0,0,0,0,0,0,0,0,0,0,0,0,0~
,0,0,0,0,0,0,0,0,0,0)';
      BIDIRECTIONAL='TRUE';
      INPUT_LOAD='(-0.01,0.01)';
      OUTPUT_LOAD='(1.0,-1.0)';
      PINUSE='BI';
    'MDA1_RSP_L':
      PIN_NUMBER='(0,0,0,BP58,0,0,0,0,0,0,0,0,0,0,0,0,0,0,0,0,0,0,0,0,0,0,0,0,0,~
0,0,0,0,0,0,0,0,0,0,0)';
      INPUT_LOAD='(-0.01,0.01)';
      PINUSE='IN';
    'MDA_PAR':
      PIN_NUMBER='(0,0,0,BC59,0,0,0,0,0,0,0,0,0,0,0,0,0,0,0,0,0,0,0,0,0,0,0,0,0,~
0,0,0,0,0,0,0,0,0,0,0)';
      OUTPUT_LOAD='(1.0,-1.0)';
      PINUSE='OUT';
    'MDB_PAR':
      PIN_NUMBER='(0,0,0,BL60,0,0,0,0,0,0,0,0,0,0,0,0,0,0,0,0,0,0,0,0,0,0,0,0,0,~
0,0,0,0,0,0,0,0,0,0,0)';
      OUTPUT_LOAD='(1.0,-1.0)';
      PINUSE='OUT';
    'MDB_CA3':
      PIN_NUMBER='(0,0,0,BJ60,0,0,0,0,0,0,0,0,0,0,0,0,0,0,0,0,0,0,0,0,0,0,0,0,0,~
0,0,0,0,0,0,0,0,0,0,0)';
      OUTPUT_LOAD='(1.0,-1.0)';
      PINUSE='OUT';
    'MDB_DQS_H9':
      PIN_NUMBER='(0,0,0,BV60,0,0,0,0,0,0,0,0,0,0,0,0,0,0,0,0,0,0,0,0,0,0,0,0,0,~
0,0,0,0,0,0,0,0,0,0,0)';
      BIDIRECTIONAL='TRUE';
      INPUT_LOAD='(-0.01,0.01)';
      OUTPUT_LOAD='(1.0,-1.0)';
      PINUSE='BI';
    'MD0_CLK_H':
      PIN_NUMBER='(0,0,0,BC60,0,0,0,0,0,0,0,0,0,0,0,0,0,0,0,0,0,0,0,0,0,0,0,0,0,~
0,0,0,0,0,0,0,0,0,0,0)';
      OUTPUT_LOAD='(1.0,-1.0)';
      PINUSE='OUT';
    'MD0_CLK_L':
      PIN_NUMBER='(0,0,0,BD60,0,0,0,0,0,0,0,0,0,0,0,0,0,0,0,0,0,0,0,0,0,0,0,0,0,~
0,0,0,0,0,0,0,0,0,0,0)';
      OUTPUT_LOAD='(1.0,-1.0)';
      PINUSE='OUT';
    'MD1_CLK_H':
      PIN_NUMBER='(0,0,0,BF60,0,0,0,0,0,0,0,0,0,0,0,0,0,0,0,0,0,0,0,0,0,0,0,0,0,~
0,0,0,0,0,0,0,0,0,0,0)';
      OUTPUT_LOAD='(1.0,-1.0)';
      PINUSE='OUT';
    'MD1_CLK_L':
      PIN_NUMBER='(0,0,0,BG60,0,0,0,0,0,0,0,0,0,0,0,0,0,0,0,0,0,0,0,0,0,0,0,0,0,~
0,0,0,0,0,0,0,0,0,0,0)';
      OUTPUT_LOAD='(1.0,-1.0)';
      PINUSE='OUT';
    'TEST39D':
      PIN_NUMBER='(0,0,0,BF58,0,0,0,0,0,0,0,0,0,0,0,0,0,0,0,0,0,0,0,0,0,0,0,0,0,~
0,0,0,0,0,0,0,0,0,0,0)';
      OUTPUT_LOAD='(1.0,-1.0)';
      PINUSE='OUT';
    'ME_ALERT_L':
      PIN_NUMBER='(0,0,0,0,AT69,0,0,0,0,0,0,0,0,0,0,0,0,0,0,0,0,0,0,0,0,0,0,0,0,~
0,0,0,0,0,0,0,0,0,0,0)';
      INPUT_LOAD='(-0.01,0.01)';
      PINUSE='IN';
    'ME_RESET_L':
      PIN_NUMBER='(0,0,0,0,AU69,0,0,0,0,0,0,0,0,0,0,0,0,0,0,0,0,0,0,0,0,0,0,0,0,~
0,0,0,0,0,0,0,0,0,0,0)';
      OUTPUT_LOAD='(1.0,-1.0)';
      PINUSE='OUT';
    'MEB_DQS_L2':
      PIN_NUMBER='(0,0,0,0,CU71,0,0,0,0,0,0,0,0,0,0,0,0,0,0,0,0,0,0,0,0,0,0,0,0,~
0,0,0,0,0,0,0,0,0,0,0)';
      BIDIRECTIONAL='TRUE';
      INPUT_LOAD='(-0.01,0.01)';
      OUTPUT_LOAD='(1.0,-1.0)';
      PINUSE='BI';
    'MEB_DATA26':
      PIN_NUMBER='(0,0,0,0,DA71,0,0,0,0,0,0,0,0,0,0,0,0,0,0,0,0,0,0,0,0,0,0,0,0,~
0,0,0,0,0,0,0,0,0,0,0)';
      BIDIRECTIONAL='TRUE';
      INPUT_LOAD='(-0.01,0.01)';
      OUTPUT_LOAD='(1.0,-1.0)';
      PINUSE='BI';
    'MEB_DATA15':
      PIN_NUMBER='(0,0,0,0,CP69,0,0,0,0,0,0,0,0,0,0,0,0,0,0,0,0,0,0,0,0,0,0,0,0,~
0,0,0,0,0,0,0,0,0,0,0)';
      BIDIRECTIONAL='TRUE';
      INPUT_LOAD='(-0.01,0.01)';
      OUTPUT_LOAD='(1.0,-1.0)';
      PINUSE='BI';
    'MEB_CHECK6':
      PIN_NUMBER='(0,0,0,0,BU71,0,0,0,0,0,0,0,0,0,0,0,0,0,0,0,0,0,0,0,0,0,0,0,0,~
0,0,0,0,0,0,0,0,0,0,0)';
      BIDIRECTIONAL='TRUE';
      INPUT_LOAD='(-0.01,0.01)';
      OUTPUT_LOAD='(1.0,-1.0)';
      PINUSE='BI';
    'MEA_DQS_L8':
      PIN_NUMBER='(0,0,0,0,AF69,0,0,0,0,0,0,0,0,0,0,0,0,0,0,0,0,0,0,0,0,0,0,0,0,~
0,0,0,0,0,0,0,0,0,0,0)';
      BIDIRECTIONAL='TRUE';
      INPUT_LOAD='(-0.01,0.01)';
      OUTPUT_LOAD='(1.0,-1.0)';
      PINUSE='BI';
    'MEA_DQS_H4':
      PIN_NUMBER='(0,0,0,0,AL71,0,0,0,0,0,0,0,0,0,0,0,0,0,0,0,0,0,0,0,0,0,0,0,0,~
0,0,0,0,0,0,0,0,0,0,0)';
      BIDIRECTIONAL='TRUE';
      INPUT_LOAD='(-0.01,0.01)';
      OUTPUT_LOAD='(1.0,-1.0)';
      PINUSE='BI';
    'MEB_DQS_L3':
      PIN_NUMBER='(0,0,0,0,DC71,0,0,0,0,0,0,0,0,0,0,0,0,0,0,0,0,0,0,0,0,0,0,0,0,~
0,0,0,0,0,0,0,0,0,0,0)';
      BIDIRECTIONAL='TRUE';
      INPUT_LOAD='(-0.01,0.01)';
      OUTPUT_LOAD='(1.0,-1.0)';
      PINUSE='BI';
    'MEB_DATA27':
      PIN_NUMBER='(0,0,0,0,DB69,0,0,0,0,0,0,0,0,0,0,0,0,0,0,0,0,0,0,0,0,0,0,0,0,~
0,0,0,0,0,0,0,0,0,0,0)';
      BIDIRECTIONAL='TRUE';
      INPUT_LOAD='(-0.01,0.01)';
      OUTPUT_LOAD='(1.0,-1.0)';
      PINUSE='BI';
    'MEB_DATA16':
      PIN_NUMBER='(0,0,0,0,CP70,0,0,0,0,0,0,0,0,0,0,0,0,0,0,0,0,0,0,0,0,0,0,0,0,~
0,0,0,0,0,0,0,0,0,0,0)';
      BIDIRECTIONAL='TRUE';
      INPUT_LOAD='(-0.01,0.01)';
      OUTPUT_LOAD='(1.0,-1.0)';
      PINUSE='BI';
    'MEB_CHECK7':
      PIN_NUMBER='(0,0,0,0,BV69,0,0,0,0,0,0,0,0,0,0,0,0,0,0,0,0,0,0,0,0,0,0,0,0,~
0,0,0,0,0,0,0,0,0,0,0)';
      BIDIRECTIONAL='TRUE';
      INPUT_LOAD='(-0.01,0.01)';
      OUTPUT_LOAD='(1.0,-1.0)';
      PINUSE='BI';
    'MEB1_RSP_L':
      PIN_NUMBER='(0,0,0,0,BR71,0,0,0,0,0,0,0,0,0,0,0,0,0,0,0,0,0,0,0,0,0,0,0,0,~
0,0,0,0,0,0,0,0,0,0,0)';
      INPUT_LOAD='(-0.01,0.01)';
      PINUSE='IN';
    'MEB0_RSP_L':
      PIN_NUMBER='(0,0,0,0,BP70,0,0,0,0,0,0,0,0,0,0,0,0,0,0,0,0,0,0,0,0,0,0,0,0,~
0,0,0,0,0,0,0,0,0,0,0)';
      INPUT_LOAD='(-0.01,0.01)';
      PINUSE='IN';
    'MEA_DQS_L9':
      PIN_NUMBER='(0,0,0,0,AM69,0,0,0,0,0,0,0,0,0,0,0,0,0,0,0,0,0,0,0,0,0,0,0,0,~
0,0,0,0,0,0,0,0,0,0,0)';
      BIDIRECTIONAL='TRUE';
      INPUT_LOAD='(-0.01,0.01)';
      OUTPUT_LOAD='(1.0,-1.0)';
      PINUSE='BI';
    'MEA_DQS_H5':
      PIN_NUMBER='(0,0,0,0,J69,0,0,0,0,0,0,0,0,0,0,0,0,0,0,0,0,0,0,0,0,0,0,0,0,0~
,0,0,0,0,0,0,0,0,0,0)';
      BIDIRECTIONAL='TRUE';
      INPUT_LOAD='(-0.01,0.01)';
      OUTPUT_LOAD='(1.0,-1.0)';
      PINUSE='BI';
    'MEB_DQS_L4':
      PIN_NUMBER='(0,0,0,0,BW69,0,0,0,0,0,0,0,0,0,0,0,0,0,0,0,0,0,0,0,0,0,0,0,0,~
0,0,0,0,0,0,0,0,0,0,0)';
      BIDIRECTIONAL='TRUE';
      INPUT_LOAD='(-0.01,0.01)';
      OUTPUT_LOAD='(1.0,-1.0)';
      PINUSE='BI';
    'MEB_DQS_H0':
      PIN_NUMBER='(0,0,0,0,CD70,0,0,0,0,0,0,0,0,0,0,0,0,0,0,0,0,0,0,0,0,0,0,0,0,~
0,0,0,0,0,0,0,0,0,0,0)';
      BIDIRECTIONAL='TRUE';
      INPUT_LOAD='(-0.01,0.01)';
      OUTPUT_LOAD='(1.0,-1.0)';
      PINUSE='BI';
    'MEB_DATA28':
      PIN_NUMBER='(0,0,0,0,DD70,0,0,0,0,0,0,0,0,0,0,0,0,0,0,0,0,0,0,0,0,0,0,0,0,~
0,0,0,0,0,0,0,0,0,0,0)';
      BIDIRECTIONAL='TRUE';
      INPUT_LOAD='(-0.01,0.01)';
      OUTPUT_LOAD='(1.0,-1.0)';
      PINUSE='BI';
    'MEB_DATA17':
      PIN_NUMBER='(0,0,0,0,CR69,0,0,0,0,0,0,0,0,0,0,0,0,0,0,0,0,0,0,0,0,0,0,0,0,~
0,0,0,0,0,0,0,0,0,0,0)';
      BIDIRECTIONAL='TRUE';
      INPUT_LOAD='(-0.01,0.01)';
      OUTPUT_LOAD='(1.0,-1.0)';
      PINUSE='BI';
    'MEA_DQS_H6':
      PIN_NUMBER='(0,0,0,0,R69,0,0,0,0,0,0,0,0,0,0,0,0,0,0,0,0,0,0,0,0,0,0,0,0,0~
,0,0,0,0,0,0,0,0,0,0)';
      BIDIRECTIONAL='TRUE';
      INPUT_LOAD='(-0.01,0.01)';
      OUTPUT_LOAD='(1.0,-1.0)';
      PINUSE='BI';
    'MEB_DQS_L5':
      PIN_NUMBER='(0,0,0,0,CE69,0,0,0,0,0,0,0,0,0,0,0,0,0,0,0,0,0,0,0,0,0,0,0,0,~
0,0,0,0,0,0,0,0,0,0,0)';
      BIDIRECTIONAL='TRUE';
      INPUT_LOAD='(-0.01,0.01)';
      OUTPUT_LOAD='(1.0,-1.0)';
      PINUSE='BI';
    'MEB_DQS_H1':
      PIN_NUMBER='(0,0,0,0,CK70,0,0,0,0,0,0,0,0,0,0,0,0,0,0,0,0,0,0,0,0,0,0,0,0,~
0,0,0,0,0,0,0,0,0,0,0)';
      BIDIRECTIONAL='TRUE';
      INPUT_LOAD='(-0.01,0.01)';
      OUTPUT_LOAD='(1.0,-1.0)';
      PINUSE='BI';
    'MEB_DATA29':
      PIN_NUMBER='(0,0,0,0,DE69,0,0,0,0,0,0,0,0,0,0,0,0,0,0,0,0,0,0,0,0,0,0,0,0,~
0,0,0,0,0,0,0,0,0,0,0)';
      BIDIRECTIONAL='TRUE';
      INPUT_LOAD='(-0.01,0.01)';
      OUTPUT_LOAD='(1.0,-1.0)';
      PINUSE='BI';
    'MEB_DATA18':
      PIN_NUMBER='(0,0,0,0,CR71,0,0,0,0,0,0,0,0,0,0,0,0,0,0,0,0,0,0,0,0,0,0,0,0,~
0,0,0,0,0,0,0,0,0,0,0)';
      BIDIRECTIONAL='TRUE';
      INPUT_LOAD='(-0.01,0.01)';
      OUTPUT_LOAD='(1.0,-1.0)';
      PINUSE='BI';
    'MEA_DQS_H7':
      PIN_NUMBER='(0,0,0,0,AA69,0,0,0,0,0,0,0,0,0,0,0,0,0,0,0,0,0,0,0,0,0,0,0,0,~
0,0,0,0,0,0,0,0,0,0,0)';
      BIDIRECTIONAL='TRUE';
      INPUT_LOAD='(-0.01,0.01)';
      OUTPUT_LOAD='(1.0,-1.0)';
      PINUSE='BI';
    'MEA_DATA0':
      PIN_NUMBER='(0,0,0,0,E71,0,0,0,0,0,0,0,0,0,0,0,0,0,0,0,0,0,0,0,0,0,0,0,0,0~
,0,0,0,0,0,0,0,0,0,0)';
      BIDIRECTIONAL='TRUE';
      INPUT_LOAD='(-0.01,0.01)';
      OUTPUT_LOAD='(1.0,-1.0)';
      PINUSE='BI';
    'MEA1_CS_L0':
      PIN_NUMBER='(0,0,0,0,AU71,0,0,0,0,0,0,0,0,0,0,0,0,0,0,0,0,0,0,0,0,0,0,0,0,~
0,0,0,0,0,0,0,0,0,0,0)';
      OUTPUT_LOAD='(1.0,-1.0)';
      PINUSE='OUT';
    'MEA0_CS_L0':
      PIN_NUMBER='(0,0,0,0,AV70,0,0,0,0,0,0,0,0,0,0,0,0,0,0,0,0,0,0,0,0,0,0,0,0,~
0,0,0,0,0,0,0,0,0,0,0)';
      OUTPUT_LOAD='(1.0,-1.0)';
      PINUSE='OUT';
    'MEB_DQS_L6':
      PIN_NUMBER='(0,0,0,0,CL69,0,0,0,0,0,0,0,0,0,0,0,0,0,0,0,0,0,0,0,0,0,0,0,0,~
0,0,0,0,0,0,0,0,0,0,0)';
      BIDIRECTIONAL='TRUE';
      INPUT_LOAD='(-0.01,0.01)';
      OUTPUT_LOAD='(1.0,-1.0)';
      PINUSE='BI';
    'MEB_DQS_H2':
      PIN_NUMBER='(0,0,0,0,CT70,0,0,0,0,0,0,0,0,0,0,0,0,0,0,0,0,0,0,0,0,0,0,0,0,~
0,0,0,0,0,0,0,0,0,0,0)';
      BIDIRECTIONAL='TRUE';
      INPUT_LOAD='(-0.01,0.01)';
      OUTPUT_LOAD='(1.0,-1.0)';
      PINUSE='BI';
    'MEB_DATA19':
      PIN_NUMBER='(0,0,0,0,CT69,0,0,0,0,0,0,0,0,0,0,0,0,0,0,0,0,0,0,0,0,0,0,0,0,~
0,0,0,0,0,0,0,0,0,0,0)';
      BIDIRECTIONAL='TRUE';
      INPUT_LOAD='(-0.01,0.01)';
      OUTPUT_LOAD='(1.0,-1.0)';
      PINUSE='BI';
    'MEB_DATA0':
      PIN_NUMBER='(0,0,0,0,CB70,0,0,0,0,0,0,0,0,0,0,0,0,0,0,0,0,0,0,0,0,0,0,0,0,~
0,0,0,0,0,0,0,0,0,0,0)';
      BIDIRECTIONAL='TRUE';
      INPUT_LOAD='(-0.01,0.01)';
      OUTPUT_LOAD='(1.0,-1.0)';
      PINUSE='BI';
    'MEA_DQS_H8':
      PIN_NUMBER='(0,0,0,0,AG69,0,0,0,0,0,0,0,0,0,0,0,0,0,0,0,0,0,0,0,0,0,0,0,0,~
0,0,0,0,0,0,0,0,0,0,0)';
      BIDIRECTIONAL='TRUE';
      INPUT_LOAD='(-0.01,0.01)';
      OUTPUT_LOAD='(1.0,-1.0)';
      PINUSE='BI';
    'MEA_DATA30':
      PIN_NUMBER='(0,0,0,0,AH70,0,0,0,0,0,0,0,0,0,0,0,0,0,0,0,0,0,0,0,0,0,0,0,0,~
0,0,0,0,0,0,0,0,0,0,0)';
      BIDIRECTIONAL='TRUE';
      INPUT_LOAD='(-0.01,0.01)';
      OUTPUT_LOAD='(1.0,-1.0)';
      PINUSE='BI';
    'MEA_DATA1':
      PIN_NUMBER='(0,0,0,0,F69,0,0,0,0,0,0,0,0,0,0,0,0,0,0,0,0,0,0,0,0,0,0,0,0,0~
,0,0,0,0,0,0,0,0,0,0)';
      BIDIRECTIONAL='TRUE';
      INPUT_LOAD='(-0.01,0.01)';
      OUTPUT_LOAD='(1.0,-1.0)';
      PINUSE='BI';
    'MEA1_CS_L1':
      PIN_NUMBER='(0,0,0,0,AV69,0,0,0,0,0,0,0,0,0,0,0,0,0,0,0,0,0,0,0,0,0,0,0,0,~
0,0,0,0,0,0,0,0,0,0,0)';
      OUTPUT_LOAD='(1.0,-1.0)';
      PINUSE='OUT';
    'MEA0_CS_L1':
      PIN_NUMBER='(0,0,0,0,AW69,0,0,0,0,0,0,0,0,0,0,0,0,0,0,0,0,0,0,0,0,0,0,0,0,~
0,0,0,0,0,0,0,0,0,0,0)';
      OUTPUT_LOAD='(1.0,-1.0)';
      PINUSE='OUT';
    'MEB_DQS_L7':
      PIN_NUMBER='(0,0,0,0,CU69,0,0,0,0,0,0,0,0,0,0,0,0,0,0,0,0,0,0,0,0,0,0,0,0,~
0,0,0,0,0,0,0,0,0,0,0)';
      BIDIRECTIONAL='TRUE';
      INPUT_LOAD='(-0.01,0.01)';
      OUTPUT_LOAD='(1.0,-1.0)';
      PINUSE='BI';
    'MEB_DQS_H3':
      PIN_NUMBER='(0,0,0,0,DB70,0,0,0,0,0,0,0,0,0,0,0,0,0,0,0,0,0,0,0,0,0,0,0,0,~
0,0,0,0,0,0,0,0,0,0,0)';
      BIDIRECTIONAL='TRUE';
      INPUT_LOAD='(-0.01,0.01)';
      OUTPUT_LOAD='(1.0,-1.0)';
      PINUSE='BI';
    'MEB_DATA1':
      PIN_NUMBER='(0,0,0,0,CC69,0,0,0,0,0,0,0,0,0,0,0,0,0,0,0,0,0,0,0,0,0,0,0,0,~
0,0,0,0,0,0,0,0,0,0,0)';
      BIDIRECTIONAL='TRUE';
      INPUT_LOAD='(-0.01,0.01)';
      OUTPUT_LOAD='(1.0,-1.0)';
      PINUSE='BI';
    'MEA_DQS_H9':
      PIN_NUMBER='(0,0,0,0,AN69,0,0,0,0,0,0,0,0,0,0,0,0,0,0,0,0,0,0,0,0,0,0,0,0,~
0,0,0,0,0,0,0,0,0,0,0)';
      BIDIRECTIONAL='TRUE';
      INPUT_LOAD='(-0.01,0.01)';
      OUTPUT_LOAD='(1.0,-1.0)';
      PINUSE='BI';
    'MEA_DATA31':
      PIN_NUMBER='(0,0,0,0,AJ69,0,0,0,0,0,0,0,0,0,0,0,0,0,0,0,0,0,0,0,0,0,0,0,0,~
0,0,0,0,0,0,0,0,0,0,0)';
      BIDIRECTIONAL='TRUE';
      INPUT_LOAD='(-0.01,0.01)';
      OUTPUT_LOAD='(1.0,-1.0)';
      PINUSE='BI';
    'MEA_DATA20':
      PIN_NUMBER='(0,0,0,0,AA71,0,0,0,0,0,0,0,0,0,0,0,0,0,0,0,0,0,0,0,0,0,0,0,0,~
0,0,0,0,0,0,0,0,0,0,0)';
      BIDIRECTIONAL='TRUE';
      INPUT_LOAD='(-0.01,0.01)';
      OUTPUT_LOAD='(1.0,-1.0)';
      PINUSE='BI';
    'MEA_DATA2':
      PIN_NUMBER='(0,0,0,0,F70,0,0,0,0,0,0,0,0,0,0,0,0,0,0,0,0,0,0,0,0,0,0,0,0,0~
,0,0,0,0,0,0,0,0,0,0)';
      BIDIRECTIONAL='TRUE';
      INPUT_LOAD='(-0.01,0.01)';
      OUTPUT_LOAD='(1.0,-1.0)';
      PINUSE='BI';
    'MEA_CHECK0':
      PIN_NUMBER='(0,0,0,0,AJ71,0,0,0,0,0,0,0,0,0,0,0,0,0,0,0,0,0,0,0,0,0,0,0,0,~
0,0,0,0,0,0,0,0,0,0,0)';
      BIDIRECTIONAL='TRUE';
      INPUT_LOAD='(-0.01,0.01)';
      OUTPUT_LOAD='(1.0,-1.0)';
      PINUSE='BI';
    'MEA_CA0':
      PIN_NUMBER='(0,0,0,0,AW71,0,0,0,0,0,0,0,0,0,0,0,0,0,0,0,0,0,0,0,0,0,0,0,0,~
0,0,0,0,0,0,0,0,0,0,0)';
      OUTPUT_LOAD='(1.0,-1.0)';
      PINUSE='OUT';
    'MEB_DQS_L8':
      PIN_NUMBER='(0,0,0,0,DC69,0,0,0,0,0,0,0,0,0,0,0,0,0,0,0,0,0,0,0,0,0,0,0,0,~
0,0,0,0,0,0,0,0,0,0,0)';
      BIDIRECTIONAL='TRUE';
      INPUT_LOAD='(-0.01,0.01)';
      OUTPUT_LOAD='(1.0,-1.0)';
      PINUSE='BI';
    'MEB_DQS_H4':
      PIN_NUMBER='(0,0,0,0,BY69,0,0,0,0,0,0,0,0,0,0,0,0,0,0,0,0,0,0,0,0,0,0,0,0,~
0,0,0,0,0,0,0,0,0,0,0)';
      BIDIRECTIONAL='TRUE';
      INPUT_LOAD='(-0.01,0.01)';
      OUTPUT_LOAD='(1.0,-1.0)';
      PINUSE='BI';
    'MEB_DATA2':
      PIN_NUMBER='(0,0,0,0,CC71,0,0,0,0,0,0,0,0,0,0,0,0,0,0,0,0,0,0,0,0,0,0,0,0,~
0,0,0,0,0,0,0,0,0,0,0)';
      BIDIRECTIONAL='TRUE';
      INPUT_LOAD='(-0.01,0.01)';
      OUTPUT_LOAD='(1.0,-1.0)';
      PINUSE='BI';
    'MEB_CA0':
      PIN_NUMBER='(0,0,0,0,BG69,0,0,0,0,0,0,0,0,0,0,0,0,0,0,0,0,0,0,0,0,0,0,0,0,~
0,0,0,0,0,0,0,0,0,0,0)';
      OUTPUT_LOAD='(1.0,-1.0)';
      PINUSE='OUT';
    'MEA_DATA21':
      PIN_NUMBER='(0,0,0,0,AB69,0,0,0,0,0,0,0,0,0,0,0,0,0,0,0,0,0,0,0,0,0,0,0,0,~
0,0,0,0,0,0,0,0,0,0,0)';
      BIDIRECTIONAL='TRUE';
      INPUT_LOAD='(-0.01,0.01)';
      OUTPUT_LOAD='(1.0,-1.0)';
      PINUSE='BI';
    'MEA_DATA10':
      PIN_NUMBER='(0,0,0,0,M70,0,0,0,0,0,0,0,0,0,0,0,0,0,0,0,0,0,0,0,0,0,0,0,0,0~
,0,0,0,0,0,0,0,0,0,0)';
      BIDIRECTIONAL='TRUE';
      INPUT_LOAD='(-0.01,0.01)';
      OUTPUT_LOAD='(1.0,-1.0)';
      PINUSE='BI';
    'MEA_DATA3':
      PIN_NUMBER='(0,0,0,0,G69,0,0,0,0,0,0,0,0,0,0,0,0,0,0,0,0,0,0,0,0,0,0,0,0,0~
,0,0,0,0,0,0,0,0,0,0)';
      BIDIRECTIONAL='TRUE';
      INPUT_LOAD='(-0.01,0.01)';
      OUTPUT_LOAD='(1.0,-1.0)';
      PINUSE='BI';
    'MEA_CHECK1':
      PIN_NUMBER='(0,0,0,0,AK69,0,0,0,0,0,0,0,0,0,0,0,0,0,0,0,0,0,0,0,0,0,0,0,0,~
0,0,0,0,0,0,0,0,0,0,0)';
      BIDIRECTIONAL='TRUE';
      INPUT_LOAD='(-0.01,0.01)';
      OUTPUT_LOAD='(1.0,-1.0)';
      PINUSE='BI';
    'MEA_CA1':
      PIN_NUMBER='(0,0,0,0,AY70,0,0,0,0,0,0,0,0,0,0,0,0,0,0,0,0,0,0,0,0,0,0,0,0,~
0,0,0,0,0,0,0,0,0,0,0)';
      OUTPUT_LOAD='(1.0,-1.0)';
      PINUSE='OUT';
    'MEB_DQS_L9':
      PIN_NUMBER='(0,0,0,0,BW71,0,0,0,0,0,0,0,0,0,0,0,0,0,0,0,0,0,0,0,0,0,0,0,0,~
0,0,0,0,0,0,0,0,0,0,0)';
      BIDIRECTIONAL='TRUE';
      INPUT_LOAD='(-0.01,0.01)';
      OUTPUT_LOAD='(1.0,-1.0)';
      PINUSE='BI';
    'MEB_DQS_H5':
      PIN_NUMBER='(0,0,0,0,CF69,0,0,0,0,0,0,0,0,0,0,0,0,0,0,0,0,0,0,0,0,0,0,0,0,~
0,0,0,0,0,0,0,0,0,0,0)';
      BIDIRECTIONAL='TRUE';
      INPUT_LOAD='(-0.01,0.01)';
      OUTPUT_LOAD='(1.0,-1.0)';
      PINUSE='BI';
    'MEB_DATA3':
      PIN_NUMBER='(0,0,0,0,CD69,0,0,0,0,0,0,0,0,0,0,0,0,0,0,0,0,0,0,0,0,0,0,0,0,~
0,0,0,0,0,0,0,0,0,0,0)';
      BIDIRECTIONAL='TRUE';
      INPUT_LOAD='(-0.01,0.01)';
      OUTPUT_LOAD='(1.0,-1.0)';
      PINUSE='BI';
    'MEB_CA1':
      PIN_NUMBER='(0,0,0,0,BH69,0,0,0,0,0,0,0,0,0,0,0,0,0,0,0,0,0,0,0,0,0,0,0,0,~
0,0,0,0,0,0,0,0,0,0,0)';
      OUTPUT_LOAD='(1.0,-1.0)';
      PINUSE='OUT';
    'MEA_DATA22':
      PIN_NUMBER='(0,0,0,0,AB70,0,0,0,0,0,0,0,0,0,0,0,0,0,0,0,0,0,0,0,0,0,0,0,0,~
0,0,0,0,0,0,0,0,0,0,0)';
      BIDIRECTIONAL='TRUE';
      INPUT_LOAD='(-0.01,0.01)';
      OUTPUT_LOAD='(1.0,-1.0)';
      PINUSE='BI';
    'MEA_DATA11':
      PIN_NUMBER='(0,0,0,0,N69,0,0,0,0,0,0,0,0,0,0,0,0,0,0,0,0,0,0,0,0,0,0,0,0,0~
,0,0,0,0,0,0,0,0,0,0)';
      BIDIRECTIONAL='TRUE';
      INPUT_LOAD='(-0.01,0.01)';
      OUTPUT_LOAD='(1.0,-1.0)';
      PINUSE='BI';
    'MEA_DATA4':
      PIN_NUMBER='(0,0,0,0,J71,0,0,0,0,0,0,0,0,0,0,0,0,0,0,0,0,0,0,0,0,0,0,0,0,0~
,0,0,0,0,0,0,0,0,0,0)';
      BIDIRECTIONAL='TRUE';
      INPUT_LOAD='(-0.01,0.01)';
      OUTPUT_LOAD='(1.0,-1.0)';
      PINUSE='BI';
    'MEA_CHECK2':
      PIN_NUMBER='(0,0,0,0,AK70,0,0,0,0,0,0,0,0,0,0,0,0,0,0,0,0,0,0,0,0,0,0,0,0,~
0,0,0,0,0,0,0,0,0,0,0)';
      BIDIRECTIONAL='TRUE';
      INPUT_LOAD='(-0.01,0.01)';
      OUTPUT_LOAD='(1.0,-1.0)';
      PINUSE='BI';
    'MEA_CA2':
      PIN_NUMBER='(0,0,0,0,AY69,0,0,0,0,0,0,0,0,0,0,0,0,0,0,0,0,0,0,0,0,0,0,0,0,~
0,0,0,0,0,0,0,0,0,0,0)';
      OUTPUT_LOAD='(1.0,-1.0)';
      PINUSE='OUT';
    'MEB_DQS_H6':
      PIN_NUMBER='(0,0,0,0,CM69,0,0,0,0,0,0,0,0,0,0,0,0,0,0,0,0,0,0,0,0,0,0,0,0,~
0,0,0,0,0,0,0,0,0,0,0)';
      BIDIRECTIONAL='TRUE';
      INPUT_LOAD='(-0.01,0.01)';
      OUTPUT_LOAD='(1.0,-1.0)';
      PINUSE='BI';
    'MEB_DATA4':
      PIN_NUMBER='(0,0,0,0,CF70,0,0,0,0,0,0,0,0,0,0,0,0,0,0,0,0,0,0,0,0,0,0,0,0,~
0,0,0,0,0,0,0,0,0,0,0)';
      BIDIRECTIONAL='TRUE';
      INPUT_LOAD='(-0.01,0.01)';
      OUTPUT_LOAD='(1.0,-1.0)';
      PINUSE='BI';
    'MEB_CA2':
      PIN_NUMBER='(0,0,0,0,BH70,0,0,0,0,0,0,0,0,0,0,0,0,0,0,0,0,0,0,0,0,0,0,0,0,~
0,0,0,0,0,0,0,0,0,0,0)';
      OUTPUT_LOAD='(1.0,-1.0)';
      PINUSE='OUT';
    'MEA_DATA23':
      PIN_NUMBER='(0,0,0,0,AC69,0,0,0,0,0,0,0,0,0,0,0,0,0,0,0,0,0,0,0,0,0,0,0,0,~
0,0,0,0,0,0,0,0,0,0,0)';
      BIDIRECTIONAL='TRUE';
      INPUT_LOAD='(-0.01,0.01)';
      OUTPUT_LOAD='(1.0,-1.0)';
      PINUSE='BI';
    'MEA_DATA12':
      PIN_NUMBER='(0,0,0,0,R71,0,0,0,0,0,0,0,0,0,0,0,0,0,0,0,0,0,0,0,0,0,0,0,0,0~
,0,0,0,0,0,0,0,0,0,0)';
      BIDIRECTIONAL='TRUE';
      INPUT_LOAD='(-0.01,0.01)';
      OUTPUT_LOAD='(1.0,-1.0)';
      PINUSE='BI';
    'MEA_DATA5':
      PIN_NUMBER='(0,0,0,0,K69,0,0,0,0,0,0,0,0,0,0,0,0,0,0,0,0,0,0,0,0,0,0,0,0,0~
,0,0,0,0,0,0,0,0,0,0)';
      BIDIRECTIONAL='TRUE';
      INPUT_LOAD='(-0.01,0.01)';
      OUTPUT_LOAD='(1.0,-1.0)';
      PINUSE='BI';
    'MEA_CHECK3':
      PIN_NUMBER='(0,0,0,0,AL69,0,0,0,0,0,0,0,0,0,0,0,0,0,0,0,0,0,0,0,0,0,0,0,0,~
0,0,0,0,0,0,0,0,0,0,0)';
      BIDIRECTIONAL='TRUE';
      INPUT_LOAD='(-0.01,0.01)';
      OUTPUT_LOAD='(1.0,-1.0)';
      PINUSE='BI';
    'MEA_CA3':
      PIN_NUMBER='(0,0,0,0,BA69,0,0,0,0,0,0,0,0,0,0,0,0,0,0,0,0,0,0,0,0,0,0,0,0,~
0,0,0,0,0,0,0,0,0,0,0)';
      OUTPUT_LOAD='(1.0,-1.0)';
      PINUSE='OUT';
    'MEB_DQS_H7':
      PIN_NUMBER='(0,0,0,0,CV69,0,0,0,0,0,0,0,0,0,0,0,0,0,0,0,0,0,0,0,0,0,0,0,0,~
0,0,0,0,0,0,0,0,0,0,0)';
      BIDIRECTIONAL='TRUE';
      INPUT_LOAD='(-0.01,0.01)';
      OUTPUT_LOAD='(1.0,-1.0)';
      PINUSE='BI';
    'MEB_DATA5':
      PIN_NUMBER='(0,0,0,0,CG69,0,0,0,0,0,0,0,0,0,0,0,0,0,0,0,0,0,0,0,0,0,0,0,0,~
0,0,0,0,0,0,0,0,0,0,0)';
      BIDIRECTIONAL='TRUE';
      INPUT_LOAD='(-0.01,0.01)';
      OUTPUT_LOAD='(1.0,-1.0)';
      PINUSE='BI';
    'MEB_CA3':
      PIN_NUMBER='(0,0,0,0,BJ71,0,0,0,0,0,0,0,0,0,0,0,0,0,0,0,0,0,0,0,0,0,0,0,0,~
0,0,0,0,0,0,0,0,0,0,0)';
      OUTPUT_LOAD='(1.0,-1.0)';
      PINUSE='OUT';
    'MEB1_CS_L0':
      PIN_NUMBER='(0,0,0,0,BL69,0,0,0,0,0,0,0,0,0,0,0,0,0,0,0,0,0,0,0,0,0,0,0,0,~
0,0,0,0,0,0,0,0,0,0,0)';
      OUTPUT_LOAD='(1.0,-1.0)';
      PINUSE='OUT';
    'MEB0_CS_L0':
      PIN_NUMBER='(0,0,0,0,BM69,0,0,0,0,0,0,0,0,0,0,0,0,0,0,0,0,0,0,0,0,0,0,0,0,~
0,0,0,0,0,0,0,0,0,0,0)';
      OUTPUT_LOAD='(1.0,-1.0)';
      PINUSE='OUT';
    'MEA_DQS_L0':
      PIN_NUMBER='(0,0,0,0,H70,0,0,0,0,0,0,0,0,0,0,0,0,0,0,0,0,0,0,0,0,0,0,0,0,0~
,0,0,0,0,0,0,0,0,0,0)';
      BIDIRECTIONAL='TRUE';
      INPUT_LOAD='(-0.01,0.01)';
      OUTPUT_LOAD='(1.0,-1.0)';
      PINUSE='BI';
    'MEA_DATA24':
      PIN_NUMBER='(0,0,0,0,AC71,0,0,0,0,0,0,0,0,0,0,0,0,0,0,0,0,0,0,0,0,0,0,0,0,~
0,0,0,0,0,0,0,0,0,0,0)';
      BIDIRECTIONAL='TRUE';
      INPUT_LOAD='(-0.01,0.01)';
      OUTPUT_LOAD='(1.0,-1.0)';
      PINUSE='BI';
    'MEA_DATA13':
      PIN_NUMBER='(0,0,0,0,T69,0,0,0,0,0,0,0,0,0,0,0,0,0,0,0,0,0,0,0,0,0,0,0,0,0~
,0,0,0,0,0,0,0,0,0,0)';
      BIDIRECTIONAL='TRUE';
      INPUT_LOAD='(-0.01,0.01)';
      OUTPUT_LOAD='(1.0,-1.0)';
      PINUSE='BI';
    'MEA_DATA6':
      PIN_NUMBER='(0,0,0,0,K70,0,0,0,0,0,0,0,0,0,0,0,0,0,0,0,0,0,0,0,0,0,0,0,0,0~
,0,0,0,0,0,0,0,0,0,0)';
      BIDIRECTIONAL='TRUE';
      INPUT_LOAD='(-0.01,0.01)';
      OUTPUT_LOAD='(1.0,-1.0)';
      PINUSE='BI';
    'MEA_CHECK4':
      PIN_NUMBER='(0,0,0,0,AN71,0,0,0,0,0,0,0,0,0,0,0,0,0,0,0,0,0,0,0,0,0,0,0,0,~
0,0,0,0,0,0,0,0,0,0,0)';
      BIDIRECTIONAL='TRUE';
      INPUT_LOAD='(-0.01,0.01)';
      OUTPUT_LOAD='(1.0,-1.0)';
      PINUSE='BI';
    'MEA_CA4':
      PIN_NUMBER='(0,0,0,0,BA71,0,0,0,0,0,0,0,0,0,0,0,0,0,0,0,0,0,0,0,0,0,0,0,0,~
0,0,0,0,0,0,0,0,0,0,0)';
      OUTPUT_LOAD='(1.0,-1.0)';
      PINUSE='OUT';
    'MEB_DQS_H8':
      PIN_NUMBER='(0,0,0,0,DD69,0,0,0,0,0,0,0,0,0,0,0,0,0,0,0,0,0,0,0,0,0,0,0,0,~
0,0,0,0,0,0,0,0,0,0,0)';
      BIDIRECTIONAL='TRUE';
      INPUT_LOAD='(-0.01,0.01)';
      OUTPUT_LOAD='(1.0,-1.0)';
      PINUSE='BI';
    'MEB_DATA30':
      PIN_NUMBER='(0,0,0,0,DE71,0,0,0,0,0,0,0,0,0,0,0,0,0,0,0,0,0,0,0,0,0,0,0,0,~
0,0,0,0,0,0,0,0,0,0,0)';
      BIDIRECTIONAL='TRUE';
      INPUT_LOAD='(-0.01,0.01)';
      OUTPUT_LOAD='(1.0,-1.0)';
      PINUSE='BI';
    'MEB_DATA6':
      PIN_NUMBER='(0,0,0,0,CG71,0,0,0,0,0,0,0,0,0,0,0,0,0,0,0,0,0,0,0,0,0,0,0,0,~
0,0,0,0,0,0,0,0,0,0,0)';
      BIDIRECTIONAL='TRUE';
      INPUT_LOAD='(-0.01,0.01)';
      OUTPUT_LOAD='(1.0,-1.0)';
      PINUSE='BI';
    'MEB_CA4':
      PIN_NUMBER='(0,0,0,0,BJ69,0,0,0,0,0,0,0,0,0,0,0,0,0,0,0,0,0,0,0,0,0,0,0,0,~
0,0,0,0,0,0,0,0,0,0,0)';
      OUTPUT_LOAD='(1.0,-1.0)';
      PINUSE='OUT';
    'MEB1_CS_L1':
      PIN_NUMBER='(0,0,0,0,BM70,0,0,0,0,0,0,0,0,0,0,0,0,0,0,0,0,0,0,0,0,0,0,0,0,~
0,0,0,0,0,0,0,0,0,0,0)';
      OUTPUT_LOAD='(1.0,-1.0)';
      PINUSE='OUT';
    'MEB0_CS_L1':
      PIN_NUMBER='(0,0,0,0,BN71,0,0,0,0,0,0,0,0,0,0,0,0,0,0,0,0,0,0,0,0,0,0,0,0,~
0,0,0,0,0,0,0,0,0,0,0)';
      OUTPUT_LOAD='(1.0,-1.0)';
      PINUSE='OUT';
    'MEA_DQS_L1':
      PIN_NUMBER='(0,0,0,0,P70,0,0,0,0,0,0,0,0,0,0,0,0,0,0,0,0,0,0,0,0,0,0,0,0,0~
,0,0,0,0,0,0,0,0,0,0)';
      BIDIRECTIONAL='TRUE';
      INPUT_LOAD='(-0.01,0.01)';
      OUTPUT_LOAD='(1.0,-1.0)';
      PINUSE='BI';
    'MEA_DATA25':
      PIN_NUMBER='(0,0,0,0,AD69,0,0,0,0,0,0,0,0,0,0,0,0,0,0,0,0,0,0,0,0,0,0,0,0,~
0,0,0,0,0,0,0,0,0,0,0)';
      BIDIRECTIONAL='TRUE';
      INPUT_LOAD='(-0.01,0.01)';
      OUTPUT_LOAD='(1.0,-1.0)';
      PINUSE='BI';
    'MEA_DATA14':
      PIN_NUMBER='(0,0,0,0,T70,0,0,0,0,0,0,0,0,0,0,0,0,0,0,0,0,0,0,0,0,0,0,0,0,0~
,0,0,0,0,0,0,0,0,0,0)';
      BIDIRECTIONAL='TRUE';
      INPUT_LOAD='(-0.01,0.01)';
      OUTPUT_LOAD='(1.0,-1.0)';
      PINUSE='BI';
    'MEA_DATA7':
      PIN_NUMBER='(0,0,0,0,L69,0,0,0,0,0,0,0,0,0,0,0,0,0,0,0,0,0,0,0,0,0,0,0,0,0~
,0,0,0,0,0,0,0,0,0,0)';
      BIDIRECTIONAL='TRUE';
      INPUT_LOAD='(-0.01,0.01)';
      OUTPUT_LOAD='(1.0,-1.0)';
      PINUSE='BI';
    'MEA_CHECK5':
      PIN_NUMBER='(0,0,0,0,AP69,0,0,0,0,0,0,0,0,0,0,0,0,0,0,0,0,0,0,0,0,0,0,0,0,~
0,0,0,0,0,0,0,0,0,0,0)';
      BIDIRECTIONAL='TRUE';
      INPUT_LOAD='(-0.01,0.01)';
      OUTPUT_LOAD='(1.0,-1.0)';
      PINUSE='BI';
    'MEA_CA5':
      PIN_NUMBER='(0,0,0,0,BB70,0,0,0,0,0,0,0,0,0,0,0,0,0,0,0,0,0,0,0,0,0,0,0,0,~
0,0,0,0,0,0,0,0,0,0,0)';
      OUTPUT_LOAD='(1.0,-1.0)';
      PINUSE='OUT';
    'MEB_DATA31':
      PIN_NUMBER='(0,0,0,0,DF69,0,0,0,0,0,0,0,0,0,0,0,0,0,0,0,0,0,0,0,0,0,0,0,0,~
0,0,0,0,0,0,0,0,0,0,0)';
      BIDIRECTIONAL='TRUE';
      INPUT_LOAD='(-0.01,0.01)';
      OUTPUT_LOAD='(1.0,-1.0)';
      PINUSE='BI';
    'MEB_DATA20':
      PIN_NUMBER='(0,0,0,0,CV70,0,0,0,0,0,0,0,0,0,0,0,0,0,0,0,0,0,0,0,0,0,0,0,0,~
0,0,0,0,0,0,0,0,0,0,0)';
      BIDIRECTIONAL='TRUE';
      INPUT_LOAD='(-0.01,0.01)';
      OUTPUT_LOAD='(1.0,-1.0)';
      PINUSE='BI';
    'MEB_DATA7':
      PIN_NUMBER='(0,0,0,0,CH69,0,0,0,0,0,0,0,0,0,0,0,0,0,0,0,0,0,0,0,0,0,0,0,0,~
0,0,0,0,0,0,0,0,0,0,0)';
      BIDIRECTIONAL='TRUE';
      INPUT_LOAD='(-0.01,0.01)';
      OUTPUT_LOAD='(1.0,-1.0)';
      PINUSE='BI';
    'MEB_CHECK0':
      PIN_NUMBER='(0,0,0,0,BY70,0,0,0,0,0,0,0,0,0,0,0,0,0,0,0,0,0,0,0,0,0,0,0,0,~
0,0,0,0,0,0,0,0,0,0,0)';
      BIDIRECTIONAL='TRUE';
      INPUT_LOAD='(-0.01,0.01)';
      OUTPUT_LOAD='(1.0,-1.0)';
      PINUSE='BI';
    'MEB_CA5':
      PIN_NUMBER='(0,0,0,0,BK69,0,0,0,0,0,0,0,0,0,0,0,0,0,0,0,0,0,0,0,0,0,0,0,0,~
0,0,0,0,0,0,0,0,0,0,0)';
      OUTPUT_LOAD='(1.0,-1.0)';
      PINUSE='OUT';
    'MEA_DQS_L2':
      PIN_NUMBER='(0,0,0,0,Y70,0,0,0,0,0,0,0,0,0,0,0,0,0,0,0,0,0,0,0,0,0,0,0,0,0~
,0,0,0,0,0,0,0,0,0,0)';
      BIDIRECTIONAL='TRUE';
      INPUT_LOAD='(-0.01,0.01)';
      OUTPUT_LOAD='(1.0,-1.0)';
      PINUSE='BI';
    'MEA_DATA26':
      PIN_NUMBER='(0,0,0,0,AD70,0,0,0,0,0,0,0,0,0,0,0,0,0,0,0,0,0,0,0,0,0,0,0,0,~
0,0,0,0,0,0,0,0,0,0,0)';
      BIDIRECTIONAL='TRUE';
      INPUT_LOAD='(-0.01,0.01)';
      OUTPUT_LOAD='(1.0,-1.0)';
      PINUSE='BI';
    'MEA_DATA15':
      PIN_NUMBER='(0,0,0,0,U69,0,0,0,0,0,0,0,0,0,0,0,0,0,0,0,0,0,0,0,0,0,0,0,0,0~
,0,0,0,0,0,0,0,0,0,0)';
      BIDIRECTIONAL='TRUE';
      INPUT_LOAD='(-0.01,0.01)';
      OUTPUT_LOAD='(1.0,-1.0)';
      PINUSE='BI';
    'MEA_DATA8':
      PIN_NUMBER='(0,0,0,0,L71,0,0,0,0,0,0,0,0,0,0,0,0,0,0,0,0,0,0,0,0,0,0,0,0,0~
,0,0,0,0,0,0,0,0,0,0)';
      BIDIRECTIONAL='TRUE';
      INPUT_LOAD='(-0.01,0.01)';
      OUTPUT_LOAD='(1.0,-1.0)';
      PINUSE='BI';
    'MEA_CHECK6':
      PIN_NUMBER='(0,0,0,0,AP70,0,0,0,0,0,0,0,0,0,0,0,0,0,0,0,0,0,0,0,0,0,0,0,0,~
0,0,0,0,0,0,0,0,0,0,0)';
      BIDIRECTIONAL='TRUE';
      INPUT_LOAD='(-0.01,0.01)';
      OUTPUT_LOAD='(1.0,-1.0)';
      PINUSE='BI';
    'MEA_CA6':
      PIN_NUMBER='(0,0,0,0,BB69,0,0,0,0,0,0,0,0,0,0,0,0,0,0,0,0,0,0,0,0,0,0,0,0,~
0,0,0,0,0,0,0,0,0,0,0)';
      OUTPUT_LOAD='(1.0,-1.0)';
      PINUSE='OUT';
    'MEB_DATA21':
      PIN_NUMBER='(0,0,0,0,CW69,0,0,0,0,0,0,0,0,0,0,0,0,0,0,0,0,0,0,0,0,0,0,0,0,~
0,0,0,0,0,0,0,0,0,0,0)';
      BIDIRECTIONAL='TRUE';
      INPUT_LOAD='(-0.01,0.01)';
      OUTPUT_LOAD='(1.0,-1.0)';
      PINUSE='BI';
    'MEB_DATA10':
      PIN_NUMBER='(0,0,0,0,CJ71,0,0,0,0,0,0,0,0,0,0,0,0,0,0,0,0,0,0,0,0,0,0,0,0,~
0,0,0,0,0,0,0,0,0,0,0)';
      BIDIRECTIONAL='TRUE';
      INPUT_LOAD='(-0.01,0.01)';
      OUTPUT_LOAD='(1.0,-1.0)';
      PINUSE='BI';
    'MEB_DATA8':
      PIN_NUMBER='(0,0,0,0,CH70,0,0,0,0,0,0,0,0,0,0,0,0,0,0,0,0,0,0,0,0,0,0,0,0,~
0,0,0,0,0,0,0,0,0,0,0)';
      BIDIRECTIONAL='TRUE';
      INPUT_LOAD='(-0.01,0.01)';
      OUTPUT_LOAD='(1.0,-1.0)';
      PINUSE='BI';
    'MEB_CHECK1':
      PIN_NUMBER='(0,0,0,0,CA69,0,0,0,0,0,0,0,0,0,0,0,0,0,0,0,0,0,0,0,0,0,0,0,0,~
0,0,0,0,0,0,0,0,0,0,0)';
      BIDIRECTIONAL='TRUE';
      INPUT_LOAD='(-0.01,0.01)';
      OUTPUT_LOAD='(1.0,-1.0)';
      PINUSE='BI';
    'MEB_CA6':
      PIN_NUMBER='(0,0,0,0,BK70,0,0,0,0,0,0,0,0,0,0,0,0,0,0,0,0,0,0,0,0,0,0,0,0,~
0,0,0,0,0,0,0,0,0,0,0)';
      OUTPUT_LOAD='(1.0,-1.0)';
      PINUSE='OUT';
    'MEA_DQS_L3':
      PIN_NUMBER='(0,0,0,0,AF70,0,0,0,0,0,0,0,0,0,0,0,0,0,0,0,0,0,0,0,0,0,0,0,0,~
0,0,0,0,0,0,0,0,0,0,0)';
      BIDIRECTIONAL='TRUE';
      INPUT_LOAD='(-0.01,0.01)';
      OUTPUT_LOAD='(1.0,-1.0)';
      PINUSE='BI';
    'MEA_DATA27':
      PIN_NUMBER='(0,0,0,0,AE69,0,0,0,0,0,0,0,0,0,0,0,0,0,0,0,0,0,0,0,0,0,0,0,0,~
0,0,0,0,0,0,0,0,0,0,0)';
      BIDIRECTIONAL='TRUE';
      INPUT_LOAD='(-0.01,0.01)';
      OUTPUT_LOAD='(1.0,-1.0)';
      PINUSE='BI';
    'MEA_DATA16':
      PIN_NUMBER='(0,0,0,0,U71,0,0,0,0,0,0,0,0,0,0,0,0,0,0,0,0,0,0,0,0,0,0,0,0,0~
,0,0,0,0,0,0,0,0,0,0)';
      BIDIRECTIONAL='TRUE';
      INPUT_LOAD='(-0.01,0.01)';
      OUTPUT_LOAD='(1.0,-1.0)';
      PINUSE='BI';
    'MEA_DATA9':
      PIN_NUMBER='(0,0,0,0,M69,0,0,0,0,0,0,0,0,0,0,0,0,0,0,0,0,0,0,0,0,0,0,0,0,0~
,0,0,0,0,0,0,0,0,0,0)';
      BIDIRECTIONAL='TRUE';
      INPUT_LOAD='(-0.01,0.01)';
      OUTPUT_LOAD='(1.0,-1.0)';
      PINUSE='BI';
    'MEA_CHECK7':
      PIN_NUMBER='(0,0,0,0,AR69,0,0,0,0,0,0,0,0,0,0,0,0,0,0,0,0,0,0,0,0,0,0,0,0,~
0,0,0,0,0,0,0,0,0,0,0)';
      BIDIRECTIONAL='TRUE';
      INPUT_LOAD='(-0.01,0.01)';
      OUTPUT_LOAD='(1.0,-1.0)';
      PINUSE='BI';
    'MEA1_RSP_L':
      PIN_NUMBER='(0,0,0,0,BP69,0,0,0,0,0,0,0,0,0,0,0,0,0,0,0,0,0,0,0,0,0,0,0,0,~
0,0,0,0,0,0,0,0,0,0,0)';
      INPUT_LOAD='(-0.01,0.01)';
      PINUSE='IN';
    'MEA0_RSP_L':
      PIN_NUMBER='(0,0,0,0,BN69,0,0,0,0,0,0,0,0,0,0,0,0,0,0,0,0,0,0,0,0,0,0,0,0,~
0,0,0,0,0,0,0,0,0,0,0)';
      INPUT_LOAD='(-0.01,0.01)';
      PINUSE='IN';
    'MEB_DATA22':
      PIN_NUMBER='(0,0,0,0,CW71,0,0,0,0,0,0,0,0,0,0,0,0,0,0,0,0,0,0,0,0,0,0,0,0,~
0,0,0,0,0,0,0,0,0,0,0)';
      BIDIRECTIONAL='TRUE';
      INPUT_LOAD='(-0.01,0.01)';
      OUTPUT_LOAD='(1.0,-1.0)';
      PINUSE='BI';
    'MEB_DATA11':
      PIN_NUMBER='(0,0,0,0,CK69,0,0,0,0,0,0,0,0,0,0,0,0,0,0,0,0,0,0,0,0,0,0,0,0,~
0,0,0,0,0,0,0,0,0,0,0)';
      BIDIRECTIONAL='TRUE';
      INPUT_LOAD='(-0.01,0.01)';
      OUTPUT_LOAD='(1.0,-1.0)';
      PINUSE='BI';
    'MEB_DATA9':
      PIN_NUMBER='(0,0,0,0,CJ69,0,0,0,0,0,0,0,0,0,0,0,0,0,0,0,0,0,0,0,0,0,0,0,0,~
0,0,0,0,0,0,0,0,0,0,0)';
      BIDIRECTIONAL='TRUE';
      INPUT_LOAD='(-0.01,0.01)';
      OUTPUT_LOAD='(1.0,-1.0)';
      PINUSE='BI';
    'MEB_CHECK2':
      PIN_NUMBER='(0,0,0,0,CA71,0,0,0,0,0,0,0,0,0,0,0,0,0,0,0,0,0,0,0,0,0,0,0,0,~
0,0,0,0,0,0,0,0,0,0,0)';
      BIDIRECTIONAL='TRUE';
      INPUT_LOAD='(-0.01,0.01)';
      OUTPUT_LOAD='(1.0,-1.0)';
      PINUSE='BI';
    'MEA_DQS_L4':
      PIN_NUMBER='(0,0,0,0,AM70,0,0,0,0,0,0,0,0,0,0,0,0,0,0,0,0,0,0,0,0,0,0,0,0,~
0,0,0,0,0,0,0,0,0,0,0)';
      BIDIRECTIONAL='TRUE';
      INPUT_LOAD='(-0.01,0.01)';
      OUTPUT_LOAD='(1.0,-1.0)';
      PINUSE='BI';
    'MEA_DQS_H0':
      PIN_NUMBER='(0,0,0,0,G71,0,0,0,0,0,0,0,0,0,0,0,0,0,0,0,0,0,0,0,0,0,0,0,0,0~
,0,0,0,0,0,0,0,0,0,0)';
      BIDIRECTIONAL='TRUE';
      INPUT_LOAD='(-0.01,0.01)';
      OUTPUT_LOAD='(1.0,-1.0)';
      PINUSE='BI';
    'MEA_DATA28':
      PIN_NUMBER='(0,0,0,0,AG71,0,0,0,0,0,0,0,0,0,0,0,0,0,0,0,0,0,0,0,0,0,0,0,0,~
0,0,0,0,0,0,0,0,0,0,0)';
      BIDIRECTIONAL='TRUE';
      INPUT_LOAD='(-0.01,0.01)';
      OUTPUT_LOAD='(1.0,-1.0)';
      PINUSE='BI';
    'MEA_DATA17':
      PIN_NUMBER='(0,0,0,0,V69,0,0,0,0,0,0,0,0,0,0,0,0,0,0,0,0,0,0,0,0,0,0,0,0,0~
,0,0,0,0,0,0,0,0,0,0)';
      BIDIRECTIONAL='TRUE';
      INPUT_LOAD='(-0.01,0.01)';
      OUTPUT_LOAD='(1.0,-1.0)';
      PINUSE='BI';
    'MEB_DATA23':
      PIN_NUMBER='(0,0,0,0,CY69,0,0,0,0,0,0,0,0,0,0,0,0,0,0,0,0,0,0,0,0,0,0,0,0,~
0,0,0,0,0,0,0,0,0,0,0)';
      BIDIRECTIONAL='TRUE';
      INPUT_LOAD='(-0.01,0.01)';
      OUTPUT_LOAD='(1.0,-1.0)';
      PINUSE='BI';
    'MEB_DATA12':
      PIN_NUMBER='(0,0,0,0,CM70,0,0,0,0,0,0,0,0,0,0,0,0,0,0,0,0,0,0,0,0,0,0,0,0,~
0,0,0,0,0,0,0,0,0,0,0)';
      BIDIRECTIONAL='TRUE';
      INPUT_LOAD='(-0.01,0.01)';
      OUTPUT_LOAD='(1.0,-1.0)';
      PINUSE='BI';
    'MEB_CHECK3':
      PIN_NUMBER='(0,0,0,0,CB69,0,0,0,0,0,0,0,0,0,0,0,0,0,0,0,0,0,0,0,0,0,0,0,0,~
0,0,0,0,0,0,0,0,0,0,0)';
      BIDIRECTIONAL='TRUE';
      INPUT_LOAD='(-0.01,0.01)';
      OUTPUT_LOAD='(1.0,-1.0)';
      PINUSE='BI';
    'MEA_DQS_L5':
      PIN_NUMBER='(0,0,0,0,H69,0,0,0,0,0,0,0,0,0,0,0,0,0,0,0,0,0,0,0,0,0,0,0,0,0~
,0,0,0,0,0,0,0,0,0,0)';
      BIDIRECTIONAL='TRUE';
      INPUT_LOAD='(-0.01,0.01)';
      OUTPUT_LOAD='(1.0,-1.0)';
      PINUSE='BI';
    'MEA_DQS_H1':
      PIN_NUMBER='(0,0,0,0,N71,0,0,0,0,0,0,0,0,0,0,0,0,0,0,0,0,0,0,0,0,0,0,0,0,0~
,0,0,0,0,0,0,0,0,0,0)';
      BIDIRECTIONAL='TRUE';
      INPUT_LOAD='(-0.01,0.01)';
      OUTPUT_LOAD='(1.0,-1.0)';
      PINUSE='BI';
    'MEA_DATA29':
      PIN_NUMBER='(0,0,0,0,AH69,0,0,0,0,0,0,0,0,0,0,0,0,0,0,0,0,0,0,0,0,0,0,0,0,~
0,0,0,0,0,0,0,0,0,0,0)';
      BIDIRECTIONAL='TRUE';
      INPUT_LOAD='(-0.01,0.01)';
      OUTPUT_LOAD='(1.0,-1.0)';
      PINUSE='BI';
    'MEA_DATA18':
      PIN_NUMBER='(0,0,0,0,V70,0,0,0,0,0,0,0,0,0,0,0,0,0,0,0,0,0,0,0,0,0,0,0,0,0~
,0,0,0,0,0,0,0,0,0,0)';
      BIDIRECTIONAL='TRUE';
      INPUT_LOAD='(-0.01,0.01)';
      OUTPUT_LOAD='(1.0,-1.0)';
      PINUSE='BI';
    'MEB_DQS_L0':
      PIN_NUMBER='(0,0,0,0,CE71,0,0,0,0,0,0,0,0,0,0,0,0,0,0,0,0,0,0,0,0,0,0,0,0,~
0,0,0,0,0,0,0,0,0,0,0)';
      BIDIRECTIONAL='TRUE';
      INPUT_LOAD='(-0.01,0.01)';
      OUTPUT_LOAD='(1.0,-1.0)';
      PINUSE='BI';
    'MEB_DATA24':
      PIN_NUMBER='(0,0,0,0,CY70,0,0,0,0,0,0,0,0,0,0,0,0,0,0,0,0,0,0,0,0,0,0,0,0,~
0,0,0,0,0,0,0,0,0,0,0)';
      BIDIRECTIONAL='TRUE';
      INPUT_LOAD='(-0.01,0.01)';
      OUTPUT_LOAD='(1.0,-1.0)';
      PINUSE='BI';
    'MEB_DATA13':
      PIN_NUMBER='(0,0,0,0,CN69,0,0,0,0,0,0,0,0,0,0,0,0,0,0,0,0,0,0,0,0,0,0,0,0,~
0,0,0,0,0,0,0,0,0,0,0)';
      BIDIRECTIONAL='TRUE';
      INPUT_LOAD='(-0.01,0.01)';
      OUTPUT_LOAD='(1.0,-1.0)';
      PINUSE='BI';
    'MEB_CHECK4':
      PIN_NUMBER='(0,0,0,0,BT70,0,0,0,0,0,0,0,0,0,0,0,0,0,0,0,0,0,0,0,0,0,0,0,0,~
0,0,0,0,0,0,0,0,0,0,0)';
      BIDIRECTIONAL='TRUE';
      INPUT_LOAD='(-0.01,0.01)';
      OUTPUT_LOAD='(1.0,-1.0)';
      PINUSE='BI';
    'MEA_DQS_L6':
      PIN_NUMBER='(0,0,0,0,P69,0,0,0,0,0,0,0,0,0,0,0,0,0,0,0,0,0,0,0,0,0,0,0,0,0~
,0,0,0,0,0,0,0,0,0,0)';
      BIDIRECTIONAL='TRUE';
      INPUT_LOAD='(-0.01,0.01)';
      OUTPUT_LOAD='(1.0,-1.0)';
      PINUSE='BI';
    'MEA_DQS_H2':
      PIN_NUMBER='(0,0,0,0,W71,0,0,0,0,0,0,0,0,0,0,0,0,0,0,0,0,0,0,0,0,0,0,0,0,0~
,0,0,0,0,0,0,0,0,0,0)';
      BIDIRECTIONAL='TRUE';
      INPUT_LOAD='(-0.01,0.01)';
      OUTPUT_LOAD='(1.0,-1.0)';
      PINUSE='BI';
    'MEA_DATA19':
      PIN_NUMBER='(0,0,0,0,W69,0,0,0,0,0,0,0,0,0,0,0,0,0,0,0,0,0,0,0,0,0,0,0,0,0~
,0,0,0,0,0,0,0,0,0,0)';
      BIDIRECTIONAL='TRUE';
      INPUT_LOAD='(-0.01,0.01)';
      OUTPUT_LOAD='(1.0,-1.0)';
      PINUSE='BI';
    'MEB_DQS_L1':
      PIN_NUMBER='(0,0,0,0,CL71,0,0,0,0,0,0,0,0,0,0,0,0,0,0,0,0,0,0,0,0,0,0,0,0,~
0,0,0,0,0,0,0,0,0,0,0)';
      BIDIRECTIONAL='TRUE';
      INPUT_LOAD='(-0.01,0.01)';
      OUTPUT_LOAD='(1.0,-1.0)';
      PINUSE='BI';
    'MEB_DATA25':
      PIN_NUMBER='(0,0,0,0,DA69,0,0,0,0,0,0,0,0,0,0,0,0,0,0,0,0,0,0,0,0,0,0,0,0,~
0,0,0,0,0,0,0,0,0,0,0)';
      BIDIRECTIONAL='TRUE';
      INPUT_LOAD='(-0.01,0.01)';
      OUTPUT_LOAD='(1.0,-1.0)';
      PINUSE='BI';
    'MEB_DATA14':
      PIN_NUMBER='(0,0,0,0,CN71,0,0,0,0,0,0,0,0,0,0,0,0,0,0,0,0,0,0,0,0,0,0,0,0,~
0,0,0,0,0,0,0,0,0,0,0)';
      BIDIRECTIONAL='TRUE';
      INPUT_LOAD='(-0.01,0.01)';
      OUTPUT_LOAD='(1.0,-1.0)';
      PINUSE='BI';
    'MEB_CHECK5':
      PIN_NUMBER='(0,0,0,0,BU69,0,0,0,0,0,0,0,0,0,0,0,0,0,0,0,0,0,0,0,0,0,0,0,0,~
0,0,0,0,0,0,0,0,0,0,0)';
      BIDIRECTIONAL='TRUE';
      INPUT_LOAD='(-0.01,0.01)';
      OUTPUT_LOAD='(1.0,-1.0)';
      PINUSE='BI';
    'MEA_DQS_L7':
      PIN_NUMBER='(0,0,0,0,Y69,0,0,0,0,0,0,0,0,0,0,0,0,0,0,0,0,0,0,0,0,0,0,0,0,0~
,0,0,0,0,0,0,0,0,0,0)';
      BIDIRECTIONAL='TRUE';
      INPUT_LOAD='(-0.01,0.01)';
      OUTPUT_LOAD='(1.0,-1.0)';
      PINUSE='BI';
    'MEA_DQS_H3':
      PIN_NUMBER='(0,0,0,0,AE71,0,0,0,0,0,0,0,0,0,0,0,0,0,0,0,0,0,0,0,0,0,0,0,0,~
0,0,0,0,0,0,0,0,0,0,0)';
      BIDIRECTIONAL='TRUE';
      INPUT_LOAD='(-0.01,0.01)';
      OUTPUT_LOAD='(1.0,-1.0)';
      PINUSE='BI';
    'MEA_PAR':
      PIN_NUMBER='(0,0,0,0,BC69,0,0,0,0,0,0,0,0,0,0,0,0,0,0,0,0,0,0,0,0,0,0,0,0,~
0,0,0,0,0,0,0,0,0,0,0)';
      OUTPUT_LOAD='(1.0,-1.0)';
      PINUSE='OUT';
    'MEB_PAR':
      PIN_NUMBER='(0,0,0,0,BL71,0,0,0,0,0,0,0,0,0,0,0,0,0,0,0,0,0,0,0,0,0,0,0,0,~
0,0,0,0,0,0,0,0,0,0,0)';
      OUTPUT_LOAD='(1.0,-1.0)';
      PINUSE='OUT';
    'MEB_DQS_H9':
      PIN_NUMBER='(0,0,0,0,BV70,0,0,0,0,0,0,0,0,0,0,0,0,0,0,0,0,0,0,0,0,0,0,0,0,~
0,0,0,0,0,0,0,0,0,0,0)';
      BIDIRECTIONAL='TRUE';
      INPUT_LOAD='(-0.01,0.01)';
      OUTPUT_LOAD='(1.0,-1.0)';
      PINUSE='BI';
    'ME0_CLK_H':
      PIN_NUMBER='(0,0,0,0,BC71,0,0,0,0,0,0,0,0,0,0,0,0,0,0,0,0,0,0,0,0,0,0,0,0,~
0,0,0,0,0,0,0,0,0,0,0)';
      OUTPUT_LOAD='(1.0,-1.0)';
      PINUSE='OUT';
    'ME0_CLK_L':
      PIN_NUMBER='(0,0,0,0,BD70,0,0,0,0,0,0,0,0,0,0,0,0,0,0,0,0,0,0,0,0,0,0,0,0,~
0,0,0,0,0,0,0,0,0,0,0)';
      OUTPUT_LOAD='(1.0,-1.0)';
      PINUSE='OUT';
    'ME1_CLK_H':
      PIN_NUMBER='(0,0,0,0,BF70,0,0,0,0,0,0,0,0,0,0,0,0,0,0,0,0,0,0,0,0,0,0,0,0,~
0,0,0,0,0,0,0,0,0,0,0)';
      OUTPUT_LOAD='(1.0,-1.0)';
      PINUSE='OUT';
    'ME1_CLK_L':
      PIN_NUMBER='(0,0,0,0,BG71,0,0,0,0,0,0,0,0,0,0,0,0,0,0,0,0,0,0,0,0,0,0,0,0,~
0,0,0,0,0,0,0,0,0,0,0)';
      OUTPUT_LOAD='(1.0,-1.0)';
      PINUSE='OUT';
    'TEST39E':
      PIN_NUMBER='(0,0,0,0,BF69,0,0,0,0,0,0,0,0,0,0,0,0,0,0,0,0,0,0,0,0,0,0,0,0,~
0,0,0,0,0,0,0,0,0,0,0)';
      OUTPUT_LOAD='(1.0,-1.0)';
      PINUSE='OUT';
    'MF_ALERT_L':
      PIN_NUMBER='(0,0,0,0,0,AT65,0,0,0,0,0,0,0,0,0,0,0,0,0,0,0,0,0,0,0,0,0,0,0,~
0,0,0,0,0,0,0,0,0,0,0)';
      INPUT_LOAD='(-0.01,0.01)';
      PINUSE='IN';
    'MF_RESET_L':
      PIN_NUMBER='(0,0,0,0,0,AU66,0,0,0,0,0,0,0,0,0,0,0,0,0,0,0,0,0,0,0,0,0,0,0,~
0,0,0,0,0,0,0,0,0,0,0)';
      OUTPUT_LOAD='(1.0,-1.0)';
      PINUSE='OUT';
    'MFB_DQS_L6':
      PIN_NUMBER='(0,0,0,0,0,CL66,0,0,0,0,0,0,0,0,0,0,0,0,0,0,0,0,0,0,0,0,0,0,0,~
0,0,0,0,0,0,0,0,0,0,0)';
      BIDIRECTIONAL='TRUE';
      INPUT_LOAD='(-0.01,0.01)';
      OUTPUT_LOAD='(1.0,-1.0)';
      PINUSE='BI';
    'MFB_DQS_H2':
      PIN_NUMBER='(0,0,0,0,0,CT67,0,0,0,0,0,0,0,0,0,0,0,0,0,0,0,0,0,0,0,0,0,0,0,~
0,0,0,0,0,0,0,0,0,0,0)';
      BIDIRECTIONAL='TRUE';
      INPUT_LOAD='(-0.01,0.01)';
      OUTPUT_LOAD='(1.0,-1.0)';
      PINUSE='BI';
    'MFB_DATA19':
      PIN_NUMBER='(0,0,0,0,0,CT65,0,0,0,0,0,0,0,0,0,0,0,0,0,0,0,0,0,0,0,0,0,0,0,~
0,0,0,0,0,0,0,0,0,0,0)';
      BIDIRECTIONAL='TRUE';
      INPUT_LOAD='(-0.01,0.01)';
      OUTPUT_LOAD='(1.0,-1.0)';
      PINUSE='BI';
    'MFB_DATA7':
      PIN_NUMBER='(0,0,0,0,0,CH65,0,0,0,0,0,0,0,0,0,0,0,0,0,0,0,0,0,0,0,0,0,0,0,~
0,0,0,0,0,0,0,0,0,0,0)';
      BIDIRECTIONAL='TRUE';
      INPUT_LOAD='(-0.01,0.01)';
      OUTPUT_LOAD='(1.0,-1.0)';
      PINUSE='BI';
    'MFA_DQS_H8':
      PIN_NUMBER='(0,0,0,0,0,AG66,0,0,0,0,0,0,0,0,0,0,0,0,0,0,0,0,0,0,0,0,0,0,0,~
0,0,0,0,0,0,0,0,0,0,0)';
      BIDIRECTIONAL='TRUE';
      INPUT_LOAD='(-0.01,0.01)';
      OUTPUT_LOAD='(1.0,-1.0)';
      PINUSE='BI';
    'MFA_DATA30':
      PIN_NUMBER='(0,0,0,0,0,AH67,0,0,0,0,0,0,0,0,0,0,0,0,0,0,0,0,0,0,0,0,0,0,0,~
0,0,0,0,0,0,0,0,0,0,0)';
      BIDIRECTIONAL='TRUE';
      INPUT_LOAD='(-0.01,0.01)';
      OUTPUT_LOAD='(1.0,-1.0)';
      PINUSE='BI';
    'MFA_DATA8':
      PIN_NUMBER='(0,0,0,0,0,L67,0,0,0,0,0,0,0,0,0,0,0,0,0,0,0,0,0,0,0,0,0,0,0,0~
,0,0,0,0,0,0,0,0,0,0)';
      BIDIRECTIONAL='TRUE';
      INPUT_LOAD='(-0.01,0.01)';
      OUTPUT_LOAD='(1.0,-1.0)';
      PINUSE='BI';
    'MFA1_CS_L0':
      PIN_NUMBER='(0,0,0,0,0,AU67,0,0,0,0,0,0,0,0,0,0,0,0,0,0,0,0,0,0,0,0,0,0,0,~
0,0,0,0,0,0,0,0,0,0,0)';
      OUTPUT_LOAD='(1.0,-1.0)';
      PINUSE='OUT';
    'MFA0_CS_L1':
      PIN_NUMBER='(0,0,0,0,0,AW66,0,0,0,0,0,0,0,0,0,0,0,0,0,0,0,0,0,0,0,0,0,0,0,~
0,0,0,0,0,0,0,0,0,0,0)';
      OUTPUT_LOAD='(1.0,-1.0)';
      PINUSE='OUT';
    'MFB_DQS_L7':
      PIN_NUMBER='(0,0,0,0,0,CU66,0,0,0,0,0,0,0,0,0,0,0,0,0,0,0,0,0,0,0,0,0,0,0,~
0,0,0,0,0,0,0,0,0,0,0)';
      BIDIRECTIONAL='TRUE';
      INPUT_LOAD='(-0.01,0.01)';
      OUTPUT_LOAD='(1.0,-1.0)';
      PINUSE='BI';
    'MFB_DQS_H3':
      PIN_NUMBER='(0,0,0,0,0,DB67,0,0,0,0,0,0,0,0,0,0,0,0,0,0,0,0,0,0,0,0,0,0,0,~
0,0,0,0,0,0,0,0,0,0,0)';
      BIDIRECTIONAL='TRUE';
      INPUT_LOAD='(-0.01,0.01)';
      OUTPUT_LOAD='(1.0,-1.0)';
      PINUSE='BI';
    'MFB_DATA8':
      PIN_NUMBER='(0,0,0,0,0,CH67,0,0,0,0,0,0,0,0,0,0,0,0,0,0,0,0,0,0,0,0,0,0,0,~
0,0,0,0,0,0,0,0,0,0,0)';
      BIDIRECTIONAL='TRUE';
      INPUT_LOAD='(-0.01,0.01)';
      OUTPUT_LOAD='(1.0,-1.0)';
      PINUSE='BI';
    'MFA_DQS_H9':
      PIN_NUMBER='(0,0,0,0,0,AN66,0,0,0,0,0,0,0,0,0,0,0,0,0,0,0,0,0,0,0,0,0,0,0,~
0,0,0,0,0,0,0,0,0,0,0)';
      BIDIRECTIONAL='TRUE';
      INPUT_LOAD='(-0.01,0.01)';
      OUTPUT_LOAD='(1.0,-1.0)';
      PINUSE='BI';
    'MFA_DATA31':
      PIN_NUMBER='(0,0,0,0,0,AJ66,0,0,0,0,0,0,0,0,0,0,0,0,0,0,0,0,0,0,0,0,0,0,0,~
0,0,0,0,0,0,0,0,0,0,0)';
      BIDIRECTIONAL='TRUE';
      INPUT_LOAD='(-0.01,0.01)';
      OUTPUT_LOAD='(1.0,-1.0)';
      PINUSE='BI';
    'MFA_DATA20':
      PIN_NUMBER='(0,0,0,0,0,AA67,0,0,0,0,0,0,0,0,0,0,0,0,0,0,0,0,0,0,0,0,0,0,0,~
0,0,0,0,0,0,0,0,0,0,0)';
      BIDIRECTIONAL='TRUE';
      INPUT_LOAD='(-0.01,0.01)';
      OUTPUT_LOAD='(1.0,-1.0)';
      PINUSE='BI';
    'MFA_DATA9':
      PIN_NUMBER='(0,0,0,0,0,M65,0,0,0,0,0,0,0,0,0,0,0,0,0,0,0,0,0,0,0,0,0,0,0,0~
,0,0,0,0,0,0,0,0,0,0)';
      BIDIRECTIONAL='TRUE';
      INPUT_LOAD='(-0.01,0.01)';
      OUTPUT_LOAD='(1.0,-1.0)';
      PINUSE='BI';
    'MFA_CHECK0':
      PIN_NUMBER='(0,0,0,0,0,AJ67,0,0,0,0,0,0,0,0,0,0,0,0,0,0,0,0,0,0,0,0,0,0,0,~
0,0,0,0,0,0,0,0,0,0,0)';
      BIDIRECTIONAL='TRUE';
      INPUT_LOAD='(-0.01,0.01)';
      OUTPUT_LOAD='(1.0,-1.0)';
      PINUSE='BI';
    'MFA1_CS_L1':
      PIN_NUMBER='(0,0,0,0,0,AV65,0,0,0,0,0,0,0,0,0,0,0,0,0,0,0,0,0,0,0,0,0,0,0,~
0,0,0,0,0,0,0,0,0,0,0)';
      OUTPUT_LOAD='(1.0,-1.0)';
      PINUSE='OUT';
    'MFB_DQS_L8':
      PIN_NUMBER='(0,0,0,0,0,DC66,0,0,0,0,0,0,0,0,0,0,0,0,0,0,0,0,0,0,0,0,0,0,0,~
0,0,0,0,0,0,0,0,0,0,0)';
      BIDIRECTIONAL='TRUE';
      INPUT_LOAD='(-0.01,0.01)';
      OUTPUT_LOAD='(1.0,-1.0)';
      PINUSE='BI';
    'MFB_DQS_H4':
      PIN_NUMBER='(0,0,0,0,0,BY65,0,0,0,0,0,0,0,0,0,0,0,0,0,0,0,0,0,0,0,0,0,0,0,~
0,0,0,0,0,0,0,0,0,0,0)';
      BIDIRECTIONAL='TRUE';
      INPUT_LOAD='(-0.01,0.01)';
      OUTPUT_LOAD='(1.0,-1.0)';
      PINUSE='BI';
    'MFB_DATA9':
      PIN_NUMBER='(0,0,0,0,0,CJ66,0,0,0,0,0,0,0,0,0,0,0,0,0,0,0,0,0,0,0,0,0,0,0,~
0,0,0,0,0,0,0,0,0,0,0)';
      BIDIRECTIONAL='TRUE';
      INPUT_LOAD='(-0.01,0.01)';
      OUTPUT_LOAD='(1.0,-1.0)';
      PINUSE='BI';
    'MFA_DATA21':
      PIN_NUMBER='(0,0,0,0,0,AB65,0,0,0,0,0,0,0,0,0,0,0,0,0,0,0,0,0,0,0,0,0,0,0,~
0,0,0,0,0,0,0,0,0,0,0)';
      BIDIRECTIONAL='TRUE';
      INPUT_LOAD='(-0.01,0.01)';
      OUTPUT_LOAD='(1.0,-1.0)';
      PINUSE='BI';
    'MFA_DATA10':
      PIN_NUMBER='(0,0,0,0,0,M67,0,0,0,0,0,0,0,0,0,0,0,0,0,0,0,0,0,0,0,0,0,0,0,0~
,0,0,0,0,0,0,0,0,0,0)';
      BIDIRECTIONAL='TRUE';
      INPUT_LOAD='(-0.01,0.01)';
      OUTPUT_LOAD='(1.0,-1.0)';
      PINUSE='BI';
    'MFA_CHECK1':
      PIN_NUMBER='(0,0,0,0,0,AK65,0,0,0,0,0,0,0,0,0,0,0,0,0,0,0,0,0,0,0,0,0,0,0,~
0,0,0,0,0,0,0,0,0,0,0)';
      BIDIRECTIONAL='TRUE';
      INPUT_LOAD='(-0.01,0.01)';
      OUTPUT_LOAD='(1.0,-1.0)';
      PINUSE='BI';
    'MFB_DQS_L9':
      PIN_NUMBER='(0,0,0,0,0,BW67,0,0,0,0,0,0,0,0,0,0,0,0,0,0,0,0,0,0,0,0,0,0,0,~
0,0,0,0,0,0,0,0,0,0,0)';
      BIDIRECTIONAL='TRUE';
      INPUT_LOAD='(-0.01,0.01)';
      OUTPUT_LOAD='(1.0,-1.0)';
      PINUSE='BI';
    'MFB_DQS_H5':
      PIN_NUMBER='(0,0,0,0,0,CF65,0,0,0,0,0,0,0,0,0,0,0,0,0,0,0,0,0,0,0,0,0,0,0,~
0,0,0,0,0,0,0,0,0,0,0)';
      BIDIRECTIONAL='TRUE';
      INPUT_LOAD='(-0.01,0.01)';
      OUTPUT_LOAD='(1.0,-1.0)';
      PINUSE='BI';
    'MFA_DATA22':
      PIN_NUMBER='(0,0,0,0,0,AB67,0,0,0,0,0,0,0,0,0,0,0,0,0,0,0,0,0,0,0,0,0,0,0,~
0,0,0,0,0,0,0,0,0,0,0)';
      BIDIRECTIONAL='TRUE';
      INPUT_LOAD='(-0.01,0.01)';
      OUTPUT_LOAD='(1.0,-1.0)';
      PINUSE='BI';
    'MFA_DATA11':
      PIN_NUMBER='(0,0,0,0,0,N66,0,0,0,0,0,0,0,0,0,0,0,0,0,0,0,0,0,0,0,0,0,0,0,0~
,0,0,0,0,0,0,0,0,0,0)';
      BIDIRECTIONAL='TRUE';
      INPUT_LOAD='(-0.01,0.01)';
      OUTPUT_LOAD='(1.0,-1.0)';
      PINUSE='BI';
    'MFA_CHECK2':
      PIN_NUMBER='(0,0,0,0,0,AK67,0,0,0,0,0,0,0,0,0,0,0,0,0,0,0,0,0,0,0,0,0,0,0,~
0,0,0,0,0,0,0,0,0,0,0)';
      BIDIRECTIONAL='TRUE';
      INPUT_LOAD='(-0.01,0.01)';
      OUTPUT_LOAD='(1.0,-1.0)';
      PINUSE='BI';
    'MFB_DQS_H6':
      PIN_NUMBER='(0,0,0,0,0,CM65,0,0,0,0,0,0,0,0,0,0,0,0,0,0,0,0,0,0,0,0,0,0,0,~
0,0,0,0,0,0,0,0,0,0,0)';
      BIDIRECTIONAL='TRUE';
      INPUT_LOAD='(-0.01,0.01)';
      OUTPUT_LOAD='(1.0,-1.0)';
      PINUSE='BI';
    'MFA_DATA23':
      PIN_NUMBER='(0,0,0,0,0,AC66,0,0,0,0,0,0,0,0,0,0,0,0,0,0,0,0,0,0,0,0,0,0,0,~
0,0,0,0,0,0,0,0,0,0,0)';
      BIDIRECTIONAL='TRUE';
      INPUT_LOAD='(-0.01,0.01)';
      OUTPUT_LOAD='(1.0,-1.0)';
      PINUSE='BI';
    'MFA_DATA12':
      PIN_NUMBER='(0,0,0,0,0,R67,0,0,0,0,0,0,0,0,0,0,0,0,0,0,0,0,0,0,0,0,0,0,0,0~
,0,0,0,0,0,0,0,0,0,0)';
      BIDIRECTIONAL='TRUE';
      INPUT_LOAD='(-0.01,0.01)';
      OUTPUT_LOAD='(1.0,-1.0)';
      PINUSE='BI';
    'MFA_CHECK3':
      PIN_NUMBER='(0,0,0,0,0,AL66,0,0,0,0,0,0,0,0,0,0,0,0,0,0,0,0,0,0,0,0,0,0,0,~
0,0,0,0,0,0,0,0,0,0,0)';
      BIDIRECTIONAL='TRUE';
      INPUT_LOAD='(-0.01,0.01)';
      OUTPUT_LOAD='(1.0,-1.0)';
      PINUSE='BI';
    'MFA_CA0':
      PIN_NUMBER='(0,0,0,0,0,AW67,0,0,0,0,0,0,0,0,0,0,0,0,0,0,0,0,0,0,0,0,0,0,0,~
0,0,0,0,0,0,0,0,0,0,0)';
      OUTPUT_LOAD='(1.0,-1.0)';
      PINUSE='OUT';
    'MFB_DQS_H7':
      PIN_NUMBER='(0,0,0,0,0,CV65,0,0,0,0,0,0,0,0,0,0,0,0,0,0,0,0,0,0,0,0,0,0,0,~
0,0,0,0,0,0,0,0,0,0,0)';
      BIDIRECTIONAL='TRUE';
      INPUT_LOAD='(-0.01,0.01)';
      OUTPUT_LOAD='(1.0,-1.0)';
      PINUSE='BI';
    'MFB_CA0':
      PIN_NUMBER='(0,0,0,0,0,BG66,0,0,0,0,0,0,0,0,0,0,0,0,0,0,0,0,0,0,0,0,0,0,0,~
0,0,0,0,0,0,0,0,0,0,0)';
      OUTPUT_LOAD='(1.0,-1.0)';
      PINUSE='OUT';
    'MFB0_CS_L0':
      PIN_NUMBER='(0,0,0,0,0,BM65,0,0,0,0,0,0,0,0,0,0,0,0,0,0,0,0,0,0,0,0,0,0,0,~
0,0,0,0,0,0,0,0,0,0,0)';
      OUTPUT_LOAD='(1.0,-1.0)';
      PINUSE='OUT';
    'MFA_DQS_L0':
      PIN_NUMBER='(0,0,0,0,0,H67,0,0,0,0,0,0,0,0,0,0,0,0,0,0,0,0,0,0,0,0,0,0,0,0~
,0,0,0,0,0,0,0,0,0,0)';
      BIDIRECTIONAL='TRUE';
      INPUT_LOAD='(-0.01,0.01)';
      OUTPUT_LOAD='(1.0,-1.0)';
      PINUSE='BI';
    'MFA_DATA24':
      PIN_NUMBER='(0,0,0,0,0,AC67,0,0,0,0,0,0,0,0,0,0,0,0,0,0,0,0,0,0,0,0,0,0,0,~
0,0,0,0,0,0,0,0,0,0,0)';
      BIDIRECTIONAL='TRUE';
      INPUT_LOAD='(-0.01,0.01)';
      OUTPUT_LOAD='(1.0,-1.0)';
      PINUSE='BI';
    'MFA_DATA13':
      PIN_NUMBER='(0,0,0,0,0,T65,0,0,0,0,0,0,0,0,0,0,0,0,0,0,0,0,0,0,0,0,0,0,0,0~
,0,0,0,0,0,0,0,0,0,0)';
      BIDIRECTIONAL='TRUE';
      INPUT_LOAD='(-0.01,0.01)';
      OUTPUT_LOAD='(1.0,-1.0)';
      PINUSE='BI';
    'MFA_CHECK4':
      PIN_NUMBER='(0,0,0,0,0,AN67,0,0,0,0,0,0,0,0,0,0,0,0,0,0,0,0,0,0,0,0,0,0,0,~
0,0,0,0,0,0,0,0,0,0,0)';
      BIDIRECTIONAL='TRUE';
      INPUT_LOAD='(-0.01,0.01)';
      OUTPUT_LOAD='(1.0,-1.0)';
      PINUSE='BI';
    'MFA_CA1':
      PIN_NUMBER='(0,0,0,0,0,AY67,0,0,0,0,0,0,0,0,0,0,0,0,0,0,0,0,0,0,0,0,0,0,0,~
0,0,0,0,0,0,0,0,0,0,0)';
      OUTPUT_LOAD='(1.0,-1.0)';
      PINUSE='OUT';
    'MFB_DQS_H8':
      PIN_NUMBER='(0,0,0,0,0,DD65,0,0,0,0,0,0,0,0,0,0,0,0,0,0,0,0,0,0,0,0,0,0,0,~
0,0,0,0,0,0,0,0,0,0,0)';
      BIDIRECTIONAL='TRUE';
      INPUT_LOAD='(-0.01,0.01)';
      OUTPUT_LOAD='(1.0,-1.0)';
      PINUSE='BI';
    'MFB_DATA30':
      PIN_NUMBER='(0,0,0,0,0,DE67,0,0,0,0,0,0,0,0,0,0,0,0,0,0,0,0,0,0,0,0,0,0,0,~
0,0,0,0,0,0,0,0,0,0,0)';
      BIDIRECTIONAL='TRUE';
      INPUT_LOAD='(-0.01,0.01)';
      OUTPUT_LOAD='(1.0,-1.0)';
      PINUSE='BI';
    'MFB_CA1':
      PIN_NUMBER='(0,0,0,0,0,BH65,0,0,0,0,0,0,0,0,0,0,0,0,0,0,0,0,0,0,0,0,0,0,0,~
0,0,0,0,0,0,0,0,0,0,0)';
      OUTPUT_LOAD='(1.0,-1.0)';
      PINUSE='OUT';
    'MFB1_CS_L0':
      PIN_NUMBER='(0,0,0,0,0,BL66,0,0,0,0,0,0,0,0,0,0,0,0,0,0,0,0,0,0,0,0,0,0,0,~
0,0,0,0,0,0,0,0,0,0,0)';
      OUTPUT_LOAD='(1.0,-1.0)';
      PINUSE='OUT';
    'MFB0_CS_L1':
      PIN_NUMBER='(0,0,0,0,0,BN67,0,0,0,0,0,0,0,0,0,0,0,0,0,0,0,0,0,0,0,0,0,0,0,~
0,0,0,0,0,0,0,0,0,0,0)';
      OUTPUT_LOAD='(1.0,-1.0)';
      PINUSE='OUT';
    'MFA_DQS_L1':
      PIN_NUMBER='(0,0,0,0,0,P67,0,0,0,0,0,0,0,0,0,0,0,0,0,0,0,0,0,0,0,0,0,0,0,0~
,0,0,0,0,0,0,0,0,0,0)';
      BIDIRECTIONAL='TRUE';
      INPUT_LOAD='(-0.01,0.01)';
      OUTPUT_LOAD='(1.0,-1.0)';
      PINUSE='BI';
    'MFA_DATA25':
      PIN_NUMBER='(0,0,0,0,0,AD65,0,0,0,0,0,0,0,0,0,0,0,0,0,0,0,0,0,0,0,0,0,0,0,~
0,0,0,0,0,0,0,0,0,0,0)';
      BIDIRECTIONAL='TRUE';
      INPUT_LOAD='(-0.01,0.01)';
      OUTPUT_LOAD='(1.0,-1.0)';
      PINUSE='BI';
    'MFA_DATA14':
      PIN_NUMBER='(0,0,0,0,0,T67,0,0,0,0,0,0,0,0,0,0,0,0,0,0,0,0,0,0,0,0,0,0,0,0~
,0,0,0,0,0,0,0,0,0,0)';
      BIDIRECTIONAL='TRUE';
      INPUT_LOAD='(-0.01,0.01)';
      OUTPUT_LOAD='(1.0,-1.0)';
      PINUSE='BI';
    'MFA_CHECK5':
      PIN_NUMBER='(0,0,0,0,0,AP65,0,0,0,0,0,0,0,0,0,0,0,0,0,0,0,0,0,0,0,0,0,0,0,~
0,0,0,0,0,0,0,0,0,0,0)';
      BIDIRECTIONAL='TRUE';
      INPUT_LOAD='(-0.01,0.01)';
      OUTPUT_LOAD='(1.0,-1.0)';
      PINUSE='BI';
    'MFA_CA2':
      PIN_NUMBER='(0,0,0,0,0,AY65,0,0,0,0,0,0,0,0,0,0,0,0,0,0,0,0,0,0,0,0,0,0,0,~
0,0,0,0,0,0,0,0,0,0,0)';
      OUTPUT_LOAD='(1.0,-1.0)';
      PINUSE='OUT';
    'MFB_DATA31':
      PIN_NUMBER='(0,0,0,0,0,DF67,0,0,0,0,0,0,0,0,0,0,0,0,0,0,0,0,0,0,0,0,0,0,0,~
0,0,0,0,0,0,0,0,0,0,0)';
      BIDIRECTIONAL='TRUE';
      INPUT_LOAD='(-0.01,0.01)';
      OUTPUT_LOAD='(1.0,-1.0)';
      PINUSE='BI';
    'MFB_DATA20':
      PIN_NUMBER='(0,0,0,0,0,CV67,0,0,0,0,0,0,0,0,0,0,0,0,0,0,0,0,0,0,0,0,0,0,0,~
0,0,0,0,0,0,0,0,0,0,0)';
      BIDIRECTIONAL='TRUE';
      INPUT_LOAD='(-0.01,0.01)';
      OUTPUT_LOAD='(1.0,-1.0)';
      PINUSE='BI';
    'MFB_CHECK0':
      PIN_NUMBER='(0,0,0,0,0,BY67,0,0,0,0,0,0,0,0,0,0,0,0,0,0,0,0,0,0,0,0,0,0,0,~
0,0,0,0,0,0,0,0,0,0,0)';
      BIDIRECTIONAL='TRUE';
      INPUT_LOAD='(-0.01,0.01)';
      OUTPUT_LOAD='(1.0,-1.0)';
      PINUSE='BI';
    'MFB_CA2':
      PIN_NUMBER='(0,0,0,0,0,BH67,0,0,0,0,0,0,0,0,0,0,0,0,0,0,0,0,0,0,0,0,0,0,0,~
0,0,0,0,0,0,0,0,0,0,0)';
      OUTPUT_LOAD='(1.0,-1.0)';
      PINUSE='OUT';
    'MFB1_CS_L1':
      PIN_NUMBER='(0,0,0,0,0,BM67,0,0,0,0,0,0,0,0,0,0,0,0,0,0,0,0,0,0,0,0,0,0,0,~
0,0,0,0,0,0,0,0,0,0,0)';
      OUTPUT_LOAD='(1.0,-1.0)';
      PINUSE='OUT';
    'MFA_DQS_L2':
      PIN_NUMBER='(0,0,0,0,0,Y67,0,0,0,0,0,0,0,0,0,0,0,0,0,0,0,0,0,0,0,0,0,0,0,0~
,0,0,0,0,0,0,0,0,0,0)';
      BIDIRECTIONAL='TRUE';
      INPUT_LOAD='(-0.01,0.01)';
      OUTPUT_LOAD='(1.0,-1.0)';
      PINUSE='BI';
    'MFA_DATA26':
      PIN_NUMBER='(0,0,0,0,0,AD67,0,0,0,0,0,0,0,0,0,0,0,0,0,0,0,0,0,0,0,0,0,0,0,~
0,0,0,0,0,0,0,0,0,0,0)';
      BIDIRECTIONAL='TRUE';
      INPUT_LOAD='(-0.01,0.01)';
      OUTPUT_LOAD='(1.0,-1.0)';
      PINUSE='BI';
    'MFA_DATA15':
      PIN_NUMBER='(0,0,0,0,0,U66,0,0,0,0,0,0,0,0,0,0,0,0,0,0,0,0,0,0,0,0,0,0,0,0~
,0,0,0,0,0,0,0,0,0,0)';
      BIDIRECTIONAL='TRUE';
      INPUT_LOAD='(-0.01,0.01)';
      OUTPUT_LOAD='(1.0,-1.0)';
      PINUSE='BI';
    'MFA_CHECK6':
      PIN_NUMBER='(0,0,0,0,0,AP67,0,0,0,0,0,0,0,0,0,0,0,0,0,0,0,0,0,0,0,0,0,0,0,~
0,0,0,0,0,0,0,0,0,0,0)';
      BIDIRECTIONAL='TRUE';
      INPUT_LOAD='(-0.01,0.01)';
      OUTPUT_LOAD='(1.0,-1.0)';
      PINUSE='BI';
    'MFA_CA3':
      PIN_NUMBER='(0,0,0,0,0,BA66,0,0,0,0,0,0,0,0,0,0,0,0,0,0,0,0,0,0,0,0,0,0,0,~
0,0,0,0,0,0,0,0,0,0,0)';
      OUTPUT_LOAD='(1.0,-1.0)';
      PINUSE='OUT';
    'MFB_DATA21':
      PIN_NUMBER='(0,0,0,0,0,CW66,0,0,0,0,0,0,0,0,0,0,0,0,0,0,0,0,0,0,0,0,0,0,0,~
0,0,0,0,0,0,0,0,0,0,0)';
      BIDIRECTIONAL='TRUE';
      INPUT_LOAD='(-0.01,0.01)';
      OUTPUT_LOAD='(1.0,-1.0)';
      PINUSE='BI';
    'MFB_DATA10':
      PIN_NUMBER='(0,0,0,0,0,CJ67,0,0,0,0,0,0,0,0,0,0,0,0,0,0,0,0,0,0,0,0,0,0,0,~
0,0,0,0,0,0,0,0,0,0,0)';
      BIDIRECTIONAL='TRUE';
      INPUT_LOAD='(-0.01,0.01)';
      OUTPUT_LOAD='(1.0,-1.0)';
      PINUSE='BI';
    'MFB_CHECK1':
      PIN_NUMBER='(0,0,0,0,0,CA66,0,0,0,0,0,0,0,0,0,0,0,0,0,0,0,0,0,0,0,0,0,0,0,~
0,0,0,0,0,0,0,0,0,0,0)';
      BIDIRECTIONAL='TRUE';
      INPUT_LOAD='(-0.01,0.01)';
      OUTPUT_LOAD='(1.0,-1.0)';
      PINUSE='BI';
    'MFB_CA3':
      PIN_NUMBER='(0,0,0,0,0,BJ67,0,0,0,0,0,0,0,0,0,0,0,0,0,0,0,0,0,0,0,0,0,0,0,~
0,0,0,0,0,0,0,0,0,0,0)';
      OUTPUT_LOAD='(1.0,-1.0)';
      PINUSE='OUT';
    'MFA_DQS_L3':
      PIN_NUMBER='(0,0,0,0,0,AF67,0,0,0,0,0,0,0,0,0,0,0,0,0,0,0,0,0,0,0,0,0,0,0,~
0,0,0,0,0,0,0,0,0,0,0)';
      BIDIRECTIONAL='TRUE';
      INPUT_LOAD='(-0.01,0.01)';
      OUTPUT_LOAD='(1.0,-1.0)';
      PINUSE='BI';
    'MFA_DATA27':
      PIN_NUMBER='(0,0,0,0,0,AE66,0,0,0,0,0,0,0,0,0,0,0,0,0,0,0,0,0,0,0,0,0,0,0,~
0,0,0,0,0,0,0,0,0,0,0)';
      BIDIRECTIONAL='TRUE';
      INPUT_LOAD='(-0.01,0.01)';
      OUTPUT_LOAD='(1.0,-1.0)';
      PINUSE='BI';
    'MFA_DATA16':
      PIN_NUMBER='(0,0,0,0,0,U67,0,0,0,0,0,0,0,0,0,0,0,0,0,0,0,0,0,0,0,0,0,0,0,0~
,0,0,0,0,0,0,0,0,0,0)';
      BIDIRECTIONAL='TRUE';
      INPUT_LOAD='(-0.01,0.01)';
      OUTPUT_LOAD='(1.0,-1.0)';
      PINUSE='BI';
    'MFA_CHECK7':
      PIN_NUMBER='(0,0,0,0,0,AR66,0,0,0,0,0,0,0,0,0,0,0,0,0,0,0,0,0,0,0,0,0,0,0,~
0,0,0,0,0,0,0,0,0,0,0)';
      BIDIRECTIONAL='TRUE';
      INPUT_LOAD='(-0.01,0.01)';
      OUTPUT_LOAD='(1.0,-1.0)';
      PINUSE='BI';
    'MFA_CA4':
      PIN_NUMBER='(0,0,0,0,0,BA67,0,0,0,0,0,0,0,0,0,0,0,0,0,0,0,0,0,0,0,0,0,0,0,~
0,0,0,0,0,0,0,0,0,0,0)';
      OUTPUT_LOAD='(1.0,-1.0)';
      PINUSE='OUT';
    'MFA0_RSP_L':
      PIN_NUMBER='(0,0,0,0,0,BN66,0,0,0,0,0,0,0,0,0,0,0,0,0,0,0,0,0,0,0,0,0,0,0,~
0,0,0,0,0,0,0,0,0,0,0)';
      INPUT_LOAD='(-0.01,0.01)';
      PINUSE='IN';
    'MFB_DATA22':
      PIN_NUMBER='(0,0,0,0,0,CW67,0,0,0,0,0,0,0,0,0,0,0,0,0,0,0,0,0,0,0,0,0,0,0,~
0,0,0,0,0,0,0,0,0,0,0)';
      BIDIRECTIONAL='TRUE';
      INPUT_LOAD='(-0.01,0.01)';
      OUTPUT_LOAD='(1.0,-1.0)';
      PINUSE='BI';
    'MFB_DATA11':
      PIN_NUMBER='(0,0,0,0,0,CK65,0,0,0,0,0,0,0,0,0,0,0,0,0,0,0,0,0,0,0,0,0,0,0,~
0,0,0,0,0,0,0,0,0,0,0)';
      BIDIRECTIONAL='TRUE';
      INPUT_LOAD='(-0.01,0.01)';
      OUTPUT_LOAD='(1.0,-1.0)';
      PINUSE='BI';
    'MFB_CHECK2':
      PIN_NUMBER='(0,0,0,0,0,CA67,0,0,0,0,0,0,0,0,0,0,0,0,0,0,0,0,0,0,0,0,0,0,0,~
0,0,0,0,0,0,0,0,0,0,0)';
      BIDIRECTIONAL='TRUE';
      INPUT_LOAD='(-0.01,0.01)';
      OUTPUT_LOAD='(1.0,-1.0)';
      PINUSE='BI';
    'MFB_CA4':
      PIN_NUMBER='(0,0,0,0,0,BJ66,0,0,0,0,0,0,0,0,0,0,0,0,0,0,0,0,0,0,0,0,0,0,0,~
0,0,0,0,0,0,0,0,0,0,0)';
      OUTPUT_LOAD='(1.0,-1.0)';
      PINUSE='OUT';
    'MFA_DQS_L4':
      PIN_NUMBER='(0,0,0,0,0,AM67,0,0,0,0,0,0,0,0,0,0,0,0,0,0,0,0,0,0,0,0,0,0,0,~
0,0,0,0,0,0,0,0,0,0,0)';
      BIDIRECTIONAL='TRUE';
      INPUT_LOAD='(-0.01,0.01)';
      OUTPUT_LOAD='(1.0,-1.0)';
      PINUSE='BI';
    'MFA_DQS_H0':
      PIN_NUMBER='(0,0,0,0,0,G67,0,0,0,0,0,0,0,0,0,0,0,0,0,0,0,0,0,0,0,0,0,0,0,0~
,0,0,0,0,0,0,0,0,0,0)';
      BIDIRECTIONAL='TRUE';
      INPUT_LOAD='(-0.01,0.01)';
      OUTPUT_LOAD='(1.0,-1.0)';
      PINUSE='BI';
    'MFA_DATA28':
      PIN_NUMBER='(0,0,0,0,0,AG67,0,0,0,0,0,0,0,0,0,0,0,0,0,0,0,0,0,0,0,0,0,0,0,~
0,0,0,0,0,0,0,0,0,0,0)';
      BIDIRECTIONAL='TRUE';
      INPUT_LOAD='(-0.01,0.01)';
      OUTPUT_LOAD='(1.0,-1.0)';
      PINUSE='BI';
    'MFA_DATA17':
      PIN_NUMBER='(0,0,0,0,0,V65,0,0,0,0,0,0,0,0,0,0,0,0,0,0,0,0,0,0,0,0,0,0,0,0~
,0,0,0,0,0,0,0,0,0,0)';
      BIDIRECTIONAL='TRUE';
      INPUT_LOAD='(-0.01,0.01)';
      OUTPUT_LOAD='(1.0,-1.0)';
      PINUSE='BI';
    'MFA_DATA0':
      PIN_NUMBER='(0,0,0,0,0,E67,0,0,0,0,0,0,0,0,0,0,0,0,0,0,0,0,0,0,0,0,0,0,0,0~
,0,0,0,0,0,0,0,0,0,0)';
      BIDIRECTIONAL='TRUE';
      INPUT_LOAD='(-0.01,0.01)';
      OUTPUT_LOAD='(1.0,-1.0)';
      PINUSE='BI';
    'MFA_CA5':
      PIN_NUMBER='(0,0,0,0,0,BB67,0,0,0,0,0,0,0,0,0,0,0,0,0,0,0,0,0,0,0,0,0,0,0,~
0,0,0,0,0,0,0,0,0,0,0)';
      OUTPUT_LOAD='(1.0,-1.0)';
      PINUSE='OUT';
    'MFA1_RSP_L':
      PIN_NUMBER='(0,0,0,0,0,BP65,0,0,0,0,0,0,0,0,0,0,0,0,0,0,0,0,0,0,0,0,0,0,0,~
0,0,0,0,0,0,0,0,0,0,0)';
      INPUT_LOAD='(-0.01,0.01)';
      PINUSE='IN';
    'MFB_DATA23':
      PIN_NUMBER='(0,0,0,0,0,CY65,0,0,0,0,0,0,0,0,0,0,0,0,0,0,0,0,0,0,0,0,0,0,0,~
0,0,0,0,0,0,0,0,0,0,0)';
      BIDIRECTIONAL='TRUE';
      INPUT_LOAD='(-0.01,0.01)';
      OUTPUT_LOAD='(1.0,-1.0)';
      PINUSE='BI';
    'MFB_DATA12':
      PIN_NUMBER='(0,0,0,0,0,CM67,0,0,0,0,0,0,0,0,0,0,0,0,0,0,0,0,0,0,0,0,0,0,0,~
0,0,0,0,0,0,0,0,0,0,0)';
      BIDIRECTIONAL='TRUE';
      INPUT_LOAD='(-0.01,0.01)';
      OUTPUT_LOAD='(1.0,-1.0)';
      PINUSE='BI';
    'MFB_DATA0':
      PIN_NUMBER='(0,0,0,0,0,CB67,0,0,0,0,0,0,0,0,0,0,0,0,0,0,0,0,0,0,0,0,0,0,0,~
0,0,0,0,0,0,0,0,0,0,0)';
      BIDIRECTIONAL='TRUE';
      INPUT_LOAD='(-0.01,0.01)';
      OUTPUT_LOAD='(1.0,-1.0)';
      PINUSE='BI';
    'MFB_CHECK3':
      PIN_NUMBER='(0,0,0,0,0,CB65,0,0,0,0,0,0,0,0,0,0,0,0,0,0,0,0,0,0,0,0,0,0,0,~
0,0,0,0,0,0,0,0,0,0,0)';
      BIDIRECTIONAL='TRUE';
      INPUT_LOAD='(-0.01,0.01)';
      OUTPUT_LOAD='(1.0,-1.0)';
      PINUSE='BI';
    'MFB_CA5':
      PIN_NUMBER='(0,0,0,0,0,BK65,0,0,0,0,0,0,0,0,0,0,0,0,0,0,0,0,0,0,0,0,0,0,0,~
0,0,0,0,0,0,0,0,0,0,0)';
      OUTPUT_LOAD='(1.0,-1.0)';
      PINUSE='OUT';
    'MFA_DQS_L5':
      PIN_NUMBER='(0,0,0,0,0,H65,0,0,0,0,0,0,0,0,0,0,0,0,0,0,0,0,0,0,0,0,0,0,0,0~
,0,0,0,0,0,0,0,0,0,0)';
      BIDIRECTIONAL='TRUE';
      INPUT_LOAD='(-0.01,0.01)';
      OUTPUT_LOAD='(1.0,-1.0)';
      PINUSE='BI';
    'MFA_DQS_H1':
      PIN_NUMBER='(0,0,0,0,0,N67,0,0,0,0,0,0,0,0,0,0,0,0,0,0,0,0,0,0,0,0,0,0,0,0~
,0,0,0,0,0,0,0,0,0,0)';
      BIDIRECTIONAL='TRUE';
      INPUT_LOAD='(-0.01,0.01)';
      OUTPUT_LOAD='(1.0,-1.0)';
      PINUSE='BI';
    'MFA_DATA29':
      PIN_NUMBER='(0,0,0,0,0,AH65,0,0,0,0,0,0,0,0,0,0,0,0,0,0,0,0,0,0,0,0,0,0,0,~
0,0,0,0,0,0,0,0,0,0,0)';
      BIDIRECTIONAL='TRUE';
      INPUT_LOAD='(-0.01,0.01)';
      OUTPUT_LOAD='(1.0,-1.0)';
      PINUSE='BI';
    'MFA_DATA18':
      PIN_NUMBER='(0,0,0,0,0,V67,0,0,0,0,0,0,0,0,0,0,0,0,0,0,0,0,0,0,0,0,0,0,0,0~
,0,0,0,0,0,0,0,0,0,0)';
      BIDIRECTIONAL='TRUE';
      INPUT_LOAD='(-0.01,0.01)';
      OUTPUT_LOAD='(1.0,-1.0)';
      PINUSE='BI';
    'MFA_DATA1':
      PIN_NUMBER='(0,0,0,0,0,F65,0,0,0,0,0,0,0,0,0,0,0,0,0,0,0,0,0,0,0,0,0,0,0,0~
,0,0,0,0,0,0,0,0,0,0)';
      BIDIRECTIONAL='TRUE';
      INPUT_LOAD='(-0.01,0.01)';
      OUTPUT_LOAD='(1.0,-1.0)';
      PINUSE='BI';
    'MFA_CA6':
      PIN_NUMBER='(0,0,0,0,0,BB65,0,0,0,0,0,0,0,0,0,0,0,0,0,0,0,0,0,0,0,0,0,0,0,~
0,0,0,0,0,0,0,0,0,0,0)';
      OUTPUT_LOAD='(1.0,-1.0)';
      PINUSE='OUT';
    'MFB_DQS_L0':
      PIN_NUMBER='(0,0,0,0,0,CE67,0,0,0,0,0,0,0,0,0,0,0,0,0,0,0,0,0,0,0,0,0,0,0,~
0,0,0,0,0,0,0,0,0,0,0)';
      BIDIRECTIONAL='TRUE';
      INPUT_LOAD='(-0.01,0.01)';
      OUTPUT_LOAD='(1.0,-1.0)';
      PINUSE='BI';
    'MFB_DATA24':
      PIN_NUMBER='(0,0,0,0,0,CY67,0,0,0,0,0,0,0,0,0,0,0,0,0,0,0,0,0,0,0,0,0,0,0,~
0,0,0,0,0,0,0,0,0,0,0)';
      BIDIRECTIONAL='TRUE';
      INPUT_LOAD='(-0.01,0.01)';
      OUTPUT_LOAD='(1.0,-1.0)';
      PINUSE='BI';
    'MFB_DATA13':
      PIN_NUMBER='(0,0,0,0,0,CN66,0,0,0,0,0,0,0,0,0,0,0,0,0,0,0,0,0,0,0,0,0,0,0,~
0,0,0,0,0,0,0,0,0,0,0)';
      BIDIRECTIONAL='TRUE';
      INPUT_LOAD='(-0.01,0.01)';
      OUTPUT_LOAD='(1.0,-1.0)';
      PINUSE='BI';
    'MFB_DATA1':
      PIN_NUMBER='(0,0,0,0,0,CC66,0,0,0,0,0,0,0,0,0,0,0,0,0,0,0,0,0,0,0,0,0,0,0,~
0,0,0,0,0,0,0,0,0,0,0)';
      BIDIRECTIONAL='TRUE';
      INPUT_LOAD='(-0.01,0.01)';
      OUTPUT_LOAD='(1.0,-1.0)';
      PINUSE='BI';
    'MFB_CHECK4':
      PIN_NUMBER='(0,0,0,0,0,BT67,0,0,0,0,0,0,0,0,0,0,0,0,0,0,0,0,0,0,0,0,0,0,0,~
0,0,0,0,0,0,0,0,0,0,0)';
      BIDIRECTIONAL='TRUE';
      INPUT_LOAD='(-0.01,0.01)';
      OUTPUT_LOAD='(1.0,-1.0)';
      PINUSE='BI';
    'MFB_CA6':
      PIN_NUMBER='(0,0,0,0,0,BK67,0,0,0,0,0,0,0,0,0,0,0,0,0,0,0,0,0,0,0,0,0,0,0,~
0,0,0,0,0,0,0,0,0,0,0)';
      OUTPUT_LOAD='(1.0,-1.0)';
      PINUSE='OUT';
    'MFA_DQS_L6':
      PIN_NUMBER='(0,0,0,0,0,P65,0,0,0,0,0,0,0,0,0,0,0,0,0,0,0,0,0,0,0,0,0,0,0,0~
,0,0,0,0,0,0,0,0,0,0)';
      BIDIRECTIONAL='TRUE';
      INPUT_LOAD='(-0.01,0.01)';
      OUTPUT_LOAD='(1.0,-1.0)';
      PINUSE='BI';
    'MFA_DQS_H2':
      PIN_NUMBER='(0,0,0,0,0,W67,0,0,0,0,0,0,0,0,0,0,0,0,0,0,0,0,0,0,0,0,0,0,0,0~
,0,0,0,0,0,0,0,0,0,0)';
      BIDIRECTIONAL='TRUE';
      INPUT_LOAD='(-0.01,0.01)';
      OUTPUT_LOAD='(1.0,-1.0)';
      PINUSE='BI';
    'MFA_DATA19':
      PIN_NUMBER='(0,0,0,0,0,W66,0,0,0,0,0,0,0,0,0,0,0,0,0,0,0,0,0,0,0,0,0,0,0,0~
,0,0,0,0,0,0,0,0,0,0)';
      BIDIRECTIONAL='TRUE';
      INPUT_LOAD='(-0.01,0.01)';
      OUTPUT_LOAD='(1.0,-1.0)';
      PINUSE='BI';
    'MFA_DATA2':
      PIN_NUMBER='(0,0,0,0,0,F67,0,0,0,0,0,0,0,0,0,0,0,0,0,0,0,0,0,0,0,0,0,0,0,0~
,0,0,0,0,0,0,0,0,0,0)';
      BIDIRECTIONAL='TRUE';
      INPUT_LOAD='(-0.01,0.01)';
      OUTPUT_LOAD='(1.0,-1.0)';
      PINUSE='BI';
    'MFB_DQS_L1':
      PIN_NUMBER='(0,0,0,0,0,CL67,0,0,0,0,0,0,0,0,0,0,0,0,0,0,0,0,0,0,0,0,0,0,0,~
0,0,0,0,0,0,0,0,0,0,0)';
      BIDIRECTIONAL='TRUE';
      INPUT_LOAD='(-0.01,0.01)';
      OUTPUT_LOAD='(1.0,-1.0)';
      PINUSE='BI';
    'MFB_DATA25':
      PIN_NUMBER='(0,0,0,0,0,DA66,0,0,0,0,0,0,0,0,0,0,0,0,0,0,0,0,0,0,0,0,0,0,0,~
0,0,0,0,0,0,0,0,0,0,0)';
      BIDIRECTIONAL='TRUE';
      INPUT_LOAD='(-0.01,0.01)';
      OUTPUT_LOAD='(1.0,-1.0)';
      PINUSE='BI';
    'MFB_DATA14':
      PIN_NUMBER='(0,0,0,0,0,CN67,0,0,0,0,0,0,0,0,0,0,0,0,0,0,0,0,0,0,0,0,0,0,0,~
0,0,0,0,0,0,0,0,0,0,0)';
      BIDIRECTIONAL='TRUE';
      INPUT_LOAD='(-0.01,0.01)';
      OUTPUT_LOAD='(1.0,-1.0)';
      PINUSE='BI';
    'MFB_DATA2':
      PIN_NUMBER='(0,0,0,0,0,CC67,0,0,0,0,0,0,0,0,0,0,0,0,0,0,0,0,0,0,0,0,0,0,0,~
0,0,0,0,0,0,0,0,0,0,0)';
      BIDIRECTIONAL='TRUE';
      INPUT_LOAD='(-0.01,0.01)';
      OUTPUT_LOAD='(1.0,-1.0)';
      PINUSE='BI';
    'MFB_CHECK5':
      PIN_NUMBER='(0,0,0,0,0,BU66,0,0,0,0,0,0,0,0,0,0,0,0,0,0,0,0,0,0,0,0,0,0,0,~
0,0,0,0,0,0,0,0,0,0,0)';
      BIDIRECTIONAL='TRUE';
      INPUT_LOAD='(-0.01,0.01)';
      OUTPUT_LOAD='(1.0,-1.0)';
      PINUSE='BI';
    'MFA_DQS_L7':
      PIN_NUMBER='(0,0,0,0,0,Y65,0,0,0,0,0,0,0,0,0,0,0,0,0,0,0,0,0,0,0,0,0,0,0,0~
,0,0,0,0,0,0,0,0,0,0)';
      BIDIRECTIONAL='TRUE';
      INPUT_LOAD='(-0.01,0.01)';
      OUTPUT_LOAD='(1.0,-1.0)';
      PINUSE='BI';
    'MFA_DQS_H3':
      PIN_NUMBER='(0,0,0,0,0,AE67,0,0,0,0,0,0,0,0,0,0,0,0,0,0,0,0,0,0,0,0,0,0,0,~
0,0,0,0,0,0,0,0,0,0,0)';
      BIDIRECTIONAL='TRUE';
      INPUT_LOAD='(-0.01,0.01)';
      OUTPUT_LOAD='(1.0,-1.0)';
      PINUSE='BI';
    'MFA_DATA3':
      PIN_NUMBER='(0,0,0,0,0,G66,0,0,0,0,0,0,0,0,0,0,0,0,0,0,0,0,0,0,0,0,0,0,0,0~
,0,0,0,0,0,0,0,0,0,0)';
      BIDIRECTIONAL='TRUE';
      INPUT_LOAD='(-0.01,0.01)';
      OUTPUT_LOAD='(1.0,-1.0)';
      PINUSE='BI';
    'MFB_DQS_L2':
      PIN_NUMBER='(0,0,0,0,0,CU67,0,0,0,0,0,0,0,0,0,0,0,0,0,0,0,0,0,0,0,0,0,0,0,~
0,0,0,0,0,0,0,0,0,0,0)';
      BIDIRECTIONAL='TRUE';
      INPUT_LOAD='(-0.01,0.01)';
      OUTPUT_LOAD='(1.0,-1.0)';
      PINUSE='BI';
    'MFB_DATA26':
      PIN_NUMBER='(0,0,0,0,0,DA67,0,0,0,0,0,0,0,0,0,0,0,0,0,0,0,0,0,0,0,0,0,0,0,~
0,0,0,0,0,0,0,0,0,0,0)';
      BIDIRECTIONAL='TRUE';
      INPUT_LOAD='(-0.01,0.01)';
      OUTPUT_LOAD='(1.0,-1.0)';
      PINUSE='BI';
    'MFB_DATA15':
      PIN_NUMBER='(0,0,0,0,0,CP65,0,0,0,0,0,0,0,0,0,0,0,0,0,0,0,0,0,0,0,0,0,0,0,~
0,0,0,0,0,0,0,0,0,0,0)';
      BIDIRECTIONAL='TRUE';
      INPUT_LOAD='(-0.01,0.01)';
      OUTPUT_LOAD='(1.0,-1.0)';
      PINUSE='BI';
    'MFB_DATA3':
      PIN_NUMBER='(0,0,0,0,0,CD65,0,0,0,0,0,0,0,0,0,0,0,0,0,0,0,0,0,0,0,0,0,0,0,~
0,0,0,0,0,0,0,0,0,0,0)';
      BIDIRECTIONAL='TRUE';
      INPUT_LOAD='(-0.01,0.01)';
      OUTPUT_LOAD='(1.0,-1.0)';
      PINUSE='BI';
    'MFB_CHECK6':
      PIN_NUMBER='(0,0,0,0,0,BU67,0,0,0,0,0,0,0,0,0,0,0,0,0,0,0,0,0,0,0,0,0,0,0,~
0,0,0,0,0,0,0,0,0,0,0)';
      BIDIRECTIONAL='TRUE';
      INPUT_LOAD='(-0.01,0.01)';
      OUTPUT_LOAD='(1.0,-1.0)';
      PINUSE='BI';
    'MFA_DQS_L8':
      PIN_NUMBER='(0,0,0,0,0,AF65,0,0,0,0,0,0,0,0,0,0,0,0,0,0,0,0,0,0,0,0,0,0,0,~
0,0,0,0,0,0,0,0,0,0,0)';
      BIDIRECTIONAL='TRUE';
      INPUT_LOAD='(-0.01,0.01)';
      OUTPUT_LOAD='(1.0,-1.0)';
      PINUSE='BI';
    'MFA_DQS_H4':
      PIN_NUMBER='(0,0,0,0,0,AL67,0,0,0,0,0,0,0,0,0,0,0,0,0,0,0,0,0,0,0,0,0,0,0,~
0,0,0,0,0,0,0,0,0,0,0)';
      BIDIRECTIONAL='TRUE';
      INPUT_LOAD='(-0.01,0.01)';
      OUTPUT_LOAD='(1.0,-1.0)';
      PINUSE='BI';
    'MFA_DATA4':
      PIN_NUMBER='(0,0,0,0,0,J67,0,0,0,0,0,0,0,0,0,0,0,0,0,0,0,0,0,0,0,0,0,0,0,0~
,0,0,0,0,0,0,0,0,0,0)';
      BIDIRECTIONAL='TRUE';
      INPUT_LOAD='(-0.01,0.01)';
      OUTPUT_LOAD='(1.0,-1.0)';
      PINUSE='BI';
    'MFB_DQS_L3':
      PIN_NUMBER='(0,0,0,0,0,DC67,0,0,0,0,0,0,0,0,0,0,0,0,0,0,0,0,0,0,0,0,0,0,0,~
0,0,0,0,0,0,0,0,0,0,0)';
      BIDIRECTIONAL='TRUE';
      INPUT_LOAD='(-0.01,0.01)';
      OUTPUT_LOAD='(1.0,-1.0)';
      PINUSE='BI';
    'MFB_DATA27':
      PIN_NUMBER='(0,0,0,0,0,DB65,0,0,0,0,0,0,0,0,0,0,0,0,0,0,0,0,0,0,0,0,0,0,0,~
0,0,0,0,0,0,0,0,0,0,0)';
      BIDIRECTIONAL='TRUE';
      INPUT_LOAD='(-0.01,0.01)';
      OUTPUT_LOAD='(1.0,-1.0)';
      PINUSE='BI';
    'MFB_DATA16':
      PIN_NUMBER='(0,0,0,0,0,CP67,0,0,0,0,0,0,0,0,0,0,0,0,0,0,0,0,0,0,0,0,0,0,0,~
0,0,0,0,0,0,0,0,0,0,0)';
      BIDIRECTIONAL='TRUE';
      INPUT_LOAD='(-0.01,0.01)';
      OUTPUT_LOAD='(1.0,-1.0)';
      PINUSE='BI';
    'MFB_DATA4':
      PIN_NUMBER='(0,0,0,0,0,CF67,0,0,0,0,0,0,0,0,0,0,0,0,0,0,0,0,0,0,0,0,0,0,0,~
0,0,0,0,0,0,0,0,0,0,0)';
      BIDIRECTIONAL='TRUE';
      INPUT_LOAD='(-0.01,0.01)';
      OUTPUT_LOAD='(1.0,-1.0)';
      PINUSE='BI';
    'MFB_CHECK7':
      PIN_NUMBER='(0,0,0,0,0,BV65,0,0,0,0,0,0,0,0,0,0,0,0,0,0,0,0,0,0,0,0,0,0,0,~
0,0,0,0,0,0,0,0,0,0,0)';
      BIDIRECTIONAL='TRUE';
      INPUT_LOAD='(-0.01,0.01)';
      OUTPUT_LOAD='(1.0,-1.0)';
      PINUSE='BI';
    'MFB0_RSP_L':
      PIN_NUMBER='(0,0,0,0,0,BP67,0,0,0,0,0,0,0,0,0,0,0,0,0,0,0,0,0,0,0,0,0,0,0,~
0,0,0,0,0,0,0,0,0,0,0)';
      INPUT_LOAD='(-0.01,0.01)';
      PINUSE='IN';
    'MFA_DQS_L9':
      PIN_NUMBER='(0,0,0,0,0,AM65,0,0,0,0,0,0,0,0,0,0,0,0,0,0,0,0,0,0,0,0,0,0,0,~
0,0,0,0,0,0,0,0,0,0,0)';
      BIDIRECTIONAL='TRUE';
      INPUT_LOAD='(-0.01,0.01)';
      OUTPUT_LOAD='(1.0,-1.0)';
      PINUSE='BI';
    'MFA_DQS_H5':
      PIN_NUMBER='(0,0,0,0,0,J66,0,0,0,0,0,0,0,0,0,0,0,0,0,0,0,0,0,0,0,0,0,0,0,0~
,0,0,0,0,0,0,0,0,0,0)';
      BIDIRECTIONAL='TRUE';
      INPUT_LOAD='(-0.01,0.01)';
      OUTPUT_LOAD='(1.0,-1.0)';
      PINUSE='BI';
    'MFA_DATA5':
      PIN_NUMBER='(0,0,0,0,0,K65,0,0,0,0,0,0,0,0,0,0,0,0,0,0,0,0,0,0,0,0,0,0,0,0~
,0,0,0,0,0,0,0,0,0,0)';
      BIDIRECTIONAL='TRUE';
      INPUT_LOAD='(-0.01,0.01)';
      OUTPUT_LOAD='(1.0,-1.0)';
      PINUSE='BI';
    'MFB_DQS_L4':
      PIN_NUMBER='(0,0,0,0,0,BW66,0,0,0,0,0,0,0,0,0,0,0,0,0,0,0,0,0,0,0,0,0,0,0,~
0,0,0,0,0,0,0,0,0,0,0)';
      BIDIRECTIONAL='TRUE';
      INPUT_LOAD='(-0.01,0.01)';
      OUTPUT_LOAD='(1.0,-1.0)';
      PINUSE='BI';
    'MFB_DQS_H0':
      PIN_NUMBER='(0,0,0,0,0,CD67,0,0,0,0,0,0,0,0,0,0,0,0,0,0,0,0,0,0,0,0,0,0,0,~
0,0,0,0,0,0,0,0,0,0,0)';
      BIDIRECTIONAL='TRUE';
      INPUT_LOAD='(-0.01,0.01)';
      OUTPUT_LOAD='(1.0,-1.0)';
      PINUSE='BI';
    'MFB_DATA28':
      PIN_NUMBER='(0,0,0,0,0,DD67,0,0,0,0,0,0,0,0,0,0,0,0,0,0,0,0,0,0,0,0,0,0,0,~
0,0,0,0,0,0,0,0,0,0,0)';
      BIDIRECTIONAL='TRUE';
      INPUT_LOAD='(-0.01,0.01)';
      OUTPUT_LOAD='(1.0,-1.0)';
      PINUSE='BI';
    'MFB_DATA17':
      PIN_NUMBER='(0,0,0,0,0,CR66,0,0,0,0,0,0,0,0,0,0,0,0,0,0,0,0,0,0,0,0,0,0,0,~
0,0,0,0,0,0,0,0,0,0,0)';
      BIDIRECTIONAL='TRUE';
      INPUT_LOAD='(-0.01,0.01)';
      OUTPUT_LOAD='(1.0,-1.0)';
      PINUSE='BI';
    'MFB_DATA5':
      PIN_NUMBER='(0,0,0,0,0,CG66,0,0,0,0,0,0,0,0,0,0,0,0,0,0,0,0,0,0,0,0,0,0,0,~
0,0,0,0,0,0,0,0,0,0,0)';
      BIDIRECTIONAL='TRUE';
      INPUT_LOAD='(-0.01,0.01)';
      OUTPUT_LOAD='(1.0,-1.0)';
      PINUSE='BI';
    'MFB1_RSP_L':
      PIN_NUMBER='(0,0,0,0,0,BR67,0,0,0,0,0,0,0,0,0,0,0,0,0,0,0,0,0,0,0,0,0,0,0,~
0,0,0,0,0,0,0,0,0,0,0)';
      INPUT_LOAD='(-0.01,0.01)';
      PINUSE='IN';
    'MFA_DQS_H6':
      PIN_NUMBER='(0,0,0,0,0,R66,0,0,0,0,0,0,0,0,0,0,0,0,0,0,0,0,0,0,0,0,0,0,0,0~
,0,0,0,0,0,0,0,0,0,0)';
      BIDIRECTIONAL='TRUE';
      INPUT_LOAD='(-0.01,0.01)';
      OUTPUT_LOAD='(1.0,-1.0)';
      PINUSE='BI';
    'MFA_DATA6':
      PIN_NUMBER='(0,0,0,0,0,K67,0,0,0,0,0,0,0,0,0,0,0,0,0,0,0,0,0,0,0,0,0,0,0,0~
,0,0,0,0,0,0,0,0,0,0)';
      BIDIRECTIONAL='TRUE';
      INPUT_LOAD='(-0.01,0.01)';
      OUTPUT_LOAD='(1.0,-1.0)';
      PINUSE='BI';
    'MFB_DQS_L5':
      PIN_NUMBER='(0,0,0,0,0,CE66,0,0,0,0,0,0,0,0,0,0,0,0,0,0,0,0,0,0,0,0,0,0,0,~
0,0,0,0,0,0,0,0,0,0,0)';
      BIDIRECTIONAL='TRUE';
      INPUT_LOAD='(-0.01,0.01)';
      OUTPUT_LOAD='(1.0,-1.0)';
      PINUSE='BI';
    'MFB_DQS_H1':
      PIN_NUMBER='(0,0,0,0,0,CK67,0,0,0,0,0,0,0,0,0,0,0,0,0,0,0,0,0,0,0,0,0,0,0,~
0,0,0,0,0,0,0,0,0,0,0)';
      BIDIRECTIONAL='TRUE';
      INPUT_LOAD='(-0.01,0.01)';
      OUTPUT_LOAD='(1.0,-1.0)';
      PINUSE='BI';
    'MFB_DATA29':
      PIN_NUMBER='(0,0,0,0,0,DE66,0,0,0,0,0,0,0,0,0,0,0,0,0,0,0,0,0,0,0,0,0,0,0,~
0,0,0,0,0,0,0,0,0,0,0)';
      BIDIRECTIONAL='TRUE';
      INPUT_LOAD='(-0.01,0.01)';
      OUTPUT_LOAD='(1.0,-1.0)';
      PINUSE='BI';
    'MFB_DATA18':
      PIN_NUMBER='(0,0,0,0,0,CR67,0,0,0,0,0,0,0,0,0,0,0,0,0,0,0,0,0,0,0,0,0,0,0,~
0,0,0,0,0,0,0,0,0,0,0)';
      BIDIRECTIONAL='TRUE';
      INPUT_LOAD='(-0.01,0.01)';
      OUTPUT_LOAD='(1.0,-1.0)';
      PINUSE='BI';
    'MFB_DATA6':
      PIN_NUMBER='(0,0,0,0,0,CG67,0,0,0,0,0,0,0,0,0,0,0,0,0,0,0,0,0,0,0,0,0,0,0,~
0,0,0,0,0,0,0,0,0,0,0)';
      BIDIRECTIONAL='TRUE';
      INPUT_LOAD='(-0.01,0.01)';
      OUTPUT_LOAD='(1.0,-1.0)';
      PINUSE='BI';
    'MFA_DQS_H7':
      PIN_NUMBER='(0,0,0,0,0,AA66,0,0,0,0,0,0,0,0,0,0,0,0,0,0,0,0,0,0,0,0,0,0,0,~
0,0,0,0,0,0,0,0,0,0,0)';
      BIDIRECTIONAL='TRUE';
      INPUT_LOAD='(-0.01,0.01)';
      OUTPUT_LOAD='(1.0,-1.0)';
      PINUSE='BI';
    'MFA_DATA7':
      PIN_NUMBER='(0,0,0,0,0,L66,0,0,0,0,0,0,0,0,0,0,0,0,0,0,0,0,0,0,0,0,0,0,0,0~
,0,0,0,0,0,0,0,0,0,0)';
      BIDIRECTIONAL='TRUE';
      INPUT_LOAD='(-0.01,0.01)';
      OUTPUT_LOAD='(1.0,-1.0)';
      PINUSE='BI';
    'MFA0_CS_L0':
      PIN_NUMBER='(0,0,0,0,0,AV67,0,0,0,0,0,0,0,0,0,0,0,0,0,0,0,0,0,0,0,0,0,0,0,~
0,0,0,0,0,0,0,0,0,0,0)';
      OUTPUT_LOAD='(1.0,-1.0)';
      PINUSE='OUT';
    'MFA_PAR':
      PIN_NUMBER='(0,0,0,0,0,BC66,0,0,0,0,0,0,0,0,0,0,0,0,0,0,0,0,0,0,0,0,0,0,0,~
0,0,0,0,0,0,0,0,0,0,0)';
      OUTPUT_LOAD='(1.0,-1.0)';
      PINUSE='OUT';
    'MFB_PAR':
      PIN_NUMBER='(0,0,0,0,0,BL67,0,0,0,0,0,0,0,0,0,0,0,0,0,0,0,0,0,0,0,0,0,0,0,~
0,0,0,0,0,0,0,0,0,0,0)';
      OUTPUT_LOAD='(1.0,-1.0)';
      PINUSE='OUT';
    'MFB_DQS_H9':
      PIN_NUMBER='(0,0,0,0,0,BV67,0,0,0,0,0,0,0,0,0,0,0,0,0,0,0,0,0,0,0,0,0,0,0,~
0,0,0,0,0,0,0,0,0,0,0)';
      BIDIRECTIONAL='TRUE';
      INPUT_LOAD='(-0.01,0.01)';
      OUTPUT_LOAD='(1.0,-1.0)';
      PINUSE='BI';
    'MF0_CLK_H':
      PIN_NUMBER='(0,0,0,0,0,BC67,0,0,0,0,0,0,0,0,0,0,0,0,0,0,0,0,0,0,0,0,0,0,0,~
0,0,0,0,0,0,0,0,0,0,0)';
      OUTPUT_LOAD='(1.0,-1.0)';
      PINUSE='OUT';
    'MF0_CLK_L':
      PIN_NUMBER='(0,0,0,0,0,BD67,0,0,0,0,0,0,0,0,0,0,0,0,0,0,0,0,0,0,0,0,0,0,0,~
0,0,0,0,0,0,0,0,0,0,0)';
      OUTPUT_LOAD='(1.0,-1.0)';
      PINUSE='OUT';
    'MF1_CLK_H':
      PIN_NUMBER='(0,0,0,0,0,BF67,0,0,0,0,0,0,0,0,0,0,0,0,0,0,0,0,0,0,0,0,0,0,0,~
0,0,0,0,0,0,0,0,0,0,0)';
      OUTPUT_LOAD='(1.0,-1.0)';
      PINUSE='OUT';
    'MF1_CLK_L':
      PIN_NUMBER='(0,0,0,0,0,BG67,0,0,0,0,0,0,0,0,0,0,0,0,0,0,0,0,0,0,0,0,0,0,0,~
0,0,0,0,0,0,0,0,0,0,0)';
      OUTPUT_LOAD='(1.0,-1.0)';
      PINUSE='OUT';
    'TEST39F':
      PIN_NUMBER='(0,0,0,0,0,BF65,0,0,0,0,0,0,0,0,0,0,0,0,0,0,0,0,0,0,0,0,0,0,0,~
0,0,0,0,0,0,0,0,0,0,0)';
      OUTPUT_LOAD='(1.0,-1.0)';
      PINUSE='OUT';
    'MG_ALERT_L':
      PIN_NUMBER='(0,0,0,0,0,0,AR2,0,0,0,0,0,0,0,0,0,0,0,0,0,0,0,0,0,0,0,0,0,0,0~
,0,0,0,0,0,0,0,0,0,0)';
      INPUT_LOAD='(-0.01,0.01)';
      PINUSE='IN';
    'MG_RESET_L':
      PIN_NUMBER='(0,0,0,0,0,0,AT2,0,0,0,0,0,0,0,0,0,0,0,0,0,0,0,0,0,0,0,0,0,0,0~
,0,0,0,0,0,0,0,0,0,0)';
      OUTPUT_LOAD='(1.0,-1.0)';
      PINUSE='OUT';
    'MGB_DQS_L9':
      PIN_NUMBER='(0,0,0,0,0,0,BW2,0,0,0,0,0,0,0,0,0,0,0,0,0,0,0,0,0,0,0,0,0,0,0~
,0,0,0,0,0,0,0,0,0,0)';
      BIDIRECTIONAL='TRUE';
      INPUT_LOAD='(-0.01,0.01)';
      OUTPUT_LOAD='(1.0,-1.0)';
      PINUSE='BI';
    'MGB_DQS_H5':
      PIN_NUMBER='(0,0,0,0,0,0,CF4,0,0,0,0,0,0,0,0,0,0,0,0,0,0,0,0,0,0,0,0,0,0,0~
,0,0,0,0,0,0,0,0,0,0)';
      BIDIRECTIONAL='TRUE';
      INPUT_LOAD='(-0.01,0.01)';
      OUTPUT_LOAD='(1.0,-1.0)';
      PINUSE='BI';
    'MGB_DATA1':
      PIN_NUMBER='(0,0,0,0,0,0,CC3,0,0,0,0,0,0,0,0,0,0,0,0,0,0,0,0,0,0,0,0,0,0,0~
,0,0,0,0,0,0,0,0,0,0)';
      BIDIRECTIONAL='TRUE';
      INPUT_LOAD='(-0.01,0.01)';
      OUTPUT_LOAD='(1.0,-1.0)';
      PINUSE='BI';
    'MGA_DATA22':
      PIN_NUMBER='(0,0,0,0,0,0,AB2,0,0,0,0,0,0,0,0,0,0,0,0,0,0,0,0,0,0,0,0,0,0,0~
,0,0,0,0,0,0,0,0,0,0)';
      BIDIRECTIONAL='TRUE';
      INPUT_LOAD='(-0.01,0.01)';
      OUTPUT_LOAD='(1.0,-1.0)';
      PINUSE='BI';
    'MGA_DATA11':
      PIN_NUMBER='(0,0,0,0,0,0,N3,0,0,0,0,0,0,0,0,0,0,0,0,0,0,0,0,0,0,0,0,0,0,0,~
0,0,0,0,0,0,0,0,0,0)';
      BIDIRECTIONAL='TRUE';
      INPUT_LOAD='(-0.01,0.01)';
      OUTPUT_LOAD='(1.0,-1.0)';
      PINUSE='BI';
    'MGA_DATA1':
      PIN_NUMBER='(0,0,0,0,0,0,F4,0,0,0,0,0,0,0,0,0,0,0,0,0,0,0,0,0,0,0,0,0,0,0,~
0,0,0,0,0,0,0,0,0,0)';
      BIDIRECTIONAL='TRUE';
      INPUT_LOAD='(-0.01,0.01)';
      OUTPUT_LOAD='(1.0,-1.0)';
      PINUSE='BI';
    'MGA_CHECK2':
      PIN_NUMBER='(0,0,0,0,0,0,AK2,0,0,0,0,0,0,0,0,0,0,0,0,0,0,0,0,0,0,0,0,0,0,0~
,0,0,0,0,0,0,0,0,0,0)';
      BIDIRECTIONAL='TRUE';
      INPUT_LOAD='(-0.01,0.01)';
      OUTPUT_LOAD='(1.0,-1.0)';
      PINUSE='BI';
    'MGB_DQS_H6':
      PIN_NUMBER='(0,0,0,0,0,0,CM4,0,0,0,0,0,0,0,0,0,0,0,0,0,0,0,0,0,0,0,0,0,0,0~
,0,0,0,0,0,0,0,0,0,0)';
      BIDIRECTIONAL='TRUE';
      INPUT_LOAD='(-0.01,0.01)';
      OUTPUT_LOAD='(1.0,-1.0)';
      PINUSE='BI';
    'MGB_DATA2':
      PIN_NUMBER='(0,0,0,0,0,0,CC2,0,0,0,0,0,0,0,0,0,0,0,0,0,0,0,0,0,0,0,0,0,0,0~
,0,0,0,0,0,0,0,0,0,0)';
      BIDIRECTIONAL='TRUE';
      INPUT_LOAD='(-0.01,0.01)';
      OUTPUT_LOAD='(1.0,-1.0)';
      PINUSE='BI';
    'MGA_DATA23':
      PIN_NUMBER='(0,0,0,0,0,0,AC3,0,0,0,0,0,0,0,0,0,0,0,0,0,0,0,0,0,0,0,0,0,0,0~
,0,0,0,0,0,0,0,0,0,0)';
      BIDIRECTIONAL='TRUE';
      INPUT_LOAD='(-0.01,0.01)';
      OUTPUT_LOAD='(1.0,-1.0)';
      PINUSE='BI';
    'MGA_DATA12':
      PIN_NUMBER='(0,0,0,0,0,0,R2,0,0,0,0,0,0,0,0,0,0,0,0,0,0,0,0,0,0,0,0,0,0,0,~
0,0,0,0,0,0,0,0,0,0)';
      BIDIRECTIONAL='TRUE';
      INPUT_LOAD='(-0.01,0.01)';
      OUTPUT_LOAD='(1.0,-1.0)';
      PINUSE='BI';
    'MGA_DATA2':
      PIN_NUMBER='(0,0,0,0,0,0,F2,0,0,0,0,0,0,0,0,0,0,0,0,0,0,0,0,0,0,0,0,0,0,0,~
0,0,0,0,0,0,0,0,0,0)';
      BIDIRECTIONAL='TRUE';
      INPUT_LOAD='(-0.01,0.01)';
      OUTPUT_LOAD='(1.0,-1.0)';
      PINUSE='BI';
    'MGA_CHECK3':
      PIN_NUMBER='(0,0,0,0,0,0,AL3,0,0,0,0,0,0,0,0,0,0,0,0,0,0,0,0,0,0,0,0,0,0,0~
,0,0,0,0,0,0,0,0,0,0)';
      BIDIRECTIONAL='TRUE';
      INPUT_LOAD='(-0.01,0.01)';
      OUTPUT_LOAD='(1.0,-1.0)';
      PINUSE='BI';
    'MGB_DQS_H7':
      PIN_NUMBER='(0,0,0,0,0,0,CV4,0,0,0,0,0,0,0,0,0,0,0,0,0,0,0,0,0,0,0,0,0,0,0~
,0,0,0,0,0,0,0,0,0,0)';
      BIDIRECTIONAL='TRUE';
      INPUT_LOAD='(-0.01,0.01)';
      OUTPUT_LOAD='(1.0,-1.0)';
      PINUSE='BI';
    'MGB_DATA3':
      PIN_NUMBER='(0,0,0,0,0,0,CD4,0,0,0,0,0,0,0,0,0,0,0,0,0,0,0,0,0,0,0,0,0,0,0~
,0,0,0,0,0,0,0,0,0,0)';
      BIDIRECTIONAL='TRUE';
      INPUT_LOAD='(-0.01,0.01)';
      OUTPUT_LOAD='(1.0,-1.0)';
      PINUSE='BI';
    'MGB1_CS_L0':
      PIN_NUMBER='(0,0,0,0,0,0,BL2,0,0,0,0,0,0,0,0,0,0,0,0,0,0,0,0,0,0,0,0,0,0,0~
,0,0,0,0,0,0,0,0,0,0)';
      OUTPUT_LOAD='(1.0,-1.0)';
      PINUSE='OUT';
    'MGB0_CS_L0':
      PIN_NUMBER='(0,0,0,0,0,0,BM4,0,0,0,0,0,0,0,0,0,0,0,0,0,0,0,0,0,0,0,0,0,0,0~
,0,0,0,0,0,0,0,0,0,0)';
      OUTPUT_LOAD='(1.0,-1.0)';
      PINUSE='OUT';
    'MGA_DQS_L0':
      PIN_NUMBER='(0,0,0,0,0,0,H2,0,0,0,0,0,0,0,0,0,0,0,0,0,0,0,0,0,0,0,0,0,0,0,~
0,0,0,0,0,0,0,0,0,0)';
      BIDIRECTIONAL='TRUE';
      INPUT_LOAD='(-0.01,0.01)';
      OUTPUT_LOAD='(1.0,-1.0)';
      PINUSE='BI';
    'MGA_DATA24':
      PIN_NUMBER='(0,0,0,0,0,0,AC2,0,0,0,0,0,0,0,0,0,0,0,0,0,0,0,0,0,0,0,0,0,0,0~
,0,0,0,0,0,0,0,0,0,0)';
      BIDIRECTIONAL='TRUE';
      INPUT_LOAD='(-0.01,0.01)';
      OUTPUT_LOAD='(1.0,-1.0)';
      PINUSE='BI';
    'MGA_DATA13':
      PIN_NUMBER='(0,0,0,0,0,0,T4,0,0,0,0,0,0,0,0,0,0,0,0,0,0,0,0,0,0,0,0,0,0,0,~
0,0,0,0,0,0,0,0,0,0)';
      BIDIRECTIONAL='TRUE';
      INPUT_LOAD='(-0.01,0.01)';
      OUTPUT_LOAD='(1.0,-1.0)';
      PINUSE='BI';
    'MGA_DATA3':
      PIN_NUMBER='(0,0,0,0,0,0,G3,0,0,0,0,0,0,0,0,0,0,0,0,0,0,0,0,0,0,0,0,0,0,0,~
0,0,0,0,0,0,0,0,0,0)';
      BIDIRECTIONAL='TRUE';
      INPUT_LOAD='(-0.01,0.01)';
      OUTPUT_LOAD='(1.0,-1.0)';
      PINUSE='BI';
    'MGA_CHECK4':
      PIN_NUMBER='(0,0,0,0,0,0,AN2,0,0,0,0,0,0,0,0,0,0,0,0,0,0,0,0,0,0,0,0,0,0,0~
,0,0,0,0,0,0,0,0,0,0)';
      BIDIRECTIONAL='TRUE';
      INPUT_LOAD='(-0.01,0.01)';
      OUTPUT_LOAD='(1.0,-1.0)';
      PINUSE='BI';
    'MGB_DQS_H8':
      PIN_NUMBER='(0,0,0,0,0,0,DD4,0,0,0,0,0,0,0,0,0,0,0,0,0,0,0,0,0,0,0,0,0,0,0~
,0,0,0,0,0,0,0,0,0,0)';
      BIDIRECTIONAL='TRUE';
      INPUT_LOAD='(-0.01,0.01)';
      OUTPUT_LOAD='(1.0,-1.0)';
      PINUSE='BI';
    'MGB_DATA30':
      PIN_NUMBER='(0,0,0,0,0,0,DE2,0,0,0,0,0,0,0,0,0,0,0,0,0,0,0,0,0,0,0,0,0,0,0~
,0,0,0,0,0,0,0,0,0,0)';
      BIDIRECTIONAL='TRUE';
      INPUT_LOAD='(-0.01,0.01)';
      OUTPUT_LOAD='(1.0,-1.0)';
      PINUSE='BI';
    'MGB_DATA4':
      PIN_NUMBER='(0,0,0,0,0,0,CF2,0,0,0,0,0,0,0,0,0,0,0,0,0,0,0,0,0,0,0,0,0,0,0~
,0,0,0,0,0,0,0,0,0,0)';
      BIDIRECTIONAL='TRUE';
      INPUT_LOAD='(-0.01,0.01)';
      OUTPUT_LOAD='(1.0,-1.0)';
      PINUSE='BI';
    'MGB1_CS_L1':
      PIN_NUMBER='(0,0,0,0,0,0,BM2,0,0,0,0,0,0,0,0,0,0,0,0,0,0,0,0,0,0,0,0,0,0,0~
,0,0,0,0,0,0,0,0,0,0)';
      OUTPUT_LOAD='(1.0,-1.0)';
      PINUSE='OUT';
    'MGB0_CS_L1':
      PIN_NUMBER='(0,0,0,0,0,0,BN2,0,0,0,0,0,0,0,0,0,0,0,0,0,0,0,0,0,0,0,0,0,0,0~
,0,0,0,0,0,0,0,0,0,0)';
      OUTPUT_LOAD='(1.0,-1.0)';
      PINUSE='OUT';
    'MGA_DQS_L1':
      PIN_NUMBER='(0,0,0,0,0,0,P2,0,0,0,0,0,0,0,0,0,0,0,0,0,0,0,0,0,0,0,0,0,0,0,~
0,0,0,0,0,0,0,0,0,0)';
      BIDIRECTIONAL='TRUE';
      INPUT_LOAD='(-0.01,0.01)';
      OUTPUT_LOAD='(1.0,-1.0)';
      PINUSE='BI';
    'MGA_DATA25':
      PIN_NUMBER='(0,0,0,0,0,0,AD4,0,0,0,0,0,0,0,0,0,0,0,0,0,0,0,0,0,0,0,0,0,0,0~
,0,0,0,0,0,0,0,0,0,0)';
      BIDIRECTIONAL='TRUE';
      INPUT_LOAD='(-0.01,0.01)';
      OUTPUT_LOAD='(1.0,-1.0)';
      PINUSE='BI';
    'MGA_DATA14':
      PIN_NUMBER='(0,0,0,0,0,0,T2,0,0,0,0,0,0,0,0,0,0,0,0,0,0,0,0,0,0,0,0,0,0,0,~
0,0,0,0,0,0,0,0,0,0)';
      BIDIRECTIONAL='TRUE';
      INPUT_LOAD='(-0.01,0.01)';
      OUTPUT_LOAD='(1.0,-1.0)';
      PINUSE='BI';
    'MGA_DATA4':
      PIN_NUMBER='(0,0,0,0,0,0,J2,0,0,0,0,0,0,0,0,0,0,0,0,0,0,0,0,0,0,0,0,0,0,0,~
0,0,0,0,0,0,0,0,0,0)';
      BIDIRECTIONAL='TRUE';
      INPUT_LOAD='(-0.01,0.01)';
      OUTPUT_LOAD='(1.0,-1.0)';
      PINUSE='BI';
    'MGA_CHECK5':
      PIN_NUMBER='(0,0,0,0,0,0,AP4,0,0,0,0,0,0,0,0,0,0,0,0,0,0,0,0,0,0,0,0,0,0,0~
,0,0,0,0,0,0,0,0,0,0)';
      BIDIRECTIONAL='TRUE';
      INPUT_LOAD='(-0.01,0.01)';
      OUTPUT_LOAD='(1.0,-1.0)';
      PINUSE='BI';
    'MGA_CA0':
      PIN_NUMBER='(0,0,0,0,0,0,AW2,0,0,0,0,0,0,0,0,0,0,0,0,0,0,0,0,0,0,0,0,0,0,0~
,0,0,0,0,0,0,0,0,0,0)';
      OUTPUT_LOAD='(1.0,-1.0)';
      PINUSE='OUT';
    'MGB_DATA31':
      PIN_NUMBER='(0,0,0,0,0,0,DF2,0,0,0,0,0,0,0,0,0,0,0,0,0,0,0,0,0,0,0,0,0,0,0~
,0,0,0,0,0,0,0,0,0,0)';
      BIDIRECTIONAL='TRUE';
      INPUT_LOAD='(-0.01,0.01)';
      OUTPUT_LOAD='(1.0,-1.0)';
      PINUSE='BI';
    'MGB_DATA20':
      PIN_NUMBER='(0,0,0,0,0,0,CV2,0,0,0,0,0,0,0,0,0,0,0,0,0,0,0,0,0,0,0,0,0,0,0~
,0,0,0,0,0,0,0,0,0,0)';
      BIDIRECTIONAL='TRUE';
      INPUT_LOAD='(-0.01,0.01)';
      OUTPUT_LOAD='(1.0,-1.0)';
      PINUSE='BI';
    'MGB_DATA5':
      PIN_NUMBER='(0,0,0,0,0,0,CG3,0,0,0,0,0,0,0,0,0,0,0,0,0,0,0,0,0,0,0,0,0,0,0~
,0,0,0,0,0,0,0,0,0,0)';
      BIDIRECTIONAL='TRUE';
      INPUT_LOAD='(-0.01,0.01)';
      OUTPUT_LOAD='(1.0,-1.0)';
      PINUSE='BI';
    'MGB_CHECK0':
      PIN_NUMBER='(0,0,0,0,0,0,BY2,0,0,0,0,0,0,0,0,0,0,0,0,0,0,0,0,0,0,0,0,0,0,0~
,0,0,0,0,0,0,0,0,0,0)';
      BIDIRECTIONAL='TRUE';
      INPUT_LOAD='(-0.01,0.01)';
      OUTPUT_LOAD='(1.0,-1.0)';
      PINUSE='BI';
    'MGB_CA0':
      PIN_NUMBER='(0,0,0,0,0,0,BG3,0,0,0,0,0,0,0,0,0,0,0,0,0,0,0,0,0,0,0,0,0,0,0~
,0,0,0,0,0,0,0,0,0,0)';
      OUTPUT_LOAD='(1.0,-1.0)';
      PINUSE='OUT';
    'MGA_DQS_L2':
      PIN_NUMBER='(0,0,0,0,0,0,Y2,0,0,0,0,0,0,0,0,0,0,0,0,0,0,0,0,0,0,0,0,0,0,0,~
0,0,0,0,0,0,0,0,0,0)';
      BIDIRECTIONAL='TRUE';
      INPUT_LOAD='(-0.01,0.01)';
      OUTPUT_LOAD='(1.0,-1.0)';
      PINUSE='BI';
    'MGA_DATA26':
      PIN_NUMBER='(0,0,0,0,0,0,AD2,0,0,0,0,0,0,0,0,0,0,0,0,0,0,0,0,0,0,0,0,0,0,0~
,0,0,0,0,0,0,0,0,0,0)';
      BIDIRECTIONAL='TRUE';
      INPUT_LOAD='(-0.01,0.01)';
      OUTPUT_LOAD='(1.0,-1.0)';
      PINUSE='BI';
    'MGA_DATA15':
      PIN_NUMBER='(0,0,0,0,0,0,U3,0,0,0,0,0,0,0,0,0,0,0,0,0,0,0,0,0,0,0,0,0,0,0,~
0,0,0,0,0,0,0,0,0,0)';
      BIDIRECTIONAL='TRUE';
      INPUT_LOAD='(-0.01,0.01)';
      OUTPUT_LOAD='(1.0,-1.0)';
      PINUSE='BI';
    'MGA_DATA5':
      PIN_NUMBER='(0,0,0,0,0,0,K4,0,0,0,0,0,0,0,0,0,0,0,0,0,0,0,0,0,0,0,0,0,0,0,~
0,0,0,0,0,0,0,0,0,0)';
      BIDIRECTIONAL='TRUE';
      INPUT_LOAD='(-0.01,0.01)';
      OUTPUT_LOAD='(1.0,-1.0)';
      PINUSE='BI';
    'MGA_CHECK6':
      PIN_NUMBER='(0,0,0,0,0,0,AP2,0,0,0,0,0,0,0,0,0,0,0,0,0,0,0,0,0,0,0,0,0,0,0~
,0,0,0,0,0,0,0,0,0,0)';
      BIDIRECTIONAL='TRUE';
      INPUT_LOAD='(-0.01,0.01)';
      OUTPUT_LOAD='(1.0,-1.0)';
      PINUSE='BI';
    'MGA_CA1':
      PIN_NUMBER='(0,0,0,0,0,0,AY2,0,0,0,0,0,0,0,0,0,0,0,0,0,0,0,0,0,0,0,0,0,0,0~
,0,0,0,0,0,0,0,0,0,0)';
      OUTPUT_LOAD='(1.0,-1.0)';
      PINUSE='OUT';
    'MGB_DATA21':
      PIN_NUMBER='(0,0,0,0,0,0,CW3,0,0,0,0,0,0,0,0,0,0,0,0,0,0,0,0,0,0,0,0,0,0,0~
,0,0,0,0,0,0,0,0,0,0)';
      BIDIRECTIONAL='TRUE';
      INPUT_LOAD='(-0.01,0.01)';
      OUTPUT_LOAD='(1.0,-1.0)';
      PINUSE='BI';
    'MGB_DATA10':
      PIN_NUMBER='(0,0,0,0,0,0,CJ2,0,0,0,0,0,0,0,0,0,0,0,0,0,0,0,0,0,0,0,0,0,0,0~
,0,0,0,0,0,0,0,0,0,0)';
      BIDIRECTIONAL='TRUE';
      INPUT_LOAD='(-0.01,0.01)';
      OUTPUT_LOAD='(1.0,-1.0)';
      PINUSE='BI';
    'MGB_DATA6':
      PIN_NUMBER='(0,0,0,0,0,0,CG2,0,0,0,0,0,0,0,0,0,0,0,0,0,0,0,0,0,0,0,0,0,0,0~
,0,0,0,0,0,0,0,0,0,0)';
      BIDIRECTIONAL='TRUE';
      INPUT_LOAD='(-0.01,0.01)';
      OUTPUT_LOAD='(1.0,-1.0)';
      PINUSE='BI';
    'MGB_CHECK1':
      PIN_NUMBER='(0,0,0,0,0,0,CA3,0,0,0,0,0,0,0,0,0,0,0,0,0,0,0,0,0,0,0,0,0,0,0~
,0,0,0,0,0,0,0,0,0,0)';
      BIDIRECTIONAL='TRUE';
      INPUT_LOAD='(-0.01,0.01)';
      OUTPUT_LOAD='(1.0,-1.0)';
      PINUSE='BI';
    'MGB_CA1':
      PIN_NUMBER='(0,0,0,0,0,0,BH4,0,0,0,0,0,0,0,0,0,0,0,0,0,0,0,0,0,0,0,0,0,0,0~
,0,0,0,0,0,0,0,0,0,0)';
      OUTPUT_LOAD='(1.0,-1.0)';
      PINUSE='OUT';
    'MGA_DQS_L3':
      PIN_NUMBER='(0,0,0,0,0,0,AF2,0,0,0,0,0,0,0,0,0,0,0,0,0,0,0,0,0,0,0,0,0,0,0~
,0,0,0,0,0,0,0,0,0,0)';
      BIDIRECTIONAL='TRUE';
      INPUT_LOAD='(-0.01,0.01)';
      OUTPUT_LOAD='(1.0,-1.0)';
      PINUSE='BI';
    'MGA_DATA27':
      PIN_NUMBER='(0,0,0,0,0,0,AE3,0,0,0,0,0,0,0,0,0,0,0,0,0,0,0,0,0,0,0,0,0,0,0~
,0,0,0,0,0,0,0,0,0,0)';
      BIDIRECTIONAL='TRUE';
      INPUT_LOAD='(-0.01,0.01)';
      OUTPUT_LOAD='(1.0,-1.0)';
      PINUSE='BI';
    'MGA_DATA16':
      PIN_NUMBER='(0,0,0,0,0,0,U2,0,0,0,0,0,0,0,0,0,0,0,0,0,0,0,0,0,0,0,0,0,0,0,~
0,0,0,0,0,0,0,0,0,0)';
      BIDIRECTIONAL='TRUE';
      INPUT_LOAD='(-0.01,0.01)';
      OUTPUT_LOAD='(1.0,-1.0)';
      PINUSE='BI';
    'MGA_DATA6':
      PIN_NUMBER='(0,0,0,0,0,0,K2,0,0,0,0,0,0,0,0,0,0,0,0,0,0,0,0,0,0,0,0,0,0,0,~
0,0,0,0,0,0,0,0,0,0)';
      BIDIRECTIONAL='TRUE';
      INPUT_LOAD='(-0.01,0.01)';
      OUTPUT_LOAD='(1.0,-1.0)';
      PINUSE='BI';
    'MGA_CHECK7':
      PIN_NUMBER='(0,0,0,0,0,0,AR3,0,0,0,0,0,0,0,0,0,0,0,0,0,0,0,0,0,0,0,0,0,0,0~
,0,0,0,0,0,0,0,0,0,0)';
      BIDIRECTIONAL='TRUE';
      INPUT_LOAD='(-0.01,0.01)';
      OUTPUT_LOAD='(1.0,-1.0)';
      PINUSE='BI';
    'MGA_CA2':
      PIN_NUMBER='(0,0,0,0,0,0,AY4,0,0,0,0,0,0,0,0,0,0,0,0,0,0,0,0,0,0,0,0,0,0,0~
,0,0,0,0,0,0,0,0,0,0)';
      OUTPUT_LOAD='(1.0,-1.0)';
      PINUSE='OUT';
    'MGA1_RSP_L':
      PIN_NUMBER='(0,0,0,0,0,0,BP4,0,0,0,0,0,0,0,0,0,0,0,0,0,0,0,0,0,0,0,0,0,0,0~
,0,0,0,0,0,0,0,0,0,0)';
      INPUT_LOAD='(-0.01,0.01)';
      PINUSE='IN';
    'MGA0_RSP_L':
      PIN_NUMBER='(0,0,0,0,0,0,BN3,0,0,0,0,0,0,0,0,0,0,0,0,0,0,0,0,0,0,0,0,0,0,0~
,0,0,0,0,0,0,0,0,0,0)';
      INPUT_LOAD='(-0.01,0.01)';
      PINUSE='IN';
    'MGB_DATA22':
      PIN_NUMBER='(0,0,0,0,0,0,CW2,0,0,0,0,0,0,0,0,0,0,0,0,0,0,0,0,0,0,0,0,0,0,0~
,0,0,0,0,0,0,0,0,0,0)';
      BIDIRECTIONAL='TRUE';
      INPUT_LOAD='(-0.01,0.01)';
      OUTPUT_LOAD='(1.0,-1.0)';
      PINUSE='BI';
    'MGB_DATA11':
      PIN_NUMBER='(0,0,0,0,0,0,CK4,0,0,0,0,0,0,0,0,0,0,0,0,0,0,0,0,0,0,0,0,0,0,0~
,0,0,0,0,0,0,0,0,0,0)';
      BIDIRECTIONAL='TRUE';
      INPUT_LOAD='(-0.01,0.01)';
      OUTPUT_LOAD='(1.0,-1.0)';
      PINUSE='BI';
    'MGB_DATA7':
      PIN_NUMBER='(0,0,0,0,0,0,CH4,0,0,0,0,0,0,0,0,0,0,0,0,0,0,0,0,0,0,0,0,0,0,0~
,0,0,0,0,0,0,0,0,0,0)';
      BIDIRECTIONAL='TRUE';
      INPUT_LOAD='(-0.01,0.01)';
      OUTPUT_LOAD='(1.0,-1.0)';
      PINUSE='BI';
    'MGB_CHECK2':
      PIN_NUMBER='(0,0,0,0,0,0,CA2,0,0,0,0,0,0,0,0,0,0,0,0,0,0,0,0,0,0,0,0,0,0,0~
,0,0,0,0,0,0,0,0,0,0)';
      BIDIRECTIONAL='TRUE';
      INPUT_LOAD='(-0.01,0.01)';
      OUTPUT_LOAD='(1.0,-1.0)';
      PINUSE='BI';
    'MGB_CA2':
      PIN_NUMBER='(0,0,0,0,0,0,BH2,0,0,0,0,0,0,0,0,0,0,0,0,0,0,0,0,0,0,0,0,0,0,0~
,0,0,0,0,0,0,0,0,0,0)';
      OUTPUT_LOAD='(1.0,-1.0)';
      PINUSE='OUT';
    'MGA_DQS_L4':
      PIN_NUMBER='(0,0,0,0,0,0,AM2,0,0,0,0,0,0,0,0,0,0,0,0,0,0,0,0,0,0,0,0,0,0,0~
,0,0,0,0,0,0,0,0,0,0)';
      BIDIRECTIONAL='TRUE';
      INPUT_LOAD='(-0.01,0.01)';
      OUTPUT_LOAD='(1.0,-1.0)';
      PINUSE='BI';
    'MGA_DQS_H0':
      PIN_NUMBER='(0,0,0,0,0,0,G2,0,0,0,0,0,0,0,0,0,0,0,0,0,0,0,0,0,0,0,0,0,0,0,~
0,0,0,0,0,0,0,0,0,0)';
      BIDIRECTIONAL='TRUE';
      INPUT_LOAD='(-0.01,0.01)';
      OUTPUT_LOAD='(1.0,-1.0)';
      PINUSE='BI';
    'MGA_DATA28':
      PIN_NUMBER='(0,0,0,0,0,0,AG2,0,0,0,0,0,0,0,0,0,0,0,0,0,0,0,0,0,0,0,0,0,0,0~
,0,0,0,0,0,0,0,0,0,0)';
      BIDIRECTIONAL='TRUE';
      INPUT_LOAD='(-0.01,0.01)';
      OUTPUT_LOAD='(1.0,-1.0)';
      PINUSE='BI';
    'MGA_DATA17':
      PIN_NUMBER='(0,0,0,0,0,0,V4,0,0,0,0,0,0,0,0,0,0,0,0,0,0,0,0,0,0,0,0,0,0,0,~
0,0,0,0,0,0,0,0,0,0)';
      BIDIRECTIONAL='TRUE';
      INPUT_LOAD='(-0.01,0.01)';
      OUTPUT_LOAD='(1.0,-1.0)';
      PINUSE='BI';
    'MGA_DATA7':
      PIN_NUMBER='(0,0,0,0,0,0,L3,0,0,0,0,0,0,0,0,0,0,0,0,0,0,0,0,0,0,0,0,0,0,0,~
0,0,0,0,0,0,0,0,0,0)';
      BIDIRECTIONAL='TRUE';
      INPUT_LOAD='(-0.01,0.01)';
      OUTPUT_LOAD='(1.0,-1.0)';
      PINUSE='BI';
    'MGA_CA3':
      PIN_NUMBER='(0,0,0,0,0,0,BA3,0,0,0,0,0,0,0,0,0,0,0,0,0,0,0,0,0,0,0,0,0,0,0~
,0,0,0,0,0,0,0,0,0,0)';
      OUTPUT_LOAD='(1.0,-1.0)';
      PINUSE='OUT';
    'MGB_DATA23':
      PIN_NUMBER='(0,0,0,0,0,0,CY4,0,0,0,0,0,0,0,0,0,0,0,0,0,0,0,0,0,0,0,0,0,0,0~
,0,0,0,0,0,0,0,0,0,0)';
      BIDIRECTIONAL='TRUE';
      INPUT_LOAD='(-0.01,0.01)';
      OUTPUT_LOAD='(1.0,-1.0)';
      PINUSE='BI';
    'MGB_DATA12':
      PIN_NUMBER='(0,0,0,0,0,0,CM2,0,0,0,0,0,0,0,0,0,0,0,0,0,0,0,0,0,0,0,0,0,0,0~
,0,0,0,0,0,0,0,0,0,0)';
      BIDIRECTIONAL='TRUE';
      INPUT_LOAD='(-0.01,0.01)';
      OUTPUT_LOAD='(1.0,-1.0)';
      PINUSE='BI';
    'MGB_DATA8':
      PIN_NUMBER='(0,0,0,0,0,0,CH2,0,0,0,0,0,0,0,0,0,0,0,0,0,0,0,0,0,0,0,0,0,0,0~
,0,0,0,0,0,0,0,0,0,0)';
      BIDIRECTIONAL='TRUE';
      INPUT_LOAD='(-0.01,0.01)';
      OUTPUT_LOAD='(1.0,-1.0)';
      PINUSE='BI';
    'MGB_CHECK3':
      PIN_NUMBER='(0,0,0,0,0,0,CB4,0,0,0,0,0,0,0,0,0,0,0,0,0,0,0,0,0,0,0,0,0,0,0~
,0,0,0,0,0,0,0,0,0,0)';
      BIDIRECTIONAL='TRUE';
      INPUT_LOAD='(-0.01,0.01)';
      OUTPUT_LOAD='(1.0,-1.0)';
      PINUSE='BI';
    'MGB_CA3':
      PIN_NUMBER='(0,0,0,0,0,0,BJ2,0,0,0,0,0,0,0,0,0,0,0,0,0,0,0,0,0,0,0,0,0,0,0~
,0,0,0,0,0,0,0,0,0,0)';
      OUTPUT_LOAD='(1.0,-1.0)';
      PINUSE='OUT';
    'MGA_DQS_L5':
      PIN_NUMBER='(0,0,0,0,0,0,H4,0,0,0,0,0,0,0,0,0,0,0,0,0,0,0,0,0,0,0,0,0,0,0,~
0,0,0,0,0,0,0,0,0,0)';
      BIDIRECTIONAL='TRUE';
      INPUT_LOAD='(-0.01,0.01)';
      OUTPUT_LOAD='(1.0,-1.0)';
      PINUSE='BI';
    'MGA_DQS_H1':
      PIN_NUMBER='(0,0,0,0,0,0,N2,0,0,0,0,0,0,0,0,0,0,0,0,0,0,0,0,0,0,0,0,0,0,0,~
0,0,0,0,0,0,0,0,0,0)';
      BIDIRECTIONAL='TRUE';
      INPUT_LOAD='(-0.01,0.01)';
      OUTPUT_LOAD='(1.0,-1.0)';
      PINUSE='BI';
    'MGA_DATA29':
      PIN_NUMBER='(0,0,0,0,0,0,AH4,0,0,0,0,0,0,0,0,0,0,0,0,0,0,0,0,0,0,0,0,0,0,0~
,0,0,0,0,0,0,0,0,0,0)';
      BIDIRECTIONAL='TRUE';
      INPUT_LOAD='(-0.01,0.01)';
      OUTPUT_LOAD='(1.0,-1.0)';
      PINUSE='BI';
    'MGA_DATA18':
      PIN_NUMBER='(0,0,0,0,0,0,V2,0,0,0,0,0,0,0,0,0,0,0,0,0,0,0,0,0,0,0,0,0,0,0,~
0,0,0,0,0,0,0,0,0,0)';
      BIDIRECTIONAL='TRUE';
      INPUT_LOAD='(-0.01,0.01)';
      OUTPUT_LOAD='(1.0,-1.0)';
      PINUSE='BI';
    'MGA_DATA8':
      PIN_NUMBER='(0,0,0,0,0,0,L2,0,0,0,0,0,0,0,0,0,0,0,0,0,0,0,0,0,0,0,0,0,0,0,~
0,0,0,0,0,0,0,0,0,0)';
      BIDIRECTIONAL='TRUE';
      INPUT_LOAD='(-0.01,0.01)';
      OUTPUT_LOAD='(1.0,-1.0)';
      PINUSE='BI';
    'MGA_CA4':
      PIN_NUMBER='(0,0,0,0,0,0,BA2,0,0,0,0,0,0,0,0,0,0,0,0,0,0,0,0,0,0,0,0,0,0,0~
,0,0,0,0,0,0,0,0,0,0)';
      OUTPUT_LOAD='(1.0,-1.0)';
      PINUSE='OUT';
    'MGB_DQS_L0':
      PIN_NUMBER='(0,0,0,0,0,0,CE2,0,0,0,0,0,0,0,0,0,0,0,0,0,0,0,0,0,0,0,0,0,0,0~
,0,0,0,0,0,0,0,0,0,0)';
      BIDIRECTIONAL='TRUE';
      INPUT_LOAD='(-0.01,0.01)';
      OUTPUT_LOAD='(1.0,-1.0)';
      PINUSE='BI';
    'MGB_DATA24':
      PIN_NUMBER='(0,0,0,0,0,0,CY2,0,0,0,0,0,0,0,0,0,0,0,0,0,0,0,0,0,0,0,0,0,0,0~
,0,0,0,0,0,0,0,0,0,0)';
      BIDIRECTIONAL='TRUE';
      INPUT_LOAD='(-0.01,0.01)';
      OUTPUT_LOAD='(1.0,-1.0)';
      PINUSE='BI';
    'MGB_DATA13':
      PIN_NUMBER='(0,0,0,0,0,0,CN3,0,0,0,0,0,0,0,0,0,0,0,0,0,0,0,0,0,0,0,0,0,0,0~
,0,0,0,0,0,0,0,0,0,0)';
      BIDIRECTIONAL='TRUE';
      INPUT_LOAD='(-0.01,0.01)';
      OUTPUT_LOAD='(1.0,-1.0)';
      PINUSE='BI';
    'MGB_DATA9':
      PIN_NUMBER='(0,0,0,0,0,0,CJ3,0,0,0,0,0,0,0,0,0,0,0,0,0,0,0,0,0,0,0,0,0,0,0~
,0,0,0,0,0,0,0,0,0,0)';
      BIDIRECTIONAL='TRUE';
      INPUT_LOAD='(-0.01,0.01)';
      OUTPUT_LOAD='(1.0,-1.0)';
      PINUSE='BI';
    'MGB_CHECK4':
      PIN_NUMBER='(0,0,0,0,0,0,BT2,0,0,0,0,0,0,0,0,0,0,0,0,0,0,0,0,0,0,0,0,0,0,0~
,0,0,0,0,0,0,0,0,0,0)';
      BIDIRECTIONAL='TRUE';
      INPUT_LOAD='(-0.01,0.01)';
      OUTPUT_LOAD='(1.0,-1.0)';
      PINUSE='BI';
    'MGB_CA4':
      PIN_NUMBER='(0,0,0,0,0,0,BJ3,0,0,0,0,0,0,0,0,0,0,0,0,0,0,0,0,0,0,0,0,0,0,0~
,0,0,0,0,0,0,0,0,0,0)';
      OUTPUT_LOAD='(1.0,-1.0)';
      PINUSE='OUT';
    'MGA_DQS_L6':
      PIN_NUMBER='(0,0,0,0,0,0,P4,0,0,0,0,0,0,0,0,0,0,0,0,0,0,0,0,0,0,0,0,0,0,0,~
0,0,0,0,0,0,0,0,0,0)';
      BIDIRECTIONAL='TRUE';
      INPUT_LOAD='(-0.01,0.01)';
      OUTPUT_LOAD='(1.0,-1.0)';
      PINUSE='BI';
    'MGA_DQS_H2':
      PIN_NUMBER='(0,0,0,0,0,0,W2,0,0,0,0,0,0,0,0,0,0,0,0,0,0,0,0,0,0,0,0,0,0,0,~
0,0,0,0,0,0,0,0,0,0)';
      BIDIRECTIONAL='TRUE';
      INPUT_LOAD='(-0.01,0.01)';
      OUTPUT_LOAD='(1.0,-1.0)';
      PINUSE='BI';
    'MGA_DATA19':
      PIN_NUMBER='(0,0,0,0,0,0,W3,0,0,0,0,0,0,0,0,0,0,0,0,0,0,0,0,0,0,0,0,0,0,0,~
0,0,0,0,0,0,0,0,0,0)';
      BIDIRECTIONAL='TRUE';
      INPUT_LOAD='(-0.01,0.01)';
      OUTPUT_LOAD='(1.0,-1.0)';
      PINUSE='BI';
    'MGA_DATA9':
      PIN_NUMBER='(0,0,0,0,0,0,M4,0,0,0,0,0,0,0,0,0,0,0,0,0,0,0,0,0,0,0,0,0,0,0,~
0,0,0,0,0,0,0,0,0,0)';
      BIDIRECTIONAL='TRUE';
      INPUT_LOAD='(-0.01,0.01)';
      OUTPUT_LOAD='(1.0,-1.0)';
      PINUSE='BI';
    'MGA_CA5':
      PIN_NUMBER='(0,0,0,0,0,0,BB2,0,0,0,0,0,0,0,0,0,0,0,0,0,0,0,0,0,0,0,0,0,0,0~
,0,0,0,0,0,0,0,0,0,0)';
      OUTPUT_LOAD='(1.0,-1.0)';
      PINUSE='OUT';
    'MGB_DQS_L1':
      PIN_NUMBER='(0,0,0,0,0,0,CL2,0,0,0,0,0,0,0,0,0,0,0,0,0,0,0,0,0,0,0,0,0,0,0~
,0,0,0,0,0,0,0,0,0,0)';
      BIDIRECTIONAL='TRUE';
      INPUT_LOAD='(-0.01,0.01)';
      OUTPUT_LOAD='(1.0,-1.0)';
      PINUSE='BI';
    'MGB_DATA25':
      PIN_NUMBER='(0,0,0,0,0,0,DA3,0,0,0,0,0,0,0,0,0,0,0,0,0,0,0,0,0,0,0,0,0,0,0~
,0,0,0,0,0,0,0,0,0,0)';
      BIDIRECTIONAL='TRUE';
      INPUT_LOAD='(-0.01,0.01)';
      OUTPUT_LOAD='(1.0,-1.0)';
      PINUSE='BI';
    'MGB_DATA14':
      PIN_NUMBER='(0,0,0,0,0,0,CN2,0,0,0,0,0,0,0,0,0,0,0,0,0,0,0,0,0,0,0,0,0,0,0~
,0,0,0,0,0,0,0,0,0,0)';
      BIDIRECTIONAL='TRUE';
      INPUT_LOAD='(-0.01,0.01)';
      OUTPUT_LOAD='(1.0,-1.0)';
      PINUSE='BI';
    'MGB_CHECK5':
      PIN_NUMBER='(0,0,0,0,0,0,BU3,0,0,0,0,0,0,0,0,0,0,0,0,0,0,0,0,0,0,0,0,0,0,0~
,0,0,0,0,0,0,0,0,0,0)';
      BIDIRECTIONAL='TRUE';
      INPUT_LOAD='(-0.01,0.01)';
      OUTPUT_LOAD='(1.0,-1.0)';
      PINUSE='BI';
    'MGB_CA5':
      PIN_NUMBER='(0,0,0,0,0,0,BK4,0,0,0,0,0,0,0,0,0,0,0,0,0,0,0,0,0,0,0,0,0,0,0~
,0,0,0,0,0,0,0,0,0,0)';
      OUTPUT_LOAD='(1.0,-1.0)';
      PINUSE='OUT';
    'MGA_DQS_L7':
      PIN_NUMBER='(0,0,0,0,0,0,Y4,0,0,0,0,0,0,0,0,0,0,0,0,0,0,0,0,0,0,0,0,0,0,0,~
0,0,0,0,0,0,0,0,0,0)';
      BIDIRECTIONAL='TRUE';
      INPUT_LOAD='(-0.01,0.01)';
      OUTPUT_LOAD='(1.0,-1.0)';
      PINUSE='BI';
    'MGA_DQS_H3':
      PIN_NUMBER='(0,0,0,0,0,0,AE2,0,0,0,0,0,0,0,0,0,0,0,0,0,0,0,0,0,0,0,0,0,0,0~
,0,0,0,0,0,0,0,0,0,0)';
      BIDIRECTIONAL='TRUE';
      INPUT_LOAD='(-0.01,0.01)';
      OUTPUT_LOAD='(1.0,-1.0)';
      PINUSE='BI';
    'MGA_CA6':
      PIN_NUMBER='(0,0,0,0,0,0,BB4,0,0,0,0,0,0,0,0,0,0,0,0,0,0,0,0,0,0,0,0,0,0,0~
,0,0,0,0,0,0,0,0,0,0)';
      OUTPUT_LOAD='(1.0,-1.0)';
      PINUSE='OUT';
    'MGB_DQS_L2':
      PIN_NUMBER='(0,0,0,0,0,0,CU2,0,0,0,0,0,0,0,0,0,0,0,0,0,0,0,0,0,0,0,0,0,0,0~
,0,0,0,0,0,0,0,0,0,0)';
      BIDIRECTIONAL='TRUE';
      INPUT_LOAD='(-0.01,0.01)';
      OUTPUT_LOAD='(1.0,-1.0)';
      PINUSE='BI';
    'MGB_DATA26':
      PIN_NUMBER='(0,0,0,0,0,0,DA2,0,0,0,0,0,0,0,0,0,0,0,0,0,0,0,0,0,0,0,0,0,0,0~
,0,0,0,0,0,0,0,0,0,0)';
      BIDIRECTIONAL='TRUE';
      INPUT_LOAD='(-0.01,0.01)';
      OUTPUT_LOAD='(1.0,-1.0)';
      PINUSE='BI';
    'MGB_DATA15':
      PIN_NUMBER='(0,0,0,0,0,0,CP4,0,0,0,0,0,0,0,0,0,0,0,0,0,0,0,0,0,0,0,0,0,0,0~
,0,0,0,0,0,0,0,0,0,0)';
      BIDIRECTIONAL='TRUE';
      INPUT_LOAD='(-0.01,0.01)';
      OUTPUT_LOAD='(1.0,-1.0)';
      PINUSE='BI';
    'MGB_CHECK6':
      PIN_NUMBER='(0,0,0,0,0,0,BU2,0,0,0,0,0,0,0,0,0,0,0,0,0,0,0,0,0,0,0,0,0,0,0~
,0,0,0,0,0,0,0,0,0,0)';
      BIDIRECTIONAL='TRUE';
      INPUT_LOAD='(-0.01,0.01)';
      OUTPUT_LOAD='(1.0,-1.0)';
      PINUSE='BI';
    'MGB_CA6':
      PIN_NUMBER='(0,0,0,0,0,0,BK2,0,0,0,0,0,0,0,0,0,0,0,0,0,0,0,0,0,0,0,0,0,0,0~
,0,0,0,0,0,0,0,0,0,0)';
      OUTPUT_LOAD='(1.0,-1.0)';
      PINUSE='OUT';
    'MGA_DQS_L8':
      PIN_NUMBER='(0,0,0,0,0,0,AF4,0,0,0,0,0,0,0,0,0,0,0,0,0,0,0,0,0,0,0,0,0,0,0~
,0,0,0,0,0,0,0,0,0,0)';
      BIDIRECTIONAL='TRUE';
      INPUT_LOAD='(-0.01,0.01)';
      OUTPUT_LOAD='(1.0,-1.0)';
      PINUSE='BI';
    'MGA_DQS_H4':
      PIN_NUMBER='(0,0,0,0,0,0,AL2,0,0,0,0,0,0,0,0,0,0,0,0,0,0,0,0,0,0,0,0,0,0,0~
,0,0,0,0,0,0,0,0,0,0)';
      BIDIRECTIONAL='TRUE';
      INPUT_LOAD='(-0.01,0.01)';
      OUTPUT_LOAD='(1.0,-1.0)';
      PINUSE='BI';
    'MGB_DQS_L3':
      PIN_NUMBER='(0,0,0,0,0,0,DC2,0,0,0,0,0,0,0,0,0,0,0,0,0,0,0,0,0,0,0,0,0,0,0~
,0,0,0,0,0,0,0,0,0,0)';
      BIDIRECTIONAL='TRUE';
      INPUT_LOAD='(-0.01,0.01)';
      OUTPUT_LOAD='(1.0,-1.0)';
      PINUSE='BI';
    'MGB_DATA27':
      PIN_NUMBER='(0,0,0,0,0,0,DB4,0,0,0,0,0,0,0,0,0,0,0,0,0,0,0,0,0,0,0,0,0,0,0~
,0,0,0,0,0,0,0,0,0,0)';
      BIDIRECTIONAL='TRUE';
      INPUT_LOAD='(-0.01,0.01)';
      OUTPUT_LOAD='(1.0,-1.0)';
      PINUSE='BI';
    'MGB_DATA16':
      PIN_NUMBER='(0,0,0,0,0,0,CP2,0,0,0,0,0,0,0,0,0,0,0,0,0,0,0,0,0,0,0,0,0,0,0~
,0,0,0,0,0,0,0,0,0,0)';
      BIDIRECTIONAL='TRUE';
      INPUT_LOAD='(-0.01,0.01)';
      OUTPUT_LOAD='(1.0,-1.0)';
      PINUSE='BI';
    'MGB_CHECK7':
      PIN_NUMBER='(0,0,0,0,0,0,BV4,0,0,0,0,0,0,0,0,0,0,0,0,0,0,0,0,0,0,0,0,0,0,0~
,0,0,0,0,0,0,0,0,0,0)';
      BIDIRECTIONAL='TRUE';
      INPUT_LOAD='(-0.01,0.01)';
      OUTPUT_LOAD='(1.0,-1.0)';
      PINUSE='BI';
    'MGB1_RSP_L':
      PIN_NUMBER='(0,0,0,0,0,0,BR2,0,0,0,0,0,0,0,0,0,0,0,0,0,0,0,0,0,0,0,0,0,0,0~
,0,0,0,0,0,0,0,0,0,0)';
      INPUT_LOAD='(-0.01,0.01)';
      PINUSE='IN';
    'MGB0_RSP_L':
      PIN_NUMBER='(0,0,0,0,0,0,BP2,0,0,0,0,0,0,0,0,0,0,0,0,0,0,0,0,0,0,0,0,0,0,0~
,0,0,0,0,0,0,0,0,0,0)';
      INPUT_LOAD='(-0.01,0.01)';
      PINUSE='IN';
    'MGA_DQS_L9':
      PIN_NUMBER='(0,0,0,0,0,0,AM4,0,0,0,0,0,0,0,0,0,0,0,0,0,0,0,0,0,0,0,0,0,0,0~
,0,0,0,0,0,0,0,0,0,0)';
      BIDIRECTIONAL='TRUE';
      INPUT_LOAD='(-0.01,0.01)';
      OUTPUT_LOAD='(1.0,-1.0)';
      PINUSE='BI';
    'MGA_DQS_H5':
      PIN_NUMBER='(0,0,0,0,0,0,J3,0,0,0,0,0,0,0,0,0,0,0,0,0,0,0,0,0,0,0,0,0,0,0,~
0,0,0,0,0,0,0,0,0,0)';
      BIDIRECTIONAL='TRUE';
      INPUT_LOAD='(-0.01,0.01)';
      OUTPUT_LOAD='(1.0,-1.0)';
      PINUSE='BI';
    'MGB_DQS_L4':
      PIN_NUMBER='(0,0,0,0,0,0,BW3,0,0,0,0,0,0,0,0,0,0,0,0,0,0,0,0,0,0,0,0,0,0,0~
,0,0,0,0,0,0,0,0,0,0)';
      BIDIRECTIONAL='TRUE';
      INPUT_LOAD='(-0.01,0.01)';
      OUTPUT_LOAD='(1.0,-1.0)';
      PINUSE='BI';
    'MGB_DQS_H0':
      PIN_NUMBER='(0,0,0,0,0,0,CD2,0,0,0,0,0,0,0,0,0,0,0,0,0,0,0,0,0,0,0,0,0,0,0~
,0,0,0,0,0,0,0,0,0,0)';
      BIDIRECTIONAL='TRUE';
      INPUT_LOAD='(-0.01,0.01)';
      OUTPUT_LOAD='(1.0,-1.0)';
      PINUSE='BI';
    'MGB_DATA28':
      PIN_NUMBER='(0,0,0,0,0,0,DD2,0,0,0,0,0,0,0,0,0,0,0,0,0,0,0,0,0,0,0,0,0,0,0~
,0,0,0,0,0,0,0,0,0,0)';
      BIDIRECTIONAL='TRUE';
      INPUT_LOAD='(-0.01,0.01)';
      OUTPUT_LOAD='(1.0,-1.0)';
      PINUSE='BI';
    'MGB_DATA17':
      PIN_NUMBER='(0,0,0,0,0,0,CR3,0,0,0,0,0,0,0,0,0,0,0,0,0,0,0,0,0,0,0,0,0,0,0~
,0,0,0,0,0,0,0,0,0,0)';
      BIDIRECTIONAL='TRUE';
      INPUT_LOAD='(-0.01,0.01)';
      OUTPUT_LOAD='(1.0,-1.0)';
      PINUSE='BI';
    'MGA_DQS_H6':
      PIN_NUMBER='(0,0,0,0,0,0,R3,0,0,0,0,0,0,0,0,0,0,0,0,0,0,0,0,0,0,0,0,0,0,0,~
0,0,0,0,0,0,0,0,0,0)';
      BIDIRECTIONAL='TRUE';
      INPUT_LOAD='(-0.01,0.01)';
      OUTPUT_LOAD='(1.0,-1.0)';
      PINUSE='BI';
    'MGB_DQS_L5':
      PIN_NUMBER='(0,0,0,0,0,0,CE3,0,0,0,0,0,0,0,0,0,0,0,0,0,0,0,0,0,0,0,0,0,0,0~
,0,0,0,0,0,0,0,0,0,0)';
      BIDIRECTIONAL='TRUE';
      INPUT_LOAD='(-0.01,0.01)';
      OUTPUT_LOAD='(1.0,-1.0)';
      PINUSE='BI';
    'MGB_DQS_H1':
      PIN_NUMBER='(0,0,0,0,0,0,CK2,0,0,0,0,0,0,0,0,0,0,0,0,0,0,0,0,0,0,0,0,0,0,0~
,0,0,0,0,0,0,0,0,0,0)';
      BIDIRECTIONAL='TRUE';
      INPUT_LOAD='(-0.01,0.01)';
      OUTPUT_LOAD='(1.0,-1.0)';
      PINUSE='BI';
    'MGB_DATA29':
      PIN_NUMBER='(0,0,0,0,0,0,DE3,0,0,0,0,0,0,0,0,0,0,0,0,0,0,0,0,0,0,0,0,0,0,0~
,0,0,0,0,0,0,0,0,0,0)';
      BIDIRECTIONAL='TRUE';
      INPUT_LOAD='(-0.01,0.01)';
      OUTPUT_LOAD='(1.0,-1.0)';
      PINUSE='BI';
    'MGB_DATA18':
      PIN_NUMBER='(0,0,0,0,0,0,CR2,0,0,0,0,0,0,0,0,0,0,0,0,0,0,0,0,0,0,0,0,0,0,0~
,0,0,0,0,0,0,0,0,0,0)';
      BIDIRECTIONAL='TRUE';
      INPUT_LOAD='(-0.01,0.01)';
      OUTPUT_LOAD='(1.0,-1.0)';
      PINUSE='BI';
    'MGA_DQS_H7':
      PIN_NUMBER='(0,0,0,0,0,0,AA3,0,0,0,0,0,0,0,0,0,0,0,0,0,0,0,0,0,0,0,0,0,0,0~
,0,0,0,0,0,0,0,0,0,0)';
      BIDIRECTIONAL='TRUE';
      INPUT_LOAD='(-0.01,0.01)';
      OUTPUT_LOAD='(1.0,-1.0)';
      PINUSE='BI';
    'MGA1_CS_L0':
      PIN_NUMBER='(0,0,0,0,0,0,AV2,0,0,0,0,0,0,0,0,0,0,0,0,0,0,0,0,0,0,0,0,0,0,0~
,0,0,0,0,0,0,0,0,0,0)';
      OUTPUT_LOAD='(1.0,-1.0)';
      PINUSE='OUT';
    'MGA0_CS_L0':
      PIN_NUMBER='(0,0,0,0,0,0,AU2,0,0,0,0,0,0,0,0,0,0,0,0,0,0,0,0,0,0,0,0,0,0,0~
,0,0,0,0,0,0,0,0,0,0)';
      OUTPUT_LOAD='(1.0,-1.0)';
      PINUSE='OUT';
    'MGB_DQS_L6':
      PIN_NUMBER='(0,0,0,0,0,0,CL3,0,0,0,0,0,0,0,0,0,0,0,0,0,0,0,0,0,0,0,0,0,0,0~
,0,0,0,0,0,0,0,0,0,0)';
      BIDIRECTIONAL='TRUE';
      INPUT_LOAD='(-0.01,0.01)';
      OUTPUT_LOAD='(1.0,-1.0)';
      PINUSE='BI';
    'MGB_DQS_H2':
      PIN_NUMBER='(0,0,0,0,0,0,CT2,0,0,0,0,0,0,0,0,0,0,0,0,0,0,0,0,0,0,0,0,0,0,0~
,0,0,0,0,0,0,0,0,0,0)';
      BIDIRECTIONAL='TRUE';
      INPUT_LOAD='(-0.01,0.01)';
      OUTPUT_LOAD='(1.0,-1.0)';
      PINUSE='BI';
    'MGB_DATA19':
      PIN_NUMBER='(0,0,0,0,0,0,CT4,0,0,0,0,0,0,0,0,0,0,0,0,0,0,0,0,0,0,0,0,0,0,0~
,0,0,0,0,0,0,0,0,0,0)';
      BIDIRECTIONAL='TRUE';
      INPUT_LOAD='(-0.01,0.01)';
      OUTPUT_LOAD='(1.0,-1.0)';
      PINUSE='BI';
    'MGA_DQS_H8':
      PIN_NUMBER='(0,0,0,0,0,0,AG3,0,0,0,0,0,0,0,0,0,0,0,0,0,0,0,0,0,0,0,0,0,0,0~
,0,0,0,0,0,0,0,0,0,0)';
      BIDIRECTIONAL='TRUE';
      INPUT_LOAD='(-0.01,0.01)';
      OUTPUT_LOAD='(1.0,-1.0)';
      PINUSE='BI';
    'MGA_DATA30':
      PIN_NUMBER='(0,0,0,0,0,0,AH2,0,0,0,0,0,0,0,0,0,0,0,0,0,0,0,0,0,0,0,0,0,0,0~
,0,0,0,0,0,0,0,0,0,0)';
      BIDIRECTIONAL='TRUE';
      INPUT_LOAD='(-0.01,0.01)';
      OUTPUT_LOAD='(1.0,-1.0)';
      PINUSE='BI';
    'MGA1_CS_L1':
      PIN_NUMBER='(0,0,0,0,0,0,AW3,0,0,0,0,0,0,0,0,0,0,0,0,0,0,0,0,0,0,0,0,0,0,0~
,0,0,0,0,0,0,0,0,0,0)';
      OUTPUT_LOAD='(1.0,-1.0)';
      PINUSE='OUT';
    'MGA0_CS_L1':
      PIN_NUMBER='(0,0,0,0,0,0,AV4,0,0,0,0,0,0,0,0,0,0,0,0,0,0,0,0,0,0,0,0,0,0,0~
,0,0,0,0,0,0,0,0,0,0)';
      OUTPUT_LOAD='(1.0,-1.0)';
      PINUSE='OUT';
    'MGB_DQS_L7':
      PIN_NUMBER='(0,0,0,0,0,0,CU3,0,0,0,0,0,0,0,0,0,0,0,0,0,0,0,0,0,0,0,0,0,0,0~
,0,0,0,0,0,0,0,0,0,0)';
      BIDIRECTIONAL='TRUE';
      INPUT_LOAD='(-0.01,0.01)';
      OUTPUT_LOAD='(1.0,-1.0)';
      PINUSE='BI';
    'MGB_DQS_H3':
      PIN_NUMBER='(0,0,0,0,0,0,DB2,0,0,0,0,0,0,0,0,0,0,0,0,0,0,0,0,0,0,0,0,0,0,0~
,0,0,0,0,0,0,0,0,0,0)';
      BIDIRECTIONAL='TRUE';
      INPUT_LOAD='(-0.01,0.01)';
      OUTPUT_LOAD='(1.0,-1.0)';
      PINUSE='BI';
    'MGA_DQS_H9':
      PIN_NUMBER='(0,0,0,0,0,0,AN3,0,0,0,0,0,0,0,0,0,0,0,0,0,0,0,0,0,0,0,0,0,0,0~
,0,0,0,0,0,0,0,0,0,0)';
      BIDIRECTIONAL='TRUE';
      INPUT_LOAD='(-0.01,0.01)';
      OUTPUT_LOAD='(1.0,-1.0)';
      PINUSE='BI';
    'MGA_DATA31':
      PIN_NUMBER='(0,0,0,0,0,0,AJ3,0,0,0,0,0,0,0,0,0,0,0,0,0,0,0,0,0,0,0,0,0,0,0~
,0,0,0,0,0,0,0,0,0,0)';
      BIDIRECTIONAL='TRUE';
      INPUT_LOAD='(-0.01,0.01)';
      OUTPUT_LOAD='(1.0,-1.0)';
      PINUSE='BI';
    'MGA_DATA20':
      PIN_NUMBER='(0,0,0,0,0,0,AA2,0,0,0,0,0,0,0,0,0,0,0,0,0,0,0,0,0,0,0,0,0,0,0~
,0,0,0,0,0,0,0,0,0,0)';
      BIDIRECTIONAL='TRUE';
      INPUT_LOAD='(-0.01,0.01)';
      OUTPUT_LOAD='(1.0,-1.0)';
      PINUSE='BI';
    'MGA_CHECK0':
      PIN_NUMBER='(0,0,0,0,0,0,AJ2,0,0,0,0,0,0,0,0,0,0,0,0,0,0,0,0,0,0,0,0,0,0,0~
,0,0,0,0,0,0,0,0,0,0)';
      BIDIRECTIONAL='TRUE';
      INPUT_LOAD='(-0.01,0.01)';
      OUTPUT_LOAD='(1.0,-1.0)';
      PINUSE='BI';
    'MGB_DQS_L8':
      PIN_NUMBER='(0,0,0,0,0,0,DC3,0,0,0,0,0,0,0,0,0,0,0,0,0,0,0,0,0,0,0,0,0,0,0~
,0,0,0,0,0,0,0,0,0,0)';
      BIDIRECTIONAL='TRUE';
      INPUT_LOAD='(-0.01,0.01)';
      OUTPUT_LOAD='(1.0,-1.0)';
      PINUSE='BI';
    'MGB_DQS_H4':
      PIN_NUMBER='(0,0,0,0,0,0,BY4,0,0,0,0,0,0,0,0,0,0,0,0,0,0,0,0,0,0,0,0,0,0,0~
,0,0,0,0,0,0,0,0,0,0)';
      BIDIRECTIONAL='TRUE';
      INPUT_LOAD='(-0.01,0.01)';
      OUTPUT_LOAD='(1.0,-1.0)';
      PINUSE='BI';
    'MGB_DATA0':
      PIN_NUMBER='(0,0,0,0,0,0,CB2,0,0,0,0,0,0,0,0,0,0,0,0,0,0,0,0,0,0,0,0,0,0,0~
,0,0,0,0,0,0,0,0,0,0)';
      BIDIRECTIONAL='TRUE';
      INPUT_LOAD='(-0.01,0.01)';
      OUTPUT_LOAD='(1.0,-1.0)';
      PINUSE='BI';
    'MGA_DATA21':
      PIN_NUMBER='(0,0,0,0,0,0,AB4,0,0,0,0,0,0,0,0,0,0,0,0,0,0,0,0,0,0,0,0,0,0,0~
,0,0,0,0,0,0,0,0,0,0)';
      BIDIRECTIONAL='TRUE';
      INPUT_LOAD='(-0.01,0.01)';
      OUTPUT_LOAD='(1.0,-1.0)';
      PINUSE='BI';
    'MGA_DATA10':
      PIN_NUMBER='(0,0,0,0,0,0,M2,0,0,0,0,0,0,0,0,0,0,0,0,0,0,0,0,0,0,0,0,0,0,0,~
0,0,0,0,0,0,0,0,0,0)';
      BIDIRECTIONAL='TRUE';
      INPUT_LOAD='(-0.01,0.01)';
      OUTPUT_LOAD='(1.0,-1.0)';
      PINUSE='BI';
    'MGA_DATA0':
      PIN_NUMBER='(0,0,0,0,0,0,E2,0,0,0,0,0,0,0,0,0,0,0,0,0,0,0,0,0,0,0,0,0,0,0,~
0,0,0,0,0,0,0,0,0,0)';
      BIDIRECTIONAL='TRUE';
      INPUT_LOAD='(-0.01,0.01)';
      OUTPUT_LOAD='(1.0,-1.0)';
      PINUSE='BI';
    'MGA_CHECK1':
      PIN_NUMBER='(0,0,0,0,0,0,AK4,0,0,0,0,0,0,0,0,0,0,0,0,0,0,0,0,0,0,0,0,0,0,0~
,0,0,0,0,0,0,0,0,0,0)';
      BIDIRECTIONAL='TRUE';
      INPUT_LOAD='(-0.01,0.01)';
      OUTPUT_LOAD='(1.0,-1.0)';
      PINUSE='BI';
    'MGB_PAR':
      PIN_NUMBER='(0,0,0,0,0,0,BL3,0,0,0,0,0,0,0,0,0,0,0,0,0,0,0,0,0,0,0,0,0,0,0~
,0,0,0,0,0,0,0,0,0,0)';
      OUTPUT_LOAD='(1.0,-1.0)';
      PINUSE='OUT';
    'MGB_DQS_H9':
      PIN_NUMBER='(0,0,0,0,0,0,BV2,0,0,0,0,0,0,0,0,0,0,0,0,0,0,0,0,0,0,0,0,0,0,0~
,0,0,0,0,0,0,0,0,0,0)';
      BIDIRECTIONAL='TRUE';
      INPUT_LOAD='(-0.01,0.01)';
      OUTPUT_LOAD='(1.0,-1.0)';
      PINUSE='BI';
    'MGA_PAR':
      PIN_NUMBER='(0,0,0,0,0,0,BC3,0,0,0,0,0,0,0,0,0,0,0,0,0,0,0,0,0,0,0,0,0,0,0~
,0,0,0,0,0,0,0,0,0,0)';
      OUTPUT_LOAD='(1.0,-1.0)';
      PINUSE='OUT';
    'MG0_CLK_H':
      PIN_NUMBER='(0,0,0,0,0,0,BC2,0,0,0,0,0,0,0,0,0,0,0,0,0,0,0,0,0,0,0,0,0,0,0~
,0,0,0,0,0,0,0,0,0,0)';
      OUTPUT_LOAD='(1.0,-1.0)';
      PINUSE='OUT';
    'MG0_CLK_L':
      PIN_NUMBER='(0,0,0,0,0,0,BD2,0,0,0,0,0,0,0,0,0,0,0,0,0,0,0,0,0,0,0,0,0,0,0~
,0,0,0,0,0,0,0,0,0,0)';
      OUTPUT_LOAD='(1.0,-1.0)';
      PINUSE='OUT';
    'MG1_CLK_H':
      PIN_NUMBER='(0,0,0,0,0,0,BF2,0,0,0,0,0,0,0,0,0,0,0,0,0,0,0,0,0,0,0,0,0,0,0~
,0,0,0,0,0,0,0,0,0,0)';
      OUTPUT_LOAD='(1.0,-1.0)';
      PINUSE='OUT';
    'MG1_CLK_L':
      PIN_NUMBER='(0,0,0,0,0,0,BG2,0,0,0,0,0,0,0,0,0,0,0,0,0,0,0,0,0,0,0,0,0,0,0~
,0,0,0,0,0,0,0,0,0,0)';
      OUTPUT_LOAD='(1.0,-1.0)';
      PINUSE='OUT';
    'TEST39G':
      PIN_NUMBER='(0,0,0,0,0,0,BF4,0,0,0,0,0,0,0,0,0,0,0,0,0,0,0,0,0,0,0,0,0,0,0~
,0,0,0,0,0,0,0,0,0,0)';
      OUTPUT_LOAD='(1.0,-1.0)';
      PINUSE='OUT';
    'MH_ALERT_L':
      PIN_NUMBER='(0,0,0,0,0,0,0,AT14,0,0,0,0,0,0,0,0,0,0,0,0,0,0,0,0,0,0,0,0,0,~
0,0,0,0,0,0,0,0,0,0,0)';
      INPUT_LOAD='(-0.01,0.01)';
      PINUSE='IN';
    'MH_RESET_L':
      PIN_NUMBER='(0,0,0,0,0,0,0,AU14,0,0,0,0,0,0,0,0,0,0,0,0,0,0,0,0,0,0,0,0,0,~
0,0,0,0,0,0,0,0,0,0,0)';
      OUTPUT_LOAD='(1.0,-1.0)';
      PINUSE='OUT';
    'MHB_DATA31':
      PIN_NUMBER='(0,0,0,0,0,0,0,DF14,0,0,0,0,0,0,0,0,0,0,0,0,0,0,0,0,0,0,0,0,0,~
0,0,0,0,0,0,0,0,0,0,0)';
      BIDIRECTIONAL='TRUE';
      INPUT_LOAD='(-0.01,0.01)';
      OUTPUT_LOAD='(1.0,-1.0)';
      PINUSE='BI';
    'MHB_DATA20':
      PIN_NUMBER='(0,0,0,0,0,0,0,CV13,0,0,0,0,0,0,0,0,0,0,0,0,0,0,0,0,0,0,0,0,0,~
0,0,0,0,0,0,0,0,0,0,0)';
      BIDIRECTIONAL='TRUE';
      INPUT_LOAD='(-0.01,0.01)';
      OUTPUT_LOAD='(1.0,-1.0)';
      PINUSE='BI';
    'MHB_CHECK0':
      PIN_NUMBER='(0,0,0,0,0,0,0,BY13,0,0,0,0,0,0,0,0,0,0,0,0,0,0,0,0,0,0,0,0,0,~
0,0,0,0,0,0,0,0,0,0,0)';
      BIDIRECTIONAL='TRUE';
      INPUT_LOAD='(-0.01,0.01)';
      OUTPUT_LOAD='(1.0,-1.0)';
      PINUSE='BI';
    'MHB1_CS_L1':
      PIN_NUMBER='(0,0,0,0,0,0,0,BM13,0,0,0,0,0,0,0,0,0,0,0,0,0,0,0,0,0,0,0,0,0,~
0,0,0,0,0,0,0,0,0,0,0)';
      OUTPUT_LOAD='(1.0,-1.0)';
      PINUSE='OUT';
    'MHA_DQS_L2':
      PIN_NUMBER='(0,0,0,0,0,0,0,Y13,0,0,0,0,0,0,0,0,0,0,0,0,0,0,0,0,0,0,0,0,0,0~
,0,0,0,0,0,0,0,0,0,0)';
      BIDIRECTIONAL='TRUE';
      INPUT_LOAD='(-0.01,0.01)';
      OUTPUT_LOAD='(1.0,-1.0)';
      PINUSE='BI';
    'MHA_DATA26':
      PIN_NUMBER='(0,0,0,0,0,0,0,AD13,0,0,0,0,0,0,0,0,0,0,0,0,0,0,0,0,0,0,0,0,0,~
0,0,0,0,0,0,0,0,0,0,0)';
      BIDIRECTIONAL='TRUE';
      INPUT_LOAD='(-0.01,0.01)';
      OUTPUT_LOAD='(1.0,-1.0)';
      PINUSE='BI';
    'MHA_DATA15':
      PIN_NUMBER='(0,0,0,0,0,0,0,U14,0,0,0,0,0,0,0,0,0,0,0,0,0,0,0,0,0,0,0,0,0,0~
,0,0,0,0,0,0,0,0,0,0)';
      BIDIRECTIONAL='TRUE';
      INPUT_LOAD='(-0.01,0.01)';
      OUTPUT_LOAD='(1.0,-1.0)';
      PINUSE='BI';
    'MHA_CHECK6':
      PIN_NUMBER='(0,0,0,0,0,0,0,AP13,0,0,0,0,0,0,0,0,0,0,0,0,0,0,0,0,0,0,0,0,0,~
0,0,0,0,0,0,0,0,0,0,0)';
      BIDIRECTIONAL='TRUE';
      INPUT_LOAD='(-0.01,0.01)';
      OUTPUT_LOAD='(1.0,-1.0)';
      PINUSE='BI';
    'MHB_DATA21':
      PIN_NUMBER='(0,0,0,0,0,0,0,CW14,0,0,0,0,0,0,0,0,0,0,0,0,0,0,0,0,0,0,0,0,0,~
0,0,0,0,0,0,0,0,0,0,0)';
      BIDIRECTIONAL='TRUE';
      INPUT_LOAD='(-0.01,0.01)';
      OUTPUT_LOAD='(1.0,-1.0)';
      PINUSE='BI';
    'MHB_DATA10':
      PIN_NUMBER='(0,0,0,0,0,0,0,CJ12,0,0,0,0,0,0,0,0,0,0,0,0,0,0,0,0,0,0,0,0,0,~
0,0,0,0,0,0,0,0,0,0,0)';
      BIDIRECTIONAL='TRUE';
      INPUT_LOAD='(-0.01,0.01)';
      OUTPUT_LOAD='(1.0,-1.0)';
      PINUSE='BI';
    'MHB_CHECK1':
      PIN_NUMBER='(0,0,0,0,0,0,0,CA14,0,0,0,0,0,0,0,0,0,0,0,0,0,0,0,0,0,0,0,0,0,~
0,0,0,0,0,0,0,0,0,0,0)';
      BIDIRECTIONAL='TRUE';
      INPUT_LOAD='(-0.01,0.01)';
      OUTPUT_LOAD='(1.0,-1.0)';
      PINUSE='BI';
    'MHA_DQS_L3':
      PIN_NUMBER='(0,0,0,0,0,0,0,AF13,0,0,0,0,0,0,0,0,0,0,0,0,0,0,0,0,0,0,0,0,0,~
0,0,0,0,0,0,0,0,0,0,0)';
      BIDIRECTIONAL='TRUE';
      INPUT_LOAD='(-0.01,0.01)';
      OUTPUT_LOAD='(1.0,-1.0)';
      PINUSE='BI';
    'MHA_DATA27':
      PIN_NUMBER='(0,0,0,0,0,0,0,AE14,0,0,0,0,0,0,0,0,0,0,0,0,0,0,0,0,0,0,0,0,0,~
0,0,0,0,0,0,0,0,0,0,0)';
      BIDIRECTIONAL='TRUE';
      INPUT_LOAD='(-0.01,0.01)';
      OUTPUT_LOAD='(1.0,-1.0)';
      PINUSE='BI';
    'MHA_DATA16':
      PIN_NUMBER='(0,0,0,0,0,0,0,U12,0,0,0,0,0,0,0,0,0,0,0,0,0,0,0,0,0,0,0,0,0,0~
,0,0,0,0,0,0,0,0,0,0)';
      BIDIRECTIONAL='TRUE';
      INPUT_LOAD='(-0.01,0.01)';
      OUTPUT_LOAD='(1.0,-1.0)';
      PINUSE='BI';
    'MHA_CHECK7':
      PIN_NUMBER='(0,0,0,0,0,0,0,AR14,0,0,0,0,0,0,0,0,0,0,0,0,0,0,0,0,0,0,0,0,0,~
0,0,0,0,0,0,0,0,0,0,0)';
      BIDIRECTIONAL='TRUE';
      INPUT_LOAD='(-0.01,0.01)';
      OUTPUT_LOAD='(1.0,-1.0)';
      PINUSE='BI';
    'MHA0_RSP_L':
      PIN_NUMBER='(0,0,0,0,0,0,0,BN14,0,0,0,0,0,0,0,0,0,0,0,0,0,0,0,0,0,0,0,0,0,~
0,0,0,0,0,0,0,0,0,0,0)';
      INPUT_LOAD='(-0.01,0.01)';
      PINUSE='IN';
    'MHB_DATA22':
      PIN_NUMBER='(0,0,0,0,0,0,0,CW12,0,0,0,0,0,0,0,0,0,0,0,0,0,0,0,0,0,0,0,0,0,~
0,0,0,0,0,0,0,0,0,0,0)';
      BIDIRECTIONAL='TRUE';
      INPUT_LOAD='(-0.01,0.01)';
      OUTPUT_LOAD='(1.0,-1.0)';
      PINUSE='BI';
    'MHB_DATA11':
      PIN_NUMBER='(0,0,0,0,0,0,0,CK14,0,0,0,0,0,0,0,0,0,0,0,0,0,0,0,0,0,0,0,0,0,~
0,0,0,0,0,0,0,0,0,0,0)';
      BIDIRECTIONAL='TRUE';
      INPUT_LOAD='(-0.01,0.01)';
      OUTPUT_LOAD='(1.0,-1.0)';
      PINUSE='BI';
    'MHB_CHECK2':
      PIN_NUMBER='(0,0,0,0,0,0,0,CA12,0,0,0,0,0,0,0,0,0,0,0,0,0,0,0,0,0,0,0,0,0,~
0,0,0,0,0,0,0,0,0,0,0)';
      BIDIRECTIONAL='TRUE';
      INPUT_LOAD='(-0.01,0.01)';
      OUTPUT_LOAD='(1.0,-1.0)';
      PINUSE='BI';
    'MHA_DQS_L4':
      PIN_NUMBER='(0,0,0,0,0,0,0,AM13,0,0,0,0,0,0,0,0,0,0,0,0,0,0,0,0,0,0,0,0,0,~
0,0,0,0,0,0,0,0,0,0,0)';
      BIDIRECTIONAL='TRUE';
      INPUT_LOAD='(-0.01,0.01)';
      OUTPUT_LOAD='(1.0,-1.0)';
      PINUSE='BI';
    'MHA_DQS_H0':
      PIN_NUMBER='(0,0,0,0,0,0,0,G12,0,0,0,0,0,0,0,0,0,0,0,0,0,0,0,0,0,0,0,0,0,0~
,0,0,0,0,0,0,0,0,0,0)';
      BIDIRECTIONAL='TRUE';
      INPUT_LOAD='(-0.01,0.01)';
      OUTPUT_LOAD='(1.0,-1.0)';
      PINUSE='BI';
    'MHA_DATA28':
      PIN_NUMBER='(0,0,0,0,0,0,0,AG12,0,0,0,0,0,0,0,0,0,0,0,0,0,0,0,0,0,0,0,0,0,~
0,0,0,0,0,0,0,0,0,0,0)';
      BIDIRECTIONAL='TRUE';
      INPUT_LOAD='(-0.01,0.01)';
      OUTPUT_LOAD='(1.0,-1.0)';
      PINUSE='BI';
    'MHA_DATA17':
      PIN_NUMBER='(0,0,0,0,0,0,0,V14,0,0,0,0,0,0,0,0,0,0,0,0,0,0,0,0,0,0,0,0,0,0~
,0,0,0,0,0,0,0,0,0,0)';
      BIDIRECTIONAL='TRUE';
      INPUT_LOAD='(-0.01,0.01)';
      OUTPUT_LOAD='(1.0,-1.0)';
      PINUSE='BI';
    'MHA_CA0':
      PIN_NUMBER='(0,0,0,0,0,0,0,AW12,0,0,0,0,0,0,0,0,0,0,0,0,0,0,0,0,0,0,0,0,0,~
0,0,0,0,0,0,0,0,0,0,0)';
      OUTPUT_LOAD='(1.0,-1.0)';
      PINUSE='OUT';
    'MHA1_RSP_L':
      PIN_NUMBER='(0,0,0,0,0,0,0,BP14,0,0,0,0,0,0,0,0,0,0,0,0,0,0,0,0,0,0,0,0,0,~
0,0,0,0,0,0,0,0,0,0,0)';
      INPUT_LOAD='(-0.01,0.01)';
      PINUSE='IN';
    'MHB_DATA23':
      PIN_NUMBER='(0,0,0,0,0,0,0,CY14,0,0,0,0,0,0,0,0,0,0,0,0,0,0,0,0,0,0,0,0,0,~
0,0,0,0,0,0,0,0,0,0,0)';
      BIDIRECTIONAL='TRUE';
      INPUT_LOAD='(-0.01,0.01)';
      OUTPUT_LOAD='(1.0,-1.0)';
      PINUSE='BI';
    'MHB_DATA12':
      PIN_NUMBER='(0,0,0,0,0,0,0,CM13,0,0,0,0,0,0,0,0,0,0,0,0,0,0,0,0,0,0,0,0,0,~
0,0,0,0,0,0,0,0,0,0,0)';
      BIDIRECTIONAL='TRUE';
      INPUT_LOAD='(-0.01,0.01)';
      OUTPUT_LOAD='(1.0,-1.0)';
      PINUSE='BI';
    'MHB_CHECK3':
      PIN_NUMBER='(0,0,0,0,0,0,0,CB14,0,0,0,0,0,0,0,0,0,0,0,0,0,0,0,0,0,0,0,0,0,~
0,0,0,0,0,0,0,0,0,0,0)';
      BIDIRECTIONAL='TRUE';
      INPUT_LOAD='(-0.01,0.01)';
      OUTPUT_LOAD='(1.0,-1.0)';
      PINUSE='BI';
    'MHB_CA0':
      PIN_NUMBER='(0,0,0,0,0,0,0,BG14,0,0,0,0,0,0,0,0,0,0,0,0,0,0,0,0,0,0,0,0,0,~
0,0,0,0,0,0,0,0,0,0,0)';
      OUTPUT_LOAD='(1.0,-1.0)';
      PINUSE='OUT';
    'MHA_DQS_L5':
      PIN_NUMBER='(0,0,0,0,0,0,0,H14,0,0,0,0,0,0,0,0,0,0,0,0,0,0,0,0,0,0,0,0,0,0~
,0,0,0,0,0,0,0,0,0,0)';
      BIDIRECTIONAL='TRUE';
      INPUT_LOAD='(-0.01,0.01)';
      OUTPUT_LOAD='(1.0,-1.0)';
      PINUSE='BI';
    'MHA_DQS_H1':
      PIN_NUMBER='(0,0,0,0,0,0,0,N12,0,0,0,0,0,0,0,0,0,0,0,0,0,0,0,0,0,0,0,0,0,0~
,0,0,0,0,0,0,0,0,0,0)';
      BIDIRECTIONAL='TRUE';
      INPUT_LOAD='(-0.01,0.01)';
      OUTPUT_LOAD='(1.0,-1.0)';
      PINUSE='BI';
    'MHA_DATA29':
      PIN_NUMBER='(0,0,0,0,0,0,0,AH14,0,0,0,0,0,0,0,0,0,0,0,0,0,0,0,0,0,0,0,0,0,~
0,0,0,0,0,0,0,0,0,0,0)';
      BIDIRECTIONAL='TRUE';
      INPUT_LOAD='(-0.01,0.01)';
      OUTPUT_LOAD='(1.0,-1.0)';
      PINUSE='BI';
    'MHA_DATA18':
      PIN_NUMBER='(0,0,0,0,0,0,0,V13,0,0,0,0,0,0,0,0,0,0,0,0,0,0,0,0,0,0,0,0,0,0~
,0,0,0,0,0,0,0,0,0,0)';
      BIDIRECTIONAL='TRUE';
      INPUT_LOAD='(-0.01,0.01)';
      OUTPUT_LOAD='(1.0,-1.0)';
      PINUSE='BI';
    'MHA_CA1':
      PIN_NUMBER='(0,0,0,0,0,0,0,AY13,0,0,0,0,0,0,0,0,0,0,0,0,0,0,0,0,0,0,0,0,0,~
0,0,0,0,0,0,0,0,0,0,0)';
      OUTPUT_LOAD='(1.0,-1.0)';
      PINUSE='OUT';
    'MHB_DQS_L0':
      PIN_NUMBER='(0,0,0,0,0,0,0,CE12,0,0,0,0,0,0,0,0,0,0,0,0,0,0,0,0,0,0,0,0,0,~
0,0,0,0,0,0,0,0,0,0,0)';
      BIDIRECTIONAL='TRUE';
      INPUT_LOAD='(-0.01,0.01)';
      OUTPUT_LOAD='(1.0,-1.0)';
      PINUSE='BI';
    'MHB_DATA24':
      PIN_NUMBER='(0,0,0,0,0,0,0,CY13,0,0,0,0,0,0,0,0,0,0,0,0,0,0,0,0,0,0,0,0,0,~
0,0,0,0,0,0,0,0,0,0,0)';
      BIDIRECTIONAL='TRUE';
      INPUT_LOAD='(-0.01,0.01)';
      OUTPUT_LOAD='(1.0,-1.0)';
      PINUSE='BI';
    'MHB_DATA13':
      PIN_NUMBER='(0,0,0,0,0,0,0,CN14,0,0,0,0,0,0,0,0,0,0,0,0,0,0,0,0,0,0,0,0,0,~
0,0,0,0,0,0,0,0,0,0,0)';
      BIDIRECTIONAL='TRUE';
      INPUT_LOAD='(-0.01,0.01)';
      OUTPUT_LOAD='(1.0,-1.0)';
      PINUSE='BI';
    'MHB_CHECK4':
      PIN_NUMBER='(0,0,0,0,0,0,0,BT13,0,0,0,0,0,0,0,0,0,0,0,0,0,0,0,0,0,0,0,0,0,~
0,0,0,0,0,0,0,0,0,0,0)';
      BIDIRECTIONAL='TRUE';
      INPUT_LOAD='(-0.01,0.01)';
      OUTPUT_LOAD='(1.0,-1.0)';
      PINUSE='BI';
    'MHB_CA1':
      PIN_NUMBER='(0,0,0,0,0,0,0,BH14,0,0,0,0,0,0,0,0,0,0,0,0,0,0,0,0,0,0,0,0,0,~
0,0,0,0,0,0,0,0,0,0,0)';
      OUTPUT_LOAD='(1.0,-1.0)';
      PINUSE='OUT';
    'MHA_DQS_L6':
      PIN_NUMBER='(0,0,0,0,0,0,0,P14,0,0,0,0,0,0,0,0,0,0,0,0,0,0,0,0,0,0,0,0,0,0~
,0,0,0,0,0,0,0,0,0,0)';
      BIDIRECTIONAL='TRUE';
      INPUT_LOAD='(-0.01,0.01)';
      OUTPUT_LOAD='(1.0,-1.0)';
      PINUSE='BI';
    'MHA_DQS_H2':
      PIN_NUMBER='(0,0,0,0,0,0,0,W12,0,0,0,0,0,0,0,0,0,0,0,0,0,0,0,0,0,0,0,0,0,0~
,0,0,0,0,0,0,0,0,0,0)';
      BIDIRECTIONAL='TRUE';
      INPUT_LOAD='(-0.01,0.01)';
      OUTPUT_LOAD='(1.0,-1.0)';
      PINUSE='BI';
    'MHA_DATA19':
      PIN_NUMBER='(0,0,0,0,0,0,0,W14,0,0,0,0,0,0,0,0,0,0,0,0,0,0,0,0,0,0,0,0,0,0~
,0,0,0,0,0,0,0,0,0,0)';
      BIDIRECTIONAL='TRUE';
      INPUT_LOAD='(-0.01,0.01)';
      OUTPUT_LOAD='(1.0,-1.0)';
      PINUSE='BI';
    'MHA_CA2':
      PIN_NUMBER='(0,0,0,0,0,0,0,AY14,0,0,0,0,0,0,0,0,0,0,0,0,0,0,0,0,0,0,0,0,0,~
0,0,0,0,0,0,0,0,0,0,0)';
      OUTPUT_LOAD='(1.0,-1.0)';
      PINUSE='OUT';
    'MHB_DQS_L1':
      PIN_NUMBER='(0,0,0,0,0,0,0,CL12,0,0,0,0,0,0,0,0,0,0,0,0,0,0,0,0,0,0,0,0,0,~
0,0,0,0,0,0,0,0,0,0,0)';
      BIDIRECTIONAL='TRUE';
      INPUT_LOAD='(-0.01,0.01)';
      OUTPUT_LOAD='(1.0,-1.0)';
      PINUSE='BI';
    'MHB_DATA25':
      PIN_NUMBER='(0,0,0,0,0,0,0,DA14,0,0,0,0,0,0,0,0,0,0,0,0,0,0,0,0,0,0,0,0,0,~
0,0,0,0,0,0,0,0,0,0,0)';
      BIDIRECTIONAL='TRUE';
      INPUT_LOAD='(-0.01,0.01)';
      OUTPUT_LOAD='(1.0,-1.0)';
      PINUSE='BI';
    'MHB_DATA14':
      PIN_NUMBER='(0,0,0,0,0,0,0,CN12,0,0,0,0,0,0,0,0,0,0,0,0,0,0,0,0,0,0,0,0,0,~
0,0,0,0,0,0,0,0,0,0,0)';
      BIDIRECTIONAL='TRUE';
      INPUT_LOAD='(-0.01,0.01)';
      OUTPUT_LOAD='(1.0,-1.0)';
      PINUSE='BI';
    'MHB_DATA0':
      PIN_NUMBER='(0,0,0,0,0,0,0,CB13,0,0,0,0,0,0,0,0,0,0,0,0,0,0,0,0,0,0,0,0,0,~
0,0,0,0,0,0,0,0,0,0,0)';
      BIDIRECTIONAL='TRUE';
      INPUT_LOAD='(-0.01,0.01)';
      OUTPUT_LOAD='(1.0,-1.0)';
      PINUSE='BI';
    'MHB_CHECK5':
      PIN_NUMBER='(0,0,0,0,0,0,0,BU14,0,0,0,0,0,0,0,0,0,0,0,0,0,0,0,0,0,0,0,0,0,~
0,0,0,0,0,0,0,0,0,0,0)';
      BIDIRECTIONAL='TRUE';
      INPUT_LOAD='(-0.01,0.01)';
      OUTPUT_LOAD='(1.0,-1.0)';
      PINUSE='BI';
    'MHB_CA2':
      PIN_NUMBER='(0,0,0,0,0,0,0,BH13,0,0,0,0,0,0,0,0,0,0,0,0,0,0,0,0,0,0,0,0,0,~
0,0,0,0,0,0,0,0,0,0,0)';
      OUTPUT_LOAD='(1.0,-1.0)';
      PINUSE='OUT';
    'MHA_DQS_L7':
      PIN_NUMBER='(0,0,0,0,0,0,0,Y14,0,0,0,0,0,0,0,0,0,0,0,0,0,0,0,0,0,0,0,0,0,0~
,0,0,0,0,0,0,0,0,0,0)';
      BIDIRECTIONAL='TRUE';
      INPUT_LOAD='(-0.01,0.01)';
      OUTPUT_LOAD='(1.0,-1.0)';
      PINUSE='BI';
    'MHA_DQS_H3':
      PIN_NUMBER='(0,0,0,0,0,0,0,AE12,0,0,0,0,0,0,0,0,0,0,0,0,0,0,0,0,0,0,0,0,0,~
0,0,0,0,0,0,0,0,0,0,0)';
      BIDIRECTIONAL='TRUE';
      INPUT_LOAD='(-0.01,0.01)';
      OUTPUT_LOAD='(1.0,-1.0)';
      PINUSE='BI';
    'MHA_DATA0':
      PIN_NUMBER='(0,0,0,0,0,0,0,E12,0,0,0,0,0,0,0,0,0,0,0,0,0,0,0,0,0,0,0,0,0,0~
,0,0,0,0,0,0,0,0,0,0)';
      BIDIRECTIONAL='TRUE';
      INPUT_LOAD='(-0.01,0.01)';
      OUTPUT_LOAD='(1.0,-1.0)';
      PINUSE='BI';
    'MHA_CA3':
      PIN_NUMBER='(0,0,0,0,0,0,0,BA14,0,0,0,0,0,0,0,0,0,0,0,0,0,0,0,0,0,0,0,0,0,~
0,0,0,0,0,0,0,0,0,0,0)';
      OUTPUT_LOAD='(1.0,-1.0)';
      PINUSE='OUT';
    'MHB_DQS_L2':
      PIN_NUMBER='(0,0,0,0,0,0,0,CU12,0,0,0,0,0,0,0,0,0,0,0,0,0,0,0,0,0,0,0,0,0,~
0,0,0,0,0,0,0,0,0,0,0)';
      BIDIRECTIONAL='TRUE';
      INPUT_LOAD='(-0.01,0.01)';
      OUTPUT_LOAD='(1.0,-1.0)';
      PINUSE='BI';
    'MHB_DATA26':
      PIN_NUMBER='(0,0,0,0,0,0,0,DA12,0,0,0,0,0,0,0,0,0,0,0,0,0,0,0,0,0,0,0,0,0,~
0,0,0,0,0,0,0,0,0,0,0)';
      BIDIRECTIONAL='TRUE';
      INPUT_LOAD='(-0.01,0.01)';
      OUTPUT_LOAD='(1.0,-1.0)';
      PINUSE='BI';
    'MHB_DATA15':
      PIN_NUMBER='(0,0,0,0,0,0,0,CP14,0,0,0,0,0,0,0,0,0,0,0,0,0,0,0,0,0,0,0,0,0,~
0,0,0,0,0,0,0,0,0,0,0)';
      BIDIRECTIONAL='TRUE';
      INPUT_LOAD='(-0.01,0.01)';
      OUTPUT_LOAD='(1.0,-1.0)';
      PINUSE='BI';
    'MHB_DATA1':
      PIN_NUMBER='(0,0,0,0,0,0,0,CC14,0,0,0,0,0,0,0,0,0,0,0,0,0,0,0,0,0,0,0,0,0,~
0,0,0,0,0,0,0,0,0,0,0)';
      BIDIRECTIONAL='TRUE';
      INPUT_LOAD='(-0.01,0.01)';
      OUTPUT_LOAD='(1.0,-1.0)';
      PINUSE='BI';
    'MHB_CHECK6':
      PIN_NUMBER='(0,0,0,0,0,0,0,BU12,0,0,0,0,0,0,0,0,0,0,0,0,0,0,0,0,0,0,0,0,0,~
0,0,0,0,0,0,0,0,0,0,0)';
      BIDIRECTIONAL='TRUE';
      INPUT_LOAD='(-0.01,0.01)';
      OUTPUT_LOAD='(1.0,-1.0)';
      PINUSE='BI';
    'MHB_CA3':
      PIN_NUMBER='(0,0,0,0,0,0,0,BJ12,0,0,0,0,0,0,0,0,0,0,0,0,0,0,0,0,0,0,0,0,0,~
0,0,0,0,0,0,0,0,0,0,0)';
      OUTPUT_LOAD='(1.0,-1.0)';
      PINUSE='OUT';
    'MHA_DQS_L8':
      PIN_NUMBER='(0,0,0,0,0,0,0,AF14,0,0,0,0,0,0,0,0,0,0,0,0,0,0,0,0,0,0,0,0,0,~
0,0,0,0,0,0,0,0,0,0,0)';
      BIDIRECTIONAL='TRUE';
      INPUT_LOAD='(-0.01,0.01)';
      OUTPUT_LOAD='(1.0,-1.0)';
      PINUSE='BI';
    'MHA_DQS_H4':
      PIN_NUMBER='(0,0,0,0,0,0,0,AL12,0,0,0,0,0,0,0,0,0,0,0,0,0,0,0,0,0,0,0,0,0,~
0,0,0,0,0,0,0,0,0,0,0)';
      BIDIRECTIONAL='TRUE';
      INPUT_LOAD='(-0.01,0.01)';
      OUTPUT_LOAD='(1.0,-1.0)';
      PINUSE='BI';
    'MHA_DATA1':
      PIN_NUMBER='(0,0,0,0,0,0,0,F14,0,0,0,0,0,0,0,0,0,0,0,0,0,0,0,0,0,0,0,0,0,0~
,0,0,0,0,0,0,0,0,0,0)';
      BIDIRECTIONAL='TRUE';
      INPUT_LOAD='(-0.01,0.01)';
      OUTPUT_LOAD='(1.0,-1.0)';
      PINUSE='BI';
    'MHA_CA4':
      PIN_NUMBER='(0,0,0,0,0,0,0,BA12,0,0,0,0,0,0,0,0,0,0,0,0,0,0,0,0,0,0,0,0,0,~
0,0,0,0,0,0,0,0,0,0,0)';
      OUTPUT_LOAD='(1.0,-1.0)';
      PINUSE='OUT';
    'MHB_DQS_L3':
      PIN_NUMBER='(0,0,0,0,0,0,0,DC12,0,0,0,0,0,0,0,0,0,0,0,0,0,0,0,0,0,0,0,0,0,~
0,0,0,0,0,0,0,0,0,0,0)';
      BIDIRECTIONAL='TRUE';
      INPUT_LOAD='(-0.01,0.01)';
      OUTPUT_LOAD='(1.0,-1.0)';
      PINUSE='BI';
    'MHB_DATA27':
      PIN_NUMBER='(0,0,0,0,0,0,0,DB14,0,0,0,0,0,0,0,0,0,0,0,0,0,0,0,0,0,0,0,0,0,~
0,0,0,0,0,0,0,0,0,0,0)';
      BIDIRECTIONAL='TRUE';
      INPUT_LOAD='(-0.01,0.01)';
      OUTPUT_LOAD='(1.0,-1.0)';
      PINUSE='BI';
    'MHB_DATA16':
      PIN_NUMBER='(0,0,0,0,0,0,0,CP13,0,0,0,0,0,0,0,0,0,0,0,0,0,0,0,0,0,0,0,0,0,~
0,0,0,0,0,0,0,0,0,0,0)';
      BIDIRECTIONAL='TRUE';
      INPUT_LOAD='(-0.01,0.01)';
      OUTPUT_LOAD='(1.0,-1.0)';
      PINUSE='BI';
    'MHB_DATA2':
      PIN_NUMBER='(0,0,0,0,0,0,0,CC12,0,0,0,0,0,0,0,0,0,0,0,0,0,0,0,0,0,0,0,0,0,~
0,0,0,0,0,0,0,0,0,0,0)';
      BIDIRECTIONAL='TRUE';
      INPUT_LOAD='(-0.01,0.01)';
      OUTPUT_LOAD='(1.0,-1.0)';
      PINUSE='BI';
    'MHB_CHECK7':
      PIN_NUMBER='(0,0,0,0,0,0,0,BV14,0,0,0,0,0,0,0,0,0,0,0,0,0,0,0,0,0,0,0,0,0,~
0,0,0,0,0,0,0,0,0,0,0)';
      BIDIRECTIONAL='TRUE';
      INPUT_LOAD='(-0.01,0.01)';
      OUTPUT_LOAD='(1.0,-1.0)';
      PINUSE='BI';
    'MHB_CA4':
      PIN_NUMBER='(0,0,0,0,0,0,0,BJ14,0,0,0,0,0,0,0,0,0,0,0,0,0,0,0,0,0,0,0,0,0,~
0,0,0,0,0,0,0,0,0,0,0)';
      OUTPUT_LOAD='(1.0,-1.0)';
      PINUSE='OUT';
    'MHB0_RSP_L':
      PIN_NUMBER='(0,0,0,0,0,0,0,BP13,0,0,0,0,0,0,0,0,0,0,0,0,0,0,0,0,0,0,0,0,0,~
0,0,0,0,0,0,0,0,0,0,0)';
      INPUT_LOAD='(-0.01,0.01)';
      PINUSE='IN';
    'MHA_DQS_L9':
      PIN_NUMBER='(0,0,0,0,0,0,0,AM14,0,0,0,0,0,0,0,0,0,0,0,0,0,0,0,0,0,0,0,0,0,~
0,0,0,0,0,0,0,0,0,0,0)';
      BIDIRECTIONAL='TRUE';
      INPUT_LOAD='(-0.01,0.01)';
      OUTPUT_LOAD='(1.0,-1.0)';
      PINUSE='BI';
    'MHA_DQS_H5':
      PIN_NUMBER='(0,0,0,0,0,0,0,J14,0,0,0,0,0,0,0,0,0,0,0,0,0,0,0,0,0,0,0,0,0,0~
,0,0,0,0,0,0,0,0,0,0)';
      BIDIRECTIONAL='TRUE';
      INPUT_LOAD='(-0.01,0.01)';
      OUTPUT_LOAD='(1.0,-1.0)';
      PINUSE='BI';
    'MHA_DATA2':
      PIN_NUMBER='(0,0,0,0,0,0,0,F13,0,0,0,0,0,0,0,0,0,0,0,0,0,0,0,0,0,0,0,0,0,0~
,0,0,0,0,0,0,0,0,0,0)';
      BIDIRECTIONAL='TRUE';
      INPUT_LOAD='(-0.01,0.01)';
      OUTPUT_LOAD='(1.0,-1.0)';
      PINUSE='BI';
    'MHA_CA5':
      PIN_NUMBER='(0,0,0,0,0,0,0,BB13,0,0,0,0,0,0,0,0,0,0,0,0,0,0,0,0,0,0,0,0,0,~
0,0,0,0,0,0,0,0,0,0,0)';
      OUTPUT_LOAD='(1.0,-1.0)';
      PINUSE='OUT';
    'MHB_DQS_L4':
      PIN_NUMBER='(0,0,0,0,0,0,0,BW14,0,0,0,0,0,0,0,0,0,0,0,0,0,0,0,0,0,0,0,0,0,~
0,0,0,0,0,0,0,0,0,0,0)';
      BIDIRECTIONAL='TRUE';
      INPUT_LOAD='(-0.01,0.01)';
      OUTPUT_LOAD='(1.0,-1.0)';
      PINUSE='BI';
    'MHB_DQS_H0':
      PIN_NUMBER='(0,0,0,0,0,0,0,CD13,0,0,0,0,0,0,0,0,0,0,0,0,0,0,0,0,0,0,0,0,0,~
0,0,0,0,0,0,0,0,0,0,0)';
      BIDIRECTIONAL='TRUE';
      INPUT_LOAD='(-0.01,0.01)';
      OUTPUT_LOAD='(1.0,-1.0)';
      PINUSE='BI';
    'MHB_DATA28':
      PIN_NUMBER='(0,0,0,0,0,0,0,DD13,0,0,0,0,0,0,0,0,0,0,0,0,0,0,0,0,0,0,0,0,0,~
0,0,0,0,0,0,0,0,0,0,0)';
      BIDIRECTIONAL='TRUE';
      INPUT_LOAD='(-0.01,0.01)';
      OUTPUT_LOAD='(1.0,-1.0)';
      PINUSE='BI';
    'MHB_DATA17':
      PIN_NUMBER='(0,0,0,0,0,0,0,CR14,0,0,0,0,0,0,0,0,0,0,0,0,0,0,0,0,0,0,0,0,0,~
0,0,0,0,0,0,0,0,0,0,0)';
      BIDIRECTIONAL='TRUE';
      INPUT_LOAD='(-0.01,0.01)';
      OUTPUT_LOAD='(1.0,-1.0)';
      PINUSE='BI';
    'MHB_DATA3':
      PIN_NUMBER='(0,0,0,0,0,0,0,CD14,0,0,0,0,0,0,0,0,0,0,0,0,0,0,0,0,0,0,0,0,0,~
0,0,0,0,0,0,0,0,0,0,0)';
      BIDIRECTIONAL='TRUE';
      INPUT_LOAD='(-0.01,0.01)';
      OUTPUT_LOAD='(1.0,-1.0)';
      PINUSE='BI';
    'MHB_CA5':
      PIN_NUMBER='(0,0,0,0,0,0,0,BK14,0,0,0,0,0,0,0,0,0,0,0,0,0,0,0,0,0,0,0,0,0,~
0,0,0,0,0,0,0,0,0,0,0)';
      OUTPUT_LOAD='(1.0,-1.0)';
      PINUSE='OUT';
    'MHB1_RSP_L':
      PIN_NUMBER='(0,0,0,0,0,0,0,BR12,0,0,0,0,0,0,0,0,0,0,0,0,0,0,0,0,0,0,0,0,0,~
0,0,0,0,0,0,0,0,0,0,0)';
      INPUT_LOAD='(-0.01,0.01)';
      PINUSE='IN';
    'MHA_DQS_H6':
      PIN_NUMBER='(0,0,0,0,0,0,0,R14,0,0,0,0,0,0,0,0,0,0,0,0,0,0,0,0,0,0,0,0,0,0~
,0,0,0,0,0,0,0,0,0,0)';
      BIDIRECTIONAL='TRUE';
      INPUT_LOAD='(-0.01,0.01)';
      OUTPUT_LOAD='(1.0,-1.0)';
      PINUSE='BI';
    'MHA_DATA3':
      PIN_NUMBER='(0,0,0,0,0,0,0,G14,0,0,0,0,0,0,0,0,0,0,0,0,0,0,0,0,0,0,0,0,0,0~
,0,0,0,0,0,0,0,0,0,0)';
      BIDIRECTIONAL='TRUE';
      INPUT_LOAD='(-0.01,0.01)';
      OUTPUT_LOAD='(1.0,-1.0)';
      PINUSE='BI';
    'MHA_CA6':
      PIN_NUMBER='(0,0,0,0,0,0,0,BB14,0,0,0,0,0,0,0,0,0,0,0,0,0,0,0,0,0,0,0,0,0,~
0,0,0,0,0,0,0,0,0,0,0)';
      OUTPUT_LOAD='(1.0,-1.0)';
      PINUSE='OUT';
    'MHB_DQS_L5':
      PIN_NUMBER='(0,0,0,0,0,0,0,CE14,0,0,0,0,0,0,0,0,0,0,0,0,0,0,0,0,0,0,0,0,0,~
0,0,0,0,0,0,0,0,0,0,0)';
      BIDIRECTIONAL='TRUE';
      INPUT_LOAD='(-0.01,0.01)';
      OUTPUT_LOAD='(1.0,-1.0)';
      PINUSE='BI';
    'MHB_DQS_H1':
      PIN_NUMBER='(0,0,0,0,0,0,0,CK13,0,0,0,0,0,0,0,0,0,0,0,0,0,0,0,0,0,0,0,0,0,~
0,0,0,0,0,0,0,0,0,0,0)';
      BIDIRECTIONAL='TRUE';
      INPUT_LOAD='(-0.01,0.01)';
      OUTPUT_LOAD='(1.0,-1.0)';
      PINUSE='BI';
    'MHB_DATA29':
      PIN_NUMBER='(0,0,0,0,0,0,0,DE14,0,0,0,0,0,0,0,0,0,0,0,0,0,0,0,0,0,0,0,0,0,~
0,0,0,0,0,0,0,0,0,0,0)';
      BIDIRECTIONAL='TRUE';
      INPUT_LOAD='(-0.01,0.01)';
      OUTPUT_LOAD='(1.0,-1.0)';
      PINUSE='BI';
    'MHB_DATA18':
      PIN_NUMBER='(0,0,0,0,0,0,0,CR12,0,0,0,0,0,0,0,0,0,0,0,0,0,0,0,0,0,0,0,0,0,~
0,0,0,0,0,0,0,0,0,0,0)';
      BIDIRECTIONAL='TRUE';
      INPUT_LOAD='(-0.01,0.01)';
      OUTPUT_LOAD='(1.0,-1.0)';
      PINUSE='BI';
    'MHB_DATA4':
      PIN_NUMBER='(0,0,0,0,0,0,0,CF13,0,0,0,0,0,0,0,0,0,0,0,0,0,0,0,0,0,0,0,0,0,~
0,0,0,0,0,0,0,0,0,0,0)';
      BIDIRECTIONAL='TRUE';
      INPUT_LOAD='(-0.01,0.01)';
      OUTPUT_LOAD='(1.0,-1.0)';
      PINUSE='BI';
    'MHB_CA6':
      PIN_NUMBER='(0,0,0,0,0,0,0,BK13,0,0,0,0,0,0,0,0,0,0,0,0,0,0,0,0,0,0,0,0,0,~
0,0,0,0,0,0,0,0,0,0,0)';
      OUTPUT_LOAD='(1.0,-1.0)';
      PINUSE='OUT';
    'MHA_DQS_H7':
      PIN_NUMBER='(0,0,0,0,0,0,0,AA14,0,0,0,0,0,0,0,0,0,0,0,0,0,0,0,0,0,0,0,0,0,~
0,0,0,0,0,0,0,0,0,0,0)';
      BIDIRECTIONAL='TRUE';
      INPUT_LOAD='(-0.01,0.01)';
      OUTPUT_LOAD='(1.0,-1.0)';
      PINUSE='BI';
    'MHA_DATA4':
      PIN_NUMBER='(0,0,0,0,0,0,0,J12,0,0,0,0,0,0,0,0,0,0,0,0,0,0,0,0,0,0,0,0,0,0~
,0,0,0,0,0,0,0,0,0,0)';
      BIDIRECTIONAL='TRUE';
      INPUT_LOAD='(-0.01,0.01)';
      OUTPUT_LOAD='(1.0,-1.0)';
      PINUSE='BI';
    'MHA0_CS_L0':
      PIN_NUMBER='(0,0,0,0,0,0,0,AU12,0,0,0,0,0,0,0,0,0,0,0,0,0,0,0,0,0,0,0,0,0,~
0,0,0,0,0,0,0,0,0,0,0)';
      OUTPUT_LOAD='(1.0,-1.0)';
      PINUSE='OUT';
    'MHB_DQS_L6':
      PIN_NUMBER='(0,0,0,0,0,0,0,CL14,0,0,0,0,0,0,0,0,0,0,0,0,0,0,0,0,0,0,0,0,0,~
0,0,0,0,0,0,0,0,0,0,0)';
      BIDIRECTIONAL='TRUE';
      INPUT_LOAD='(-0.01,0.01)';
      OUTPUT_LOAD='(1.0,-1.0)';
      PINUSE='BI';
    'MHB_DQS_H2':
      PIN_NUMBER='(0,0,0,0,0,0,0,CT13,0,0,0,0,0,0,0,0,0,0,0,0,0,0,0,0,0,0,0,0,0,~
0,0,0,0,0,0,0,0,0,0,0)';
      BIDIRECTIONAL='TRUE';
      INPUT_LOAD='(-0.01,0.01)';
      OUTPUT_LOAD='(1.0,-1.0)';
      PINUSE='BI';
    'MHB_DATA19':
      PIN_NUMBER='(0,0,0,0,0,0,0,CT14,0,0,0,0,0,0,0,0,0,0,0,0,0,0,0,0,0,0,0,0,0,~
0,0,0,0,0,0,0,0,0,0,0)';
      BIDIRECTIONAL='TRUE';
      INPUT_LOAD='(-0.01,0.01)';
      OUTPUT_LOAD='(1.0,-1.0)';
      PINUSE='BI';
    'MHB_DATA5':
      PIN_NUMBER='(0,0,0,0,0,0,0,CG14,0,0,0,0,0,0,0,0,0,0,0,0,0,0,0,0,0,0,0,0,0,~
0,0,0,0,0,0,0,0,0,0,0)';
      BIDIRECTIONAL='TRUE';
      INPUT_LOAD='(-0.01,0.01)';
      OUTPUT_LOAD='(1.0,-1.0)';
      PINUSE='BI';
    'MHA_DQS_H8':
      PIN_NUMBER='(0,0,0,0,0,0,0,AG14,0,0,0,0,0,0,0,0,0,0,0,0,0,0,0,0,0,0,0,0,0,~
0,0,0,0,0,0,0,0,0,0,0)';
      BIDIRECTIONAL='TRUE';
      INPUT_LOAD='(-0.01,0.01)';
      OUTPUT_LOAD='(1.0,-1.0)';
      PINUSE='BI';
    'MHA_DATA30':
      PIN_NUMBER='(0,0,0,0,0,0,0,AH13,0,0,0,0,0,0,0,0,0,0,0,0,0,0,0,0,0,0,0,0,0,~
0,0,0,0,0,0,0,0,0,0,0)';
      BIDIRECTIONAL='TRUE';
      INPUT_LOAD='(-0.01,0.01)';
      OUTPUT_LOAD='(1.0,-1.0)';
      PINUSE='BI';
    'MHA_DATA5':
      PIN_NUMBER='(0,0,0,0,0,0,0,K14,0,0,0,0,0,0,0,0,0,0,0,0,0,0,0,0,0,0,0,0,0,0~
,0,0,0,0,0,0,0,0,0,0)';
      BIDIRECTIONAL='TRUE';
      INPUT_LOAD='(-0.01,0.01)';
      OUTPUT_LOAD='(1.0,-1.0)';
      PINUSE='BI';
    'MHA1_CS_L0':
      PIN_NUMBER='(0,0,0,0,0,0,0,AV13,0,0,0,0,0,0,0,0,0,0,0,0,0,0,0,0,0,0,0,0,0,~
0,0,0,0,0,0,0,0,0,0,0)';
      OUTPUT_LOAD='(1.0,-1.0)';
      PINUSE='OUT';
    'MHA0_CS_L1':
      PIN_NUMBER='(0,0,0,0,0,0,0,AV14,0,0,0,0,0,0,0,0,0,0,0,0,0,0,0,0,0,0,0,0,0,~
0,0,0,0,0,0,0,0,0,0,0)';
      OUTPUT_LOAD='(1.0,-1.0)';
      PINUSE='OUT';
    'MHB_DQS_L7':
      PIN_NUMBER='(0,0,0,0,0,0,0,CU14,0,0,0,0,0,0,0,0,0,0,0,0,0,0,0,0,0,0,0,0,0,~
0,0,0,0,0,0,0,0,0,0,0)';
      BIDIRECTIONAL='TRUE';
      INPUT_LOAD='(-0.01,0.01)';
      OUTPUT_LOAD='(1.0,-1.0)';
      PINUSE='BI';
    'MHB_DQS_H3':
      PIN_NUMBER='(0,0,0,0,0,0,0,DB13,0,0,0,0,0,0,0,0,0,0,0,0,0,0,0,0,0,0,0,0,0,~
0,0,0,0,0,0,0,0,0,0,0)';
      BIDIRECTIONAL='TRUE';
      INPUT_LOAD='(-0.01,0.01)';
      OUTPUT_LOAD='(1.0,-1.0)';
      PINUSE='BI';
    'MHB_DATA6':
      PIN_NUMBER='(0,0,0,0,0,0,0,CG12,0,0,0,0,0,0,0,0,0,0,0,0,0,0,0,0,0,0,0,0,0,~
0,0,0,0,0,0,0,0,0,0,0)';
      BIDIRECTIONAL='TRUE';
      INPUT_LOAD='(-0.01,0.01)';
      OUTPUT_LOAD='(1.0,-1.0)';
      PINUSE='BI';
    'MHA_DQS_H9':
      PIN_NUMBER='(0,0,0,0,0,0,0,AN14,0,0,0,0,0,0,0,0,0,0,0,0,0,0,0,0,0,0,0,0,0,~
0,0,0,0,0,0,0,0,0,0,0)';
      BIDIRECTIONAL='TRUE';
      INPUT_LOAD='(-0.01,0.01)';
      OUTPUT_LOAD='(1.0,-1.0)';
      PINUSE='BI';
    'MHA_DATA31':
      PIN_NUMBER='(0,0,0,0,0,0,0,AJ14,0,0,0,0,0,0,0,0,0,0,0,0,0,0,0,0,0,0,0,0,0,~
0,0,0,0,0,0,0,0,0,0,0)';
      BIDIRECTIONAL='TRUE';
      INPUT_LOAD='(-0.01,0.01)';
      OUTPUT_LOAD='(1.0,-1.0)';
      PINUSE='BI';
    'MHA_DATA20':
      PIN_NUMBER='(0,0,0,0,0,0,0,AA12,0,0,0,0,0,0,0,0,0,0,0,0,0,0,0,0,0,0,0,0,0,~
0,0,0,0,0,0,0,0,0,0,0)';
      BIDIRECTIONAL='TRUE';
      INPUT_LOAD='(-0.01,0.01)';
      OUTPUT_LOAD='(1.0,-1.0)';
      PINUSE='BI';
    'MHA_DATA6':
      PIN_NUMBER='(0,0,0,0,0,0,0,K13,0,0,0,0,0,0,0,0,0,0,0,0,0,0,0,0,0,0,0,0,0,0~
,0,0,0,0,0,0,0,0,0,0)';
      BIDIRECTIONAL='TRUE';
      INPUT_LOAD='(-0.01,0.01)';
      OUTPUT_LOAD='(1.0,-1.0)';
      PINUSE='BI';
    'MHA_CHECK0':
      PIN_NUMBER='(0,0,0,0,0,0,0,AJ12,0,0,0,0,0,0,0,0,0,0,0,0,0,0,0,0,0,0,0,0,0,~
0,0,0,0,0,0,0,0,0,0,0)';
      BIDIRECTIONAL='TRUE';
      INPUT_LOAD='(-0.01,0.01)';
      OUTPUT_LOAD='(1.0,-1.0)';
      PINUSE='BI';
    'MHA1_CS_L1':
      PIN_NUMBER='(0,0,0,0,0,0,0,AW14,0,0,0,0,0,0,0,0,0,0,0,0,0,0,0,0,0,0,0,0,0,~
0,0,0,0,0,0,0,0,0,0,0)';
      OUTPUT_LOAD='(1.0,-1.0)';
      PINUSE='OUT';
    'MHB_DQS_L8':
      PIN_NUMBER='(0,0,0,0,0,0,0,DC14,0,0,0,0,0,0,0,0,0,0,0,0,0,0,0,0,0,0,0,0,0,~
0,0,0,0,0,0,0,0,0,0,0)';
      BIDIRECTIONAL='TRUE';
      INPUT_LOAD='(-0.01,0.01)';
      OUTPUT_LOAD='(1.0,-1.0)';
      PINUSE='BI';
    'MHB_DQS_H4':
      PIN_NUMBER='(0,0,0,0,0,0,0,BY14,0,0,0,0,0,0,0,0,0,0,0,0,0,0,0,0,0,0,0,0,0,~
0,0,0,0,0,0,0,0,0,0,0)';
      BIDIRECTIONAL='TRUE';
      INPUT_LOAD='(-0.01,0.01)';
      OUTPUT_LOAD='(1.0,-1.0)';
      PINUSE='BI';
    'MHB_DATA7':
      PIN_NUMBER='(0,0,0,0,0,0,0,CH14,0,0,0,0,0,0,0,0,0,0,0,0,0,0,0,0,0,0,0,0,0,~
0,0,0,0,0,0,0,0,0,0,0)';
      BIDIRECTIONAL='TRUE';
      INPUT_LOAD='(-0.01,0.01)';
      OUTPUT_LOAD='(1.0,-1.0)';
      PINUSE='BI';
    'MHA_DATA21':
      PIN_NUMBER='(0,0,0,0,0,0,0,AB14,0,0,0,0,0,0,0,0,0,0,0,0,0,0,0,0,0,0,0,0,0,~
0,0,0,0,0,0,0,0,0,0,0)';
      BIDIRECTIONAL='TRUE';
      INPUT_LOAD='(-0.01,0.01)';
      OUTPUT_LOAD='(1.0,-1.0)';
      PINUSE='BI';
    'MHA_DATA10':
      PIN_NUMBER='(0,0,0,0,0,0,0,M13,0,0,0,0,0,0,0,0,0,0,0,0,0,0,0,0,0,0,0,0,0,0~
,0,0,0,0,0,0,0,0,0,0)';
      BIDIRECTIONAL='TRUE';
      INPUT_LOAD='(-0.01,0.01)';
      OUTPUT_LOAD='(1.0,-1.0)';
      PINUSE='BI';
    'MHA_DATA7':
      PIN_NUMBER='(0,0,0,0,0,0,0,L14,0,0,0,0,0,0,0,0,0,0,0,0,0,0,0,0,0,0,0,0,0,0~
,0,0,0,0,0,0,0,0,0,0)';
      BIDIRECTIONAL='TRUE';
      INPUT_LOAD='(-0.01,0.01)';
      OUTPUT_LOAD='(1.0,-1.0)';
      PINUSE='BI';
    'MHA_CHECK1':
      PIN_NUMBER='(0,0,0,0,0,0,0,AK14,0,0,0,0,0,0,0,0,0,0,0,0,0,0,0,0,0,0,0,0,0,~
0,0,0,0,0,0,0,0,0,0,0)';
      BIDIRECTIONAL='TRUE';
      INPUT_LOAD='(-0.01,0.01)';
      OUTPUT_LOAD='(1.0,-1.0)';
      PINUSE='BI';
    'MHB_DQS_L9':
      PIN_NUMBER='(0,0,0,0,0,0,0,BW12,0,0,0,0,0,0,0,0,0,0,0,0,0,0,0,0,0,0,0,0,0,~
0,0,0,0,0,0,0,0,0,0,0)';
      BIDIRECTIONAL='TRUE';
      INPUT_LOAD='(-0.01,0.01)';
      OUTPUT_LOAD='(1.0,-1.0)';
      PINUSE='BI';
    'MHB_DQS_H5':
      PIN_NUMBER='(0,0,0,0,0,0,0,CF14,0,0,0,0,0,0,0,0,0,0,0,0,0,0,0,0,0,0,0,0,0,~
0,0,0,0,0,0,0,0,0,0,0)';
      BIDIRECTIONAL='TRUE';
      INPUT_LOAD='(-0.01,0.01)';
      OUTPUT_LOAD='(1.0,-1.0)';
      PINUSE='BI';
    'MHB_DATA8':
      PIN_NUMBER='(0,0,0,0,0,0,0,CH13,0,0,0,0,0,0,0,0,0,0,0,0,0,0,0,0,0,0,0,0,0,~
0,0,0,0,0,0,0,0,0,0,0)';
      BIDIRECTIONAL='TRUE';
      INPUT_LOAD='(-0.01,0.01)';
      OUTPUT_LOAD='(1.0,-1.0)';
      PINUSE='BI';
    'MHA_DATA22':
      PIN_NUMBER='(0,0,0,0,0,0,0,AB13,0,0,0,0,0,0,0,0,0,0,0,0,0,0,0,0,0,0,0,0,0,~
0,0,0,0,0,0,0,0,0,0,0)';
      BIDIRECTIONAL='TRUE';
      INPUT_LOAD='(-0.01,0.01)';
      OUTPUT_LOAD='(1.0,-1.0)';
      PINUSE='BI';
    'MHA_DATA11':
      PIN_NUMBER='(0,0,0,0,0,0,0,N14,0,0,0,0,0,0,0,0,0,0,0,0,0,0,0,0,0,0,0,0,0,0~
,0,0,0,0,0,0,0,0,0,0)';
      BIDIRECTIONAL='TRUE';
      INPUT_LOAD='(-0.01,0.01)';
      OUTPUT_LOAD='(1.0,-1.0)';
      PINUSE='BI';
    'MHA_DATA8':
      PIN_NUMBER='(0,0,0,0,0,0,0,L12,0,0,0,0,0,0,0,0,0,0,0,0,0,0,0,0,0,0,0,0,0,0~
,0,0,0,0,0,0,0,0,0,0)';
      BIDIRECTIONAL='TRUE';
      INPUT_LOAD='(-0.01,0.01)';
      OUTPUT_LOAD='(1.0,-1.0)';
      PINUSE='BI';
    'MHA_CHECK2':
      PIN_NUMBER='(0,0,0,0,0,0,0,AK13,0,0,0,0,0,0,0,0,0,0,0,0,0,0,0,0,0,0,0,0,0,~
0,0,0,0,0,0,0,0,0,0,0)';
      BIDIRECTIONAL='TRUE';
      INPUT_LOAD='(-0.01,0.01)';
      OUTPUT_LOAD='(1.0,-1.0)';
      PINUSE='BI';
    'MHB_DQS_H6':
      PIN_NUMBER='(0,0,0,0,0,0,0,CM14,0,0,0,0,0,0,0,0,0,0,0,0,0,0,0,0,0,0,0,0,0,~
0,0,0,0,0,0,0,0,0,0,0)';
      BIDIRECTIONAL='TRUE';
      INPUT_LOAD='(-0.01,0.01)';
      OUTPUT_LOAD='(1.0,-1.0)';
      PINUSE='BI';
    'MHB_DATA9':
      PIN_NUMBER='(0,0,0,0,0,0,0,CJ14,0,0,0,0,0,0,0,0,0,0,0,0,0,0,0,0,0,0,0,0,0,~
0,0,0,0,0,0,0,0,0,0,0)';
      BIDIRECTIONAL='TRUE';
      INPUT_LOAD='(-0.01,0.01)';
      OUTPUT_LOAD='(1.0,-1.0)';
      PINUSE='BI';
    'MHA_DATA23':
      PIN_NUMBER='(0,0,0,0,0,0,0,AC14,0,0,0,0,0,0,0,0,0,0,0,0,0,0,0,0,0,0,0,0,0,~
0,0,0,0,0,0,0,0,0,0,0)';
      BIDIRECTIONAL='TRUE';
      INPUT_LOAD='(-0.01,0.01)';
      OUTPUT_LOAD='(1.0,-1.0)';
      PINUSE='BI';
    'MHA_DATA12':
      PIN_NUMBER='(0,0,0,0,0,0,0,R12,0,0,0,0,0,0,0,0,0,0,0,0,0,0,0,0,0,0,0,0,0,0~
,0,0,0,0,0,0,0,0,0,0)';
      BIDIRECTIONAL='TRUE';
      INPUT_LOAD='(-0.01,0.01)';
      OUTPUT_LOAD='(1.0,-1.0)';
      PINUSE='BI';
    'MHA_DATA9':
      PIN_NUMBER='(0,0,0,0,0,0,0,M14,0,0,0,0,0,0,0,0,0,0,0,0,0,0,0,0,0,0,0,0,0,0~
,0,0,0,0,0,0,0,0,0,0)';
      BIDIRECTIONAL='TRUE';
      INPUT_LOAD='(-0.01,0.01)';
      OUTPUT_LOAD='(1.0,-1.0)';
      PINUSE='BI';
    'MHA_CHECK3':
      PIN_NUMBER='(0,0,0,0,0,0,0,AL14,0,0,0,0,0,0,0,0,0,0,0,0,0,0,0,0,0,0,0,0,0,~
0,0,0,0,0,0,0,0,0,0,0)';
      BIDIRECTIONAL='TRUE';
      INPUT_LOAD='(-0.01,0.01)';
      OUTPUT_LOAD='(1.0,-1.0)';
      PINUSE='BI';
    'MHB_DQS_H7':
      PIN_NUMBER='(0,0,0,0,0,0,0,CV14,0,0,0,0,0,0,0,0,0,0,0,0,0,0,0,0,0,0,0,0,0,~
0,0,0,0,0,0,0,0,0,0,0)';
      BIDIRECTIONAL='TRUE';
      INPUT_LOAD='(-0.01,0.01)';
      OUTPUT_LOAD='(1.0,-1.0)';
      PINUSE='BI';
    'MHB0_CS_L0':
      PIN_NUMBER='(0,0,0,0,0,0,0,BM14,0,0,0,0,0,0,0,0,0,0,0,0,0,0,0,0,0,0,0,0,0,~
0,0,0,0,0,0,0,0,0,0,0)';
      OUTPUT_LOAD='(1.0,-1.0)';
      PINUSE='OUT';
    'MHA_DQS_L0':
      PIN_NUMBER='(0,0,0,0,0,0,0,H13,0,0,0,0,0,0,0,0,0,0,0,0,0,0,0,0,0,0,0,0,0,0~
,0,0,0,0,0,0,0,0,0,0)';
      BIDIRECTIONAL='TRUE';
      INPUT_LOAD='(-0.01,0.01)';
      OUTPUT_LOAD='(1.0,-1.0)';
      PINUSE='BI';
    'MHA_DATA24':
      PIN_NUMBER='(0,0,0,0,0,0,0,AC12,0,0,0,0,0,0,0,0,0,0,0,0,0,0,0,0,0,0,0,0,0,~
0,0,0,0,0,0,0,0,0,0,0)';
      BIDIRECTIONAL='TRUE';
      INPUT_LOAD='(-0.01,0.01)';
      OUTPUT_LOAD='(1.0,-1.0)';
      PINUSE='BI';
    'MHA_DATA13':
      PIN_NUMBER='(0,0,0,0,0,0,0,T14,0,0,0,0,0,0,0,0,0,0,0,0,0,0,0,0,0,0,0,0,0,0~
,0,0,0,0,0,0,0,0,0,0)';
      BIDIRECTIONAL='TRUE';
      INPUT_LOAD='(-0.01,0.01)';
      OUTPUT_LOAD='(1.0,-1.0)';
      PINUSE='BI';
    'MHA_CHECK4':
      PIN_NUMBER='(0,0,0,0,0,0,0,AN12,0,0,0,0,0,0,0,0,0,0,0,0,0,0,0,0,0,0,0,0,0,~
0,0,0,0,0,0,0,0,0,0,0)';
      BIDIRECTIONAL='TRUE';
      INPUT_LOAD='(-0.01,0.01)';
      OUTPUT_LOAD='(1.0,-1.0)';
      PINUSE='BI';
    'MHB_DQS_H8':
      PIN_NUMBER='(0,0,0,0,0,0,0,DD14,0,0,0,0,0,0,0,0,0,0,0,0,0,0,0,0,0,0,0,0,0,~
0,0,0,0,0,0,0,0,0,0,0)';
      BIDIRECTIONAL='TRUE';
      INPUT_LOAD='(-0.01,0.01)';
      OUTPUT_LOAD='(1.0,-1.0)';
      PINUSE='BI';
    'MHB_DATA30':
      PIN_NUMBER='(0,0,0,0,0,0,0,DE12,0,0,0,0,0,0,0,0,0,0,0,0,0,0,0,0,0,0,0,0,0,~
0,0,0,0,0,0,0,0,0,0,0)';
      BIDIRECTIONAL='TRUE';
      INPUT_LOAD='(-0.01,0.01)';
      OUTPUT_LOAD='(1.0,-1.0)';
      PINUSE='BI';
    'MHB1_CS_L0':
      PIN_NUMBER='(0,0,0,0,0,0,0,BL12,0,0,0,0,0,0,0,0,0,0,0,0,0,0,0,0,0,0,0,0,0,~
0,0,0,0,0,0,0,0,0,0,0)';
      OUTPUT_LOAD='(1.0,-1.0)';
      PINUSE='OUT';
    'MHB0_CS_L1':
      PIN_NUMBER='(0,0,0,0,0,0,0,BN12,0,0,0,0,0,0,0,0,0,0,0,0,0,0,0,0,0,0,0,0,0,~
0,0,0,0,0,0,0,0,0,0,0)';
      OUTPUT_LOAD='(1.0,-1.0)';
      PINUSE='OUT';
    'MHA_DQS_L1':
      PIN_NUMBER='(0,0,0,0,0,0,0,P13,0,0,0,0,0,0,0,0,0,0,0,0,0,0,0,0,0,0,0,0,0,0~
,0,0,0,0,0,0,0,0,0,0)';
      BIDIRECTIONAL='TRUE';
      INPUT_LOAD='(-0.01,0.01)';
      OUTPUT_LOAD='(1.0,-1.0)';
      PINUSE='BI';
    'MHA_DATA25':
      PIN_NUMBER='(0,0,0,0,0,0,0,AD14,0,0,0,0,0,0,0,0,0,0,0,0,0,0,0,0,0,0,0,0,0,~
0,0,0,0,0,0,0,0,0,0,0)';
      BIDIRECTIONAL='TRUE';
      INPUT_LOAD='(-0.01,0.01)';
      OUTPUT_LOAD='(1.0,-1.0)';
      PINUSE='BI';
    'MHA_DATA14':
      PIN_NUMBER='(0,0,0,0,0,0,0,T13,0,0,0,0,0,0,0,0,0,0,0,0,0,0,0,0,0,0,0,0,0,0~
,0,0,0,0,0,0,0,0,0,0)';
      BIDIRECTIONAL='TRUE';
      INPUT_LOAD='(-0.01,0.01)';
      OUTPUT_LOAD='(1.0,-1.0)';
      PINUSE='BI';
    'MHA_CHECK5':
      PIN_NUMBER='(0,0,0,0,0,0,0,AP14,0,0,0,0,0,0,0,0,0,0,0,0,0,0,0,0,0,0,0,0,0,~
0,0,0,0,0,0,0,0,0,0,0)';
      BIDIRECTIONAL='TRUE';
      INPUT_LOAD='(-0.01,0.01)';
      OUTPUT_LOAD='(1.0,-1.0)';
      PINUSE='BI';
    'MHB_DQS_H9':
      PIN_NUMBER='(0,0,0,0,0,0,0,BV13,0,0,0,0,0,0,0,0,0,0,0,0,0,0,0,0,0,0,0,0,0,~
0,0,0,0,0,0,0,0,0,0,0)';
      BIDIRECTIONAL='TRUE';
      INPUT_LOAD='(-0.01,0.01)';
      OUTPUT_LOAD='(1.0,-1.0)';
      PINUSE='BI';
    'MHA_PAR':
      PIN_NUMBER='(0,0,0,0,0,0,0,BC14,0,0,0,0,0,0,0,0,0,0,0,0,0,0,0,0,0,0,0,0,0,~
0,0,0,0,0,0,0,0,0,0,0)';
      OUTPUT_LOAD='(1.0,-1.0)';
      PINUSE='OUT';
    'MHB_PAR':
      PIN_NUMBER='(0,0,0,0,0,0,0,BL14,0,0,0,0,0,0,0,0,0,0,0,0,0,0,0,0,0,0,0,0,0,~
0,0,0,0,0,0,0,0,0,0,0)';
      OUTPUT_LOAD='(1.0,-1.0)';
      PINUSE='OUT';
    'MH0_CLK_H':
      PIN_NUMBER='(0,0,0,0,0,0,0,BC12,0,0,0,0,0,0,0,0,0,0,0,0,0,0,0,0,0,0,0,0,0,~
0,0,0,0,0,0,0,0,0,0,0)';
      OUTPUT_LOAD='(1.0,-1.0)';
      PINUSE='OUT';
    'MH0_CLK_L':
      PIN_NUMBER='(0,0,0,0,0,0,0,BD13,0,0,0,0,0,0,0,0,0,0,0,0,0,0,0,0,0,0,0,0,0,~
0,0,0,0,0,0,0,0,0,0,0)';
      OUTPUT_LOAD='(1.0,-1.0)';
      PINUSE='OUT';
    'MH1_CLK_H':
      PIN_NUMBER='(0,0,0,0,0,0,0,BF13,0,0,0,0,0,0,0,0,0,0,0,0,0,0,0,0,0,0,0,0,0,~
0,0,0,0,0,0,0,0,0,0,0)';
      OUTPUT_LOAD='(1.0,-1.0)';
      PINUSE='OUT';
    'MH1_CLK_L':
      PIN_NUMBER='(0,0,0,0,0,0,0,BG12,0,0,0,0,0,0,0,0,0,0,0,0,0,0,0,0,0,0,0,0,0,~
0,0,0,0,0,0,0,0,0,0,0)';
      OUTPUT_LOAD='(1.0,-1.0)';
      PINUSE='OUT';
    'TEST39H':
      PIN_NUMBER='(0,0,0,0,0,0,0,BF14,0,0,0,0,0,0,0,0,0,0,0,0,0,0,0,0,0,0,0,0,0,~
0,0,0,0,0,0,0,0,0,0,0)';
      OUTPUT_LOAD='(1.0,-1.0)';
      PINUSE='OUT';
    'MIB_DATA23':
      PIN_NUMBER='(0,0,0,0,0,0,0,0,CY21,0,0,0,0,0,0,0,0,0,0,0,0,0,0,0,0,0,0,0,0,~
0,0,0,0,0,0,0,0,0,0,0)';
      BIDIRECTIONAL='TRUE';
      INPUT_LOAD='(-0.01,0.01)';
      OUTPUT_LOAD='(1.0,-1.0)';
      PINUSE='BI';
    'MIB_DATA12':
      PIN_NUMBER='(0,0,0,0,0,0,0,0,CM20,0,0,0,0,0,0,0,0,0,0,0,0,0,0,0,0,0,0,0,0,~
0,0,0,0,0,0,0,0,0,0,0)';
      BIDIRECTIONAL='TRUE';
      INPUT_LOAD='(-0.01,0.01)';
      OUTPUT_LOAD='(1.0,-1.0)';
      PINUSE='BI';
    'MIB_DATA6':
      PIN_NUMBER='(0,0,0,0,0,0,0,0,CG19,0,0,0,0,0,0,0,0,0,0,0,0,0,0,0,0,0,0,0,0,~
0,0,0,0,0,0,0,0,0,0,0)';
      BIDIRECTIONAL='TRUE';
      INPUT_LOAD='(-0.01,0.01)';
      OUTPUT_LOAD='(1.0,-1.0)';
      PINUSE='BI';
    'MIB_CHECK3':
      PIN_NUMBER='(0,0,0,0,0,0,0,0,CB21,0,0,0,0,0,0,0,0,0,0,0,0,0,0,0,0,0,0,0,0,~
0,0,0,0,0,0,0,0,0,0,0)';
      BIDIRECTIONAL='TRUE';
      INPUT_LOAD='(-0.01,0.01)';
      OUTPUT_LOAD='(1.0,-1.0)';
      PINUSE='BI';
    'MIA_DQS_L5':
      PIN_NUMBER='(0,0,0,0,0,0,0,0,H21,0,0,0,0,0,0,0,0,0,0,0,0,0,0,0,0,0,0,0,0,0~
,0,0,0,0,0,0,0,0,0,0)';
      BIDIRECTIONAL='TRUE';
      INPUT_LOAD='(-0.01,0.01)';
      OUTPUT_LOAD='(1.0,-1.0)';
      PINUSE='BI';
    'MIA_DQS_H1':
      PIN_NUMBER='(0,0,0,0,0,0,0,0,N19,0,0,0,0,0,0,0,0,0,0,0,0,0,0,0,0,0,0,0,0,0~
,0,0,0,0,0,0,0,0,0,0)';
      BIDIRECTIONAL='TRUE';
      INPUT_LOAD='(-0.01,0.01)';
      OUTPUT_LOAD='(1.0,-1.0)';
      PINUSE='BI';
    'MIA_DATA29':
      PIN_NUMBER='(0,0,0,0,0,0,0,0,AH21,0,0,0,0,0,0,0,0,0,0,0,0,0,0,0,0,0,0,0,0,~
0,0,0,0,0,0,0,0,0,0,0)';
      BIDIRECTIONAL='TRUE';
      INPUT_LOAD='(-0.01,0.01)';
      OUTPUT_LOAD='(1.0,-1.0)';
      PINUSE='BI';
    'MIA_DATA18':
      PIN_NUMBER='(0,0,0,0,0,0,0,0,V20,0,0,0,0,0,0,0,0,0,0,0,0,0,0,0,0,0,0,0,0,0~
,0,0,0,0,0,0,0,0,0,0)';
      BIDIRECTIONAL='TRUE';
      INPUT_LOAD='(-0.01,0.01)';
      OUTPUT_LOAD='(1.0,-1.0)';
      PINUSE='BI';
    'MIA_DATA6':
      PIN_NUMBER='(0,0,0,0,0,0,0,0,K20,0,0,0,0,0,0,0,0,0,0,0,0,0,0,0,0,0,0,0,0,0~
,0,0,0,0,0,0,0,0,0,0)';
      BIDIRECTIONAL='TRUE';
      INPUT_LOAD='(-0.01,0.01)';
      OUTPUT_LOAD='(1.0,-1.0)';
      PINUSE='BI';
    'MIB_DQS_L0':
      PIN_NUMBER='(0,0,0,0,0,0,0,0,CE19,0,0,0,0,0,0,0,0,0,0,0,0,0,0,0,0,0,0,0,0,~
0,0,0,0,0,0,0,0,0,0,0)';
      BIDIRECTIONAL='TRUE';
      INPUT_LOAD='(-0.01,0.01)';
      OUTPUT_LOAD='(1.0,-1.0)';
      PINUSE='BI';
    'MIB_DATA24':
      PIN_NUMBER='(0,0,0,0,0,0,0,0,CY20,0,0,0,0,0,0,0,0,0,0,0,0,0,0,0,0,0,0,0,0,~
0,0,0,0,0,0,0,0,0,0,0)';
      BIDIRECTIONAL='TRUE';
      INPUT_LOAD='(-0.01,0.01)';
      OUTPUT_LOAD='(1.0,-1.0)';
      PINUSE='BI';
    'MIB_DATA13':
      PIN_NUMBER='(0,0,0,0,0,0,0,0,CN21,0,0,0,0,0,0,0,0,0,0,0,0,0,0,0,0,0,0,0,0,~
0,0,0,0,0,0,0,0,0,0,0)';
      BIDIRECTIONAL='TRUE';
      INPUT_LOAD='(-0.01,0.01)';
      OUTPUT_LOAD='(1.0,-1.0)';
      PINUSE='BI';
    'MIB_DATA7':
      PIN_NUMBER='(0,0,0,0,0,0,0,0,CH21,0,0,0,0,0,0,0,0,0,0,0,0,0,0,0,0,0,0,0,0,~
0,0,0,0,0,0,0,0,0,0,0)';
      BIDIRECTIONAL='TRUE';
      INPUT_LOAD='(-0.01,0.01)';
      OUTPUT_LOAD='(1.0,-1.0)';
      PINUSE='BI';
    'MIB_CHECK4':
      PIN_NUMBER='(0,0,0,0,0,0,0,0,BT20,0,0,0,0,0,0,0,0,0,0,0,0,0,0,0,0,0,0,0,0,~
0,0,0,0,0,0,0,0,0,0,0)';
      BIDIRECTIONAL='TRUE';
      INPUT_LOAD='(-0.01,0.01)';
      OUTPUT_LOAD='(1.0,-1.0)';
      PINUSE='BI';
    'MIA_DQS_L6':
      PIN_NUMBER='(0,0,0,0,0,0,0,0,P21,0,0,0,0,0,0,0,0,0,0,0,0,0,0,0,0,0,0,0,0,0~
,0,0,0,0,0,0,0,0,0,0)';
      BIDIRECTIONAL='TRUE';
      INPUT_LOAD='(-0.01,0.01)';
      OUTPUT_LOAD='(1.0,-1.0)';
      PINUSE='BI';
    'MIA_DQS_H2':
      PIN_NUMBER='(0,0,0,0,0,0,0,0,W19,0,0,0,0,0,0,0,0,0,0,0,0,0,0,0,0,0,0,0,0,0~
,0,0,0,0,0,0,0,0,0,0)';
      BIDIRECTIONAL='TRUE';
      INPUT_LOAD='(-0.01,0.01)';
      OUTPUT_LOAD='(1.0,-1.0)';
      PINUSE='BI';
    'MIA_DATA19':
      PIN_NUMBER='(0,0,0,0,0,0,0,0,W21,0,0,0,0,0,0,0,0,0,0,0,0,0,0,0,0,0,0,0,0,0~
,0,0,0,0,0,0,0,0,0,0)';
      BIDIRECTIONAL='TRUE';
      INPUT_LOAD='(-0.01,0.01)';
      OUTPUT_LOAD='(1.0,-1.0)';
      PINUSE='BI';
    'MIA_DATA7':
      PIN_NUMBER='(0,0,0,0,0,0,0,0,L21,0,0,0,0,0,0,0,0,0,0,0,0,0,0,0,0,0,0,0,0,0~
,0,0,0,0,0,0,0,0,0,0)';
      BIDIRECTIONAL='TRUE';
      INPUT_LOAD='(-0.01,0.01)';
      OUTPUT_LOAD='(1.0,-1.0)';
      PINUSE='BI';
    'MIA_CA0':
      PIN_NUMBER='(0,0,0,0,0,0,0,0,AW19,0,0,0,0,0,0,0,0,0,0,0,0,0,0,0,0,0,0,0,0,~
0,0,0,0,0,0,0,0,0,0,0)';
      OUTPUT_LOAD='(1.0,-1.0)';
      PINUSE='OUT';
    'MIB_DQS_L1':
      PIN_NUMBER='(0,0,0,0,0,0,0,0,CL19,0,0,0,0,0,0,0,0,0,0,0,0,0,0,0,0,0,0,0,0,~
0,0,0,0,0,0,0,0,0,0,0)';
      BIDIRECTIONAL='TRUE';
      INPUT_LOAD='(-0.01,0.01)';
      OUTPUT_LOAD='(1.0,-1.0)';
      PINUSE='BI';
    'MIB_DATA25':
      PIN_NUMBER='(0,0,0,0,0,0,0,0,DA21,0,0,0,0,0,0,0,0,0,0,0,0,0,0,0,0,0,0,0,0,~
0,0,0,0,0,0,0,0,0,0,0)';
      BIDIRECTIONAL='TRUE';
      INPUT_LOAD='(-0.01,0.01)';
      OUTPUT_LOAD='(1.0,-1.0)';
      PINUSE='BI';
    'MIB_DATA14':
      PIN_NUMBER='(0,0,0,0,0,0,0,0,CN19,0,0,0,0,0,0,0,0,0,0,0,0,0,0,0,0,0,0,0,0,~
0,0,0,0,0,0,0,0,0,0,0)';
      BIDIRECTIONAL='TRUE';
      INPUT_LOAD='(-0.01,0.01)';
      OUTPUT_LOAD='(1.0,-1.0)';
      PINUSE='BI';
    'MIB_DATA8':
      PIN_NUMBER='(0,0,0,0,0,0,0,0,CH20,0,0,0,0,0,0,0,0,0,0,0,0,0,0,0,0,0,0,0,0,~
0,0,0,0,0,0,0,0,0,0,0)';
      BIDIRECTIONAL='TRUE';
      INPUT_LOAD='(-0.01,0.01)';
      OUTPUT_LOAD='(1.0,-1.0)';
      PINUSE='BI';
    'MIB_CHECK5':
      PIN_NUMBER='(0,0,0,0,0,0,0,0,BU21,0,0,0,0,0,0,0,0,0,0,0,0,0,0,0,0,0,0,0,0,~
0,0,0,0,0,0,0,0,0,0,0)';
      BIDIRECTIONAL='TRUE';
      INPUT_LOAD='(-0.01,0.01)';
      OUTPUT_LOAD='(1.0,-1.0)';
      PINUSE='BI';
    'MIB_CA0':
      PIN_NUMBER='(0,0,0,0,0,0,0,0,BG21,0,0,0,0,0,0,0,0,0,0,0,0,0,0,0,0,0,0,0,0,~
0,0,0,0,0,0,0,0,0,0,0)';
      OUTPUT_LOAD='(1.0,-1.0)';
      PINUSE='OUT';
    'MIA_DQS_L7':
      PIN_NUMBER='(0,0,0,0,0,0,0,0,Y21,0,0,0,0,0,0,0,0,0,0,0,0,0,0,0,0,0,0,0,0,0~
,0,0,0,0,0,0,0,0,0,0)';
      BIDIRECTIONAL='TRUE';
      INPUT_LOAD='(-0.01,0.01)';
      OUTPUT_LOAD='(1.0,-1.0)';
      PINUSE='BI';
    'MIA_DQS_H3':
      PIN_NUMBER='(0,0,0,0,0,0,0,0,AE19,0,0,0,0,0,0,0,0,0,0,0,0,0,0,0,0,0,0,0,0,~
0,0,0,0,0,0,0,0,0,0,0)';
      BIDIRECTIONAL='TRUE';
      INPUT_LOAD='(-0.01,0.01)';
      OUTPUT_LOAD='(1.0,-1.0)';
      PINUSE='BI';
    'MIA_DATA8':
      PIN_NUMBER='(0,0,0,0,0,0,0,0,L19,0,0,0,0,0,0,0,0,0,0,0,0,0,0,0,0,0,0,0,0,0~
,0,0,0,0,0,0,0,0,0,0)';
      BIDIRECTIONAL='TRUE';
      INPUT_LOAD='(-0.01,0.01)';
      OUTPUT_LOAD='(1.0,-1.0)';
      PINUSE='BI';
    'MIA_CA1':
      PIN_NUMBER='(0,0,0,0,0,0,0,0,AY20,0,0,0,0,0,0,0,0,0,0,0,0,0,0,0,0,0,0,0,0,~
0,0,0,0,0,0,0,0,0,0,0)';
      OUTPUT_LOAD='(1.0,-1.0)';
      PINUSE='OUT';
    'MIB_DQS_L2':
      PIN_NUMBER='(0,0,0,0,0,0,0,0,CU19,0,0,0,0,0,0,0,0,0,0,0,0,0,0,0,0,0,0,0,0,~
0,0,0,0,0,0,0,0,0,0,0)';
      BIDIRECTIONAL='TRUE';
      INPUT_LOAD='(-0.01,0.01)';
      OUTPUT_LOAD='(1.0,-1.0)';
      PINUSE='BI';
    'MIB_DATA26':
      PIN_NUMBER='(0,0,0,0,0,0,0,0,DA19,0,0,0,0,0,0,0,0,0,0,0,0,0,0,0,0,0,0,0,0,~
0,0,0,0,0,0,0,0,0,0,0)';
      BIDIRECTIONAL='TRUE';
      INPUT_LOAD='(-0.01,0.01)';
      OUTPUT_LOAD='(1.0,-1.0)';
      PINUSE='BI';
    'MIB_DATA15':
      PIN_NUMBER='(0,0,0,0,0,0,0,0,CP21,0,0,0,0,0,0,0,0,0,0,0,0,0,0,0,0,0,0,0,0,~
0,0,0,0,0,0,0,0,0,0,0)';
      BIDIRECTIONAL='TRUE';
      INPUT_LOAD='(-0.01,0.01)';
      OUTPUT_LOAD='(1.0,-1.0)';
      PINUSE='BI';
    'MIB_DATA9':
      PIN_NUMBER='(0,0,0,0,0,0,0,0,CJ21,0,0,0,0,0,0,0,0,0,0,0,0,0,0,0,0,0,0,0,0,~
0,0,0,0,0,0,0,0,0,0,0)';
      BIDIRECTIONAL='TRUE';
      INPUT_LOAD='(-0.01,0.01)';
      OUTPUT_LOAD='(1.0,-1.0)';
      PINUSE='BI';
    'MIB_CHECK6':
      PIN_NUMBER='(0,0,0,0,0,0,0,0,BU19,0,0,0,0,0,0,0,0,0,0,0,0,0,0,0,0,0,0,0,0,~
0,0,0,0,0,0,0,0,0,0,0)';
      BIDIRECTIONAL='TRUE';
      INPUT_LOAD='(-0.01,0.01)';
      OUTPUT_LOAD='(1.0,-1.0)';
      PINUSE='BI';
    'MIB_CA1':
      PIN_NUMBER='(0,0,0,0,0,0,0,0,BH21,0,0,0,0,0,0,0,0,0,0,0,0,0,0,0,0,0,0,0,0,~
0,0,0,0,0,0,0,0,0,0,0)';
      OUTPUT_LOAD='(1.0,-1.0)';
      PINUSE='OUT';
    'MIA_DQS_L8':
      PIN_NUMBER='(0,0,0,0,0,0,0,0,AF21,0,0,0,0,0,0,0,0,0,0,0,0,0,0,0,0,0,0,0,0,~
0,0,0,0,0,0,0,0,0,0,0)';
      BIDIRECTIONAL='TRUE';
      INPUT_LOAD='(-0.01,0.01)';
      OUTPUT_LOAD='(1.0,-1.0)';
      PINUSE='BI';
    'MIA_DQS_H4':
      PIN_NUMBER='(0,0,0,0,0,0,0,0,AL19,0,0,0,0,0,0,0,0,0,0,0,0,0,0,0,0,0,0,0,0,~
0,0,0,0,0,0,0,0,0,0,0)';
      BIDIRECTIONAL='TRUE';
      INPUT_LOAD='(-0.01,0.01)';
      OUTPUT_LOAD='(1.0,-1.0)';
      PINUSE='BI';
    'MIA_DATA9':
      PIN_NUMBER='(0,0,0,0,0,0,0,0,M21,0,0,0,0,0,0,0,0,0,0,0,0,0,0,0,0,0,0,0,0,0~
,0,0,0,0,0,0,0,0,0,0)';
      BIDIRECTIONAL='TRUE';
      INPUT_LOAD='(-0.01,0.01)';
      OUTPUT_LOAD='(1.0,-1.0)';
      PINUSE='BI';
    'MIA_CA2':
      PIN_NUMBER='(0,0,0,0,0,0,0,0,AY21,0,0,0,0,0,0,0,0,0,0,0,0,0,0,0,0,0,0,0,0,~
0,0,0,0,0,0,0,0,0,0,0)';
      OUTPUT_LOAD='(1.0,-1.0)';
      PINUSE='OUT';
    'MIB_DQS_L3':
      PIN_NUMBER='(0,0,0,0,0,0,0,0,DC19,0,0,0,0,0,0,0,0,0,0,0,0,0,0,0,0,0,0,0,0,~
0,0,0,0,0,0,0,0,0,0,0)';
      BIDIRECTIONAL='TRUE';
      INPUT_LOAD='(-0.01,0.01)';
      OUTPUT_LOAD='(1.0,-1.0)';
      PINUSE='BI';
    'MIB_DATA27':
      PIN_NUMBER='(0,0,0,0,0,0,0,0,DB21,0,0,0,0,0,0,0,0,0,0,0,0,0,0,0,0,0,0,0,0,~
0,0,0,0,0,0,0,0,0,0,0)';
      BIDIRECTIONAL='TRUE';
      INPUT_LOAD='(-0.01,0.01)';
      OUTPUT_LOAD='(1.0,-1.0)';
      PINUSE='BI';
    'MIB_DATA16':
      PIN_NUMBER='(0,0,0,0,0,0,0,0,CP20,0,0,0,0,0,0,0,0,0,0,0,0,0,0,0,0,0,0,0,0,~
0,0,0,0,0,0,0,0,0,0,0)';
      BIDIRECTIONAL='TRUE';
      INPUT_LOAD='(-0.01,0.01)';
      OUTPUT_LOAD='(1.0,-1.0)';
      PINUSE='BI';
    'MIB_CHECK7':
      PIN_NUMBER='(0,0,0,0,0,0,0,0,BV21,0,0,0,0,0,0,0,0,0,0,0,0,0,0,0,0,0,0,0,0,~
0,0,0,0,0,0,0,0,0,0,0)';
      BIDIRECTIONAL='TRUE';
      INPUT_LOAD='(-0.01,0.01)';
      OUTPUT_LOAD='(1.0,-1.0)';
      PINUSE='BI';
    'MIB_CA2':
      PIN_NUMBER='(0,0,0,0,0,0,0,0,BH20,0,0,0,0,0,0,0,0,0,0,0,0,0,0,0,0,0,0,0,0,~
0,0,0,0,0,0,0,0,0,0,0)';
      OUTPUT_LOAD='(1.0,-1.0)';
      PINUSE='OUT';
    'MIB0_RSP_L':
      PIN_NUMBER='(0,0,0,0,0,0,0,0,BP20,0,0,0,0,0,0,0,0,0,0,0,0,0,0,0,0,0,0,0,0,~
0,0,0,0,0,0,0,0,0,0,0)';
      INPUT_LOAD='(-0.01,0.01)';
      PINUSE='IN';
    'MIA_DQS_L9':
      PIN_NUMBER='(0,0,0,0,0,0,0,0,AM21,0,0,0,0,0,0,0,0,0,0,0,0,0,0,0,0,0,0,0,0,~
0,0,0,0,0,0,0,0,0,0,0)';
      BIDIRECTIONAL='TRUE';
      INPUT_LOAD='(-0.01,0.01)';
      OUTPUT_LOAD='(1.0,-1.0)';
      PINUSE='BI';
    'MIA_DQS_H5':
      PIN_NUMBER='(0,0,0,0,0,0,0,0,J21,0,0,0,0,0,0,0,0,0,0,0,0,0,0,0,0,0,0,0,0,0~
,0,0,0,0,0,0,0,0,0,0)';
      BIDIRECTIONAL='TRUE';
      INPUT_LOAD='(-0.01,0.01)';
      OUTPUT_LOAD='(1.0,-1.0)';
      PINUSE='BI';
    'MIA_CA3':
      PIN_NUMBER='(0,0,0,0,0,0,0,0,BA21,0,0,0,0,0,0,0,0,0,0,0,0,0,0,0,0,0,0,0,0,~
0,0,0,0,0,0,0,0,0,0,0)';
      OUTPUT_LOAD='(1.0,-1.0)';
      PINUSE='OUT';
    'MIB_DQS_L4':
      PIN_NUMBER='(0,0,0,0,0,0,0,0,BW21,0,0,0,0,0,0,0,0,0,0,0,0,0,0,0,0,0,0,0,0,~
0,0,0,0,0,0,0,0,0,0,0)';
      BIDIRECTIONAL='TRUE';
      INPUT_LOAD='(-0.01,0.01)';
      OUTPUT_LOAD='(1.0,-1.0)';
      PINUSE='BI';
    'MIB_DQS_H0':
      PIN_NUMBER='(0,0,0,0,0,0,0,0,CD20,0,0,0,0,0,0,0,0,0,0,0,0,0,0,0,0,0,0,0,0,~
0,0,0,0,0,0,0,0,0,0,0)';
      BIDIRECTIONAL='TRUE';
      INPUT_LOAD='(-0.01,0.01)';
      OUTPUT_LOAD='(1.0,-1.0)';
      PINUSE='BI';
    'MIB_DATA28':
      PIN_NUMBER='(0,0,0,0,0,0,0,0,DD20,0,0,0,0,0,0,0,0,0,0,0,0,0,0,0,0,0,0,0,0,~
0,0,0,0,0,0,0,0,0,0,0)';
      BIDIRECTIONAL='TRUE';
      INPUT_LOAD='(-0.01,0.01)';
      OUTPUT_LOAD='(1.0,-1.0)';
      PINUSE='BI';
    'MIB_DATA17':
      PIN_NUMBER='(0,0,0,0,0,0,0,0,CR21,0,0,0,0,0,0,0,0,0,0,0,0,0,0,0,0,0,0,0,0,~
0,0,0,0,0,0,0,0,0,0,0)';
      BIDIRECTIONAL='TRUE';
      INPUT_LOAD='(-0.01,0.01)';
      OUTPUT_LOAD='(1.0,-1.0)';
      PINUSE='BI';
    'MIB_CA3':
      PIN_NUMBER='(0,0,0,0,0,0,0,0,BJ19,0,0,0,0,0,0,0,0,0,0,0,0,0,0,0,0,0,0,0,0,~
0,0,0,0,0,0,0,0,0,0,0)';
      OUTPUT_LOAD='(1.0,-1.0)';
      PINUSE='OUT';
    'MIB1_RSP_L':
      PIN_NUMBER='(0,0,0,0,0,0,0,0,BR19,0,0,0,0,0,0,0,0,0,0,0,0,0,0,0,0,0,0,0,0,~
0,0,0,0,0,0,0,0,0,0,0)';
      INPUT_LOAD='(-0.01,0.01)';
      PINUSE='IN';
    'MIA_DQS_H6':
      PIN_NUMBER='(0,0,0,0,0,0,0,0,R21,0,0,0,0,0,0,0,0,0,0,0,0,0,0,0,0,0,0,0,0,0~
,0,0,0,0,0,0,0,0,0,0)';
      BIDIRECTIONAL='TRUE';
      INPUT_LOAD='(-0.01,0.01)';
      OUTPUT_LOAD='(1.0,-1.0)';
      PINUSE='BI';
    'MIA_CA4':
      PIN_NUMBER='(0,0,0,0,0,0,0,0,BA19,0,0,0,0,0,0,0,0,0,0,0,0,0,0,0,0,0,0,0,0,~
0,0,0,0,0,0,0,0,0,0,0)';
      OUTPUT_LOAD='(1.0,-1.0)';
      PINUSE='OUT';
    'MIB_DQS_L5':
      PIN_NUMBER='(0,0,0,0,0,0,0,0,CE21,0,0,0,0,0,0,0,0,0,0,0,0,0,0,0,0,0,0,0,0,~
0,0,0,0,0,0,0,0,0,0,0)';
      BIDIRECTIONAL='TRUE';
      INPUT_LOAD='(-0.01,0.01)';
      OUTPUT_LOAD='(1.0,-1.0)';
      PINUSE='BI';
    'MIB_DQS_H1':
      PIN_NUMBER='(0,0,0,0,0,0,0,0,CK20,0,0,0,0,0,0,0,0,0,0,0,0,0,0,0,0,0,0,0,0,~
0,0,0,0,0,0,0,0,0,0,0)';
      BIDIRECTIONAL='TRUE';
      INPUT_LOAD='(-0.01,0.01)';
      OUTPUT_LOAD='(1.0,-1.0)';
      PINUSE='BI';
    'MIB_DATA29':
      PIN_NUMBER='(0,0,0,0,0,0,0,0,DE21,0,0,0,0,0,0,0,0,0,0,0,0,0,0,0,0,0,0,0,0,~
0,0,0,0,0,0,0,0,0,0,0)';
      BIDIRECTIONAL='TRUE';
      INPUT_LOAD='(-0.01,0.01)';
      OUTPUT_LOAD='(1.0,-1.0)';
      PINUSE='BI';
    'MIB_DATA18':
      PIN_NUMBER='(0,0,0,0,0,0,0,0,CR19,0,0,0,0,0,0,0,0,0,0,0,0,0,0,0,0,0,0,0,0,~
0,0,0,0,0,0,0,0,0,0,0)';
      BIDIRECTIONAL='TRUE';
      INPUT_LOAD='(-0.01,0.01)';
      OUTPUT_LOAD='(1.0,-1.0)';
      PINUSE='BI';
    'MIB_CA4':
      PIN_NUMBER='(0,0,0,0,0,0,0,0,BJ21,0,0,0,0,0,0,0,0,0,0,0,0,0,0,0,0,0,0,0,0,~
0,0,0,0,0,0,0,0,0,0,0)';
      OUTPUT_LOAD='(1.0,-1.0)';
      PINUSE='OUT';
    'MIA_DQS_H7':
      PIN_NUMBER='(0,0,0,0,0,0,0,0,AA21,0,0,0,0,0,0,0,0,0,0,0,0,0,0,0,0,0,0,0,0,~
0,0,0,0,0,0,0,0,0,0,0)';
      BIDIRECTIONAL='TRUE';
      INPUT_LOAD='(-0.01,0.01)';
      OUTPUT_LOAD='(1.0,-1.0)';
      PINUSE='BI';
    'MIA_CA5':
      PIN_NUMBER='(0,0,0,0,0,0,0,0,BB20,0,0,0,0,0,0,0,0,0,0,0,0,0,0,0,0,0,0,0,0,~
0,0,0,0,0,0,0,0,0,0,0)';
      OUTPUT_LOAD='(1.0,-1.0)';
      PINUSE='OUT';
    'MIA1_CS_L0':
      PIN_NUMBER='(0,0,0,0,0,0,0,0,AV20,0,0,0,0,0,0,0,0,0,0,0,0,0,0,0,0,0,0,0,0,~
0,0,0,0,0,0,0,0,0,0,0)';
      OUTPUT_LOAD='(1.0,-1.0)';
      PINUSE='OUT';
    'MIA0_CS_L0':
      PIN_NUMBER='(0,0,0,0,0,0,0,0,AU19,0,0,0,0,0,0,0,0,0,0,0,0,0,0,0,0,0,0,0,0,~
0,0,0,0,0,0,0,0,0,0,0)';
      OUTPUT_LOAD='(1.0,-1.0)';
      PINUSE='OUT';
    'MI1_CLK_H':
      PIN_NUMBER='(0,0,0,0,0,0,0,0,BF20,0,0,0,0,0,0,0,0,0,0,0,0,0,0,0,0,0,0,0,0,~
0,0,0,0,0,0,0,0,0,0,0)';
      OUTPUT_LOAD='(1.0,-1.0)';
      PINUSE='OUT';
    'MI0_CLK_H':
      PIN_NUMBER='(0,0,0,0,0,0,0,0,BC19,0,0,0,0,0,0,0,0,0,0,0,0,0,0,0,0,0,0,0,0,~
0,0,0,0,0,0,0,0,0,0,0)';
      OUTPUT_LOAD='(1.0,-1.0)';
      PINUSE='OUT';
    'MIB_DQS_L6':
      PIN_NUMBER='(0,0,0,0,0,0,0,0,CL21,0,0,0,0,0,0,0,0,0,0,0,0,0,0,0,0,0,0,0,0,~
0,0,0,0,0,0,0,0,0,0,0)';
      BIDIRECTIONAL='TRUE';
      INPUT_LOAD='(-0.01,0.01)';
      OUTPUT_LOAD='(1.0,-1.0)';
      PINUSE='BI';
    'MIB_DQS_H2':
      PIN_NUMBER='(0,0,0,0,0,0,0,0,CT20,0,0,0,0,0,0,0,0,0,0,0,0,0,0,0,0,0,0,0,0,~
0,0,0,0,0,0,0,0,0,0,0)';
      BIDIRECTIONAL='TRUE';
      INPUT_LOAD='(-0.01,0.01)';
      OUTPUT_LOAD='(1.0,-1.0)';
      PINUSE='BI';
    'MIB_DATA19':
      PIN_NUMBER='(0,0,0,0,0,0,0,0,CT21,0,0,0,0,0,0,0,0,0,0,0,0,0,0,0,0,0,0,0,0,~
0,0,0,0,0,0,0,0,0,0,0)';
      BIDIRECTIONAL='TRUE';
      INPUT_LOAD='(-0.01,0.01)';
      OUTPUT_LOAD='(1.0,-1.0)';
      PINUSE='BI';
    'MIB_CA5':
      PIN_NUMBER='(0,0,0,0,0,0,0,0,BK21,0,0,0,0,0,0,0,0,0,0,0,0,0,0,0,0,0,0,0,0,~
0,0,0,0,0,0,0,0,0,0,0)';
      OUTPUT_LOAD='(1.0,-1.0)';
      PINUSE='OUT';
    'MIA_DQS_H8':
      PIN_NUMBER='(0,0,0,0,0,0,0,0,AG21,0,0,0,0,0,0,0,0,0,0,0,0,0,0,0,0,0,0,0,0,~
0,0,0,0,0,0,0,0,0,0,0)';
      BIDIRECTIONAL='TRUE';
      INPUT_LOAD='(-0.01,0.01)';
      OUTPUT_LOAD='(1.0,-1.0)';
      PINUSE='BI';
    'MIA_DATA30':
      PIN_NUMBER='(0,0,0,0,0,0,0,0,AH20,0,0,0,0,0,0,0,0,0,0,0,0,0,0,0,0,0,0,0,0,~
0,0,0,0,0,0,0,0,0,0,0)';
      BIDIRECTIONAL='TRUE';
      INPUT_LOAD='(-0.01,0.01)';
      OUTPUT_LOAD='(1.0,-1.0)';
      PINUSE='BI';
    'MIA_CA6':
      PIN_NUMBER='(0,0,0,0,0,0,0,0,BB21,0,0,0,0,0,0,0,0,0,0,0,0,0,0,0,0,0,0,0,0,~
0,0,0,0,0,0,0,0,0,0,0)';
      OUTPUT_LOAD='(1.0,-1.0)';
      PINUSE='OUT';
    'MIA1_CS_L1':
      PIN_NUMBER='(0,0,0,0,0,0,0,0,AW21,0,0,0,0,0,0,0,0,0,0,0,0,0,0,0,0,0,0,0,0,~
0,0,0,0,0,0,0,0,0,0,0)';
      OUTPUT_LOAD='(1.0,-1.0)';
      PINUSE='OUT';
    'MIA0_CS_L1':
      PIN_NUMBER='(0,0,0,0,0,0,0,0,AV21,0,0,0,0,0,0,0,0,0,0,0,0,0,0,0,0,0,0,0,0,~
0,0,0,0,0,0,0,0,0,0,0)';
      OUTPUT_LOAD='(1.0,-1.0)';
      PINUSE='OUT';
    'MIB_DQS_L7':
      PIN_NUMBER='(0,0,0,0,0,0,0,0,CU21,0,0,0,0,0,0,0,0,0,0,0,0,0,0,0,0,0,0,0,0,~
0,0,0,0,0,0,0,0,0,0,0)';
      BIDIRECTIONAL='TRUE';
      INPUT_LOAD='(-0.01,0.01)';
      OUTPUT_LOAD='(1.0,-1.0)';
      PINUSE='BI';
    'MIB_DQS_H3':
      PIN_NUMBER='(0,0,0,0,0,0,0,0,DB20,0,0,0,0,0,0,0,0,0,0,0,0,0,0,0,0,0,0,0,0,~
0,0,0,0,0,0,0,0,0,0,0)';
      BIDIRECTIONAL='TRUE';
      INPUT_LOAD='(-0.01,0.01)';
      OUTPUT_LOAD='(1.0,-1.0)';
      PINUSE='BI';
    'MIB_CA6':
      PIN_NUMBER='(0,0,0,0,0,0,0,0,BK20,0,0,0,0,0,0,0,0,0,0,0,0,0,0,0,0,0,0,0,0,~
0,0,0,0,0,0,0,0,0,0,0)';
      OUTPUT_LOAD='(1.0,-1.0)';
      PINUSE='OUT';
    'MIA_DQS_H9':
      PIN_NUMBER='(0,0,0,0,0,0,0,0,AN21,0,0,0,0,0,0,0,0,0,0,0,0,0,0,0,0,0,0,0,0,~
0,0,0,0,0,0,0,0,0,0,0)';
      BIDIRECTIONAL='TRUE';
      INPUT_LOAD='(-0.01,0.01)';
      OUTPUT_LOAD='(1.0,-1.0)';
      PINUSE='BI';
    'MIA_DATA31':
      PIN_NUMBER='(0,0,0,0,0,0,0,0,AJ21,0,0,0,0,0,0,0,0,0,0,0,0,0,0,0,0,0,0,0,0,~
0,0,0,0,0,0,0,0,0,0,0)';
      BIDIRECTIONAL='TRUE';
      INPUT_LOAD='(-0.01,0.01)';
      OUTPUT_LOAD='(1.0,-1.0)';
      PINUSE='BI';
    'MIA_DATA20':
      PIN_NUMBER='(0,0,0,0,0,0,0,0,AA19,0,0,0,0,0,0,0,0,0,0,0,0,0,0,0,0,0,0,0,0,~
0,0,0,0,0,0,0,0,0,0,0)';
      BIDIRECTIONAL='TRUE';
      INPUT_LOAD='(-0.01,0.01)';
      OUTPUT_LOAD='(1.0,-1.0)';
      PINUSE='BI';
    'MIA_CHECK0':
      PIN_NUMBER='(0,0,0,0,0,0,0,0,AJ19,0,0,0,0,0,0,0,0,0,0,0,0,0,0,0,0,0,0,0,0,~
0,0,0,0,0,0,0,0,0,0,0)';
      BIDIRECTIONAL='TRUE';
      INPUT_LOAD='(-0.01,0.01)';
      OUTPUT_LOAD='(1.0,-1.0)';
      PINUSE='BI';
    'MIB_DQS_L8':
      PIN_NUMBER='(0,0,0,0,0,0,0,0,DC21,0,0,0,0,0,0,0,0,0,0,0,0,0,0,0,0,0,0,0,0,~
0,0,0,0,0,0,0,0,0,0,0)';
      BIDIRECTIONAL='TRUE';
      INPUT_LOAD='(-0.01,0.01)';
      OUTPUT_LOAD='(1.0,-1.0)';
      PINUSE='BI';
    'MIB_DQS_H4':
      PIN_NUMBER='(0,0,0,0,0,0,0,0,BY21,0,0,0,0,0,0,0,0,0,0,0,0,0,0,0,0,0,0,0,0,~
0,0,0,0,0,0,0,0,0,0,0)';
      BIDIRECTIONAL='TRUE';
      INPUT_LOAD='(-0.01,0.01)';
      OUTPUT_LOAD='(1.0,-1.0)';
      PINUSE='BI';
    'MIA_DATA21':
      PIN_NUMBER='(0,0,0,0,0,0,0,0,AB21,0,0,0,0,0,0,0,0,0,0,0,0,0,0,0,0,0,0,0,0,~
0,0,0,0,0,0,0,0,0,0,0)';
      BIDIRECTIONAL='TRUE';
      INPUT_LOAD='(-0.01,0.01)';
      OUTPUT_LOAD='(1.0,-1.0)';
      PINUSE='BI';
    'MIA_DATA10':
      PIN_NUMBER='(0,0,0,0,0,0,0,0,M20,0,0,0,0,0,0,0,0,0,0,0,0,0,0,0,0,0,0,0,0,0~
,0,0,0,0,0,0,0,0,0,0)';
      BIDIRECTIONAL='TRUE';
      INPUT_LOAD='(-0.01,0.01)';
      OUTPUT_LOAD='(1.0,-1.0)';
      PINUSE='BI';
    'MIA_CHECK1':
      PIN_NUMBER='(0,0,0,0,0,0,0,0,AK21,0,0,0,0,0,0,0,0,0,0,0,0,0,0,0,0,0,0,0,0,~
0,0,0,0,0,0,0,0,0,0,0)';
      BIDIRECTIONAL='TRUE';
      INPUT_LOAD='(-0.01,0.01)';
      OUTPUT_LOAD='(1.0,-1.0)';
      PINUSE='BI';
    'MIB_DQS_L9':
      PIN_NUMBER='(0,0,0,0,0,0,0,0,BW19,0,0,0,0,0,0,0,0,0,0,0,0,0,0,0,0,0,0,0,0,~
0,0,0,0,0,0,0,0,0,0,0)';
      BIDIRECTIONAL='TRUE';
      INPUT_LOAD='(-0.01,0.01)';
      OUTPUT_LOAD='(1.0,-1.0)';
      PINUSE='BI';
    'MIB_DQS_H5':
      PIN_NUMBER='(0,0,0,0,0,0,0,0,CF21,0,0,0,0,0,0,0,0,0,0,0,0,0,0,0,0,0,0,0,0,~
0,0,0,0,0,0,0,0,0,0,0)';
      BIDIRECTIONAL='TRUE';
      INPUT_LOAD='(-0.01,0.01)';
      OUTPUT_LOAD='(1.0,-1.0)';
      PINUSE='BI';
    'MIA_DATA22':
      PIN_NUMBER='(0,0,0,0,0,0,0,0,AB20,0,0,0,0,0,0,0,0,0,0,0,0,0,0,0,0,0,0,0,0,~
0,0,0,0,0,0,0,0,0,0,0)';
      BIDIRECTIONAL='TRUE';
      INPUT_LOAD='(-0.01,0.01)';
      OUTPUT_LOAD='(1.0,-1.0)';
      PINUSE='BI';
    'MIA_DATA11':
      PIN_NUMBER='(0,0,0,0,0,0,0,0,N21,0,0,0,0,0,0,0,0,0,0,0,0,0,0,0,0,0,0,0,0,0~
,0,0,0,0,0,0,0,0,0,0)';
      BIDIRECTIONAL='TRUE';
      INPUT_LOAD='(-0.01,0.01)';
      OUTPUT_LOAD='(1.0,-1.0)';
      PINUSE='BI';
    'MIA_CHECK2':
      PIN_NUMBER='(0,0,0,0,0,0,0,0,AK20,0,0,0,0,0,0,0,0,0,0,0,0,0,0,0,0,0,0,0,0,~
0,0,0,0,0,0,0,0,0,0,0)';
      BIDIRECTIONAL='TRUE';
      INPUT_LOAD='(-0.01,0.01)';
      OUTPUT_LOAD='(1.0,-1.0)';
      PINUSE='BI';
    'MI1_CLK_L':
      PIN_NUMBER='(0,0,0,0,0,0,0,0,BG19,0,0,0,0,0,0,0,0,0,0,0,0,0,0,0,0,0,0,0,0,~
0,0,0,0,0,0,0,0,0,0,0)';
      OUTPUT_LOAD='(1.0,-1.0)';
      PINUSE='OUT';
    'MI0_CLK_L':
      PIN_NUMBER='(0,0,0,0,0,0,0,0,BD20,0,0,0,0,0,0,0,0,0,0,0,0,0,0,0,0,0,0,0,0,~
0,0,0,0,0,0,0,0,0,0,0)';
      OUTPUT_LOAD='(1.0,-1.0)';
      PINUSE='OUT';
    'MI_RESET_L':
      PIN_NUMBER='(0,0,0,0,0,0,0,0,AU21,0,0,0,0,0,0,0,0,0,0,0,0,0,0,0,0,0,0,0,0,~
0,0,0,0,0,0,0,0,0,0,0)';
      OUTPUT_LOAD='(1.0,-1.0)';
      PINUSE='OUT';
    'MIB_DQS_H6':
      PIN_NUMBER='(0,0,0,0,0,0,0,0,CM21,0,0,0,0,0,0,0,0,0,0,0,0,0,0,0,0,0,0,0,0,~
0,0,0,0,0,0,0,0,0,0,0)';
      BIDIRECTIONAL='TRUE';
      INPUT_LOAD='(-0.01,0.01)';
      OUTPUT_LOAD='(1.0,-1.0)';
      PINUSE='BI';
    'MIB_DATA0':
      PIN_NUMBER='(0,0,0,0,0,0,0,0,CB20,0,0,0,0,0,0,0,0,0,0,0,0,0,0,0,0,0,0,0,0,~
0,0,0,0,0,0,0,0,0,0,0)';
      BIDIRECTIONAL='TRUE';
      INPUT_LOAD='(-0.01,0.01)';
      OUTPUT_LOAD='(1.0,-1.0)';
      PINUSE='BI';
    'MIA_DATA23':
      PIN_NUMBER='(0,0,0,0,0,0,0,0,AC21,0,0,0,0,0,0,0,0,0,0,0,0,0,0,0,0,0,0,0,0,~
0,0,0,0,0,0,0,0,0,0,0)';
      BIDIRECTIONAL='TRUE';
      INPUT_LOAD='(-0.01,0.01)';
      OUTPUT_LOAD='(1.0,-1.0)';
      PINUSE='BI';
    'MIA_DATA12':
      PIN_NUMBER='(0,0,0,0,0,0,0,0,R19,0,0,0,0,0,0,0,0,0,0,0,0,0,0,0,0,0,0,0,0,0~
,0,0,0,0,0,0,0,0,0,0)';
      BIDIRECTIONAL='TRUE';
      INPUT_LOAD='(-0.01,0.01)';
      OUTPUT_LOAD='(1.0,-1.0)';
      PINUSE='BI';
    'MIA_DATA0':
      PIN_NUMBER='(0,0,0,0,0,0,0,0,E19,0,0,0,0,0,0,0,0,0,0,0,0,0,0,0,0,0,0,0,0,0~
,0,0,0,0,0,0,0,0,0,0)';
      BIDIRECTIONAL='TRUE';
      INPUT_LOAD='(-0.01,0.01)';
      OUTPUT_LOAD='(1.0,-1.0)';
      PINUSE='BI';
    'MIA_CHECK3':
      PIN_NUMBER='(0,0,0,0,0,0,0,0,AL21,0,0,0,0,0,0,0,0,0,0,0,0,0,0,0,0,0,0,0,0,~
0,0,0,0,0,0,0,0,0,0,0)';
      BIDIRECTIONAL='TRUE';
      INPUT_LOAD='(-0.01,0.01)';
      OUTPUT_LOAD='(1.0,-1.0)';
      PINUSE='BI';
    'MIB_DQS_H7':
      PIN_NUMBER='(0,0,0,0,0,0,0,0,CV21,0,0,0,0,0,0,0,0,0,0,0,0,0,0,0,0,0,0,0,0,~
0,0,0,0,0,0,0,0,0,0,0)';
      BIDIRECTIONAL='TRUE';
      INPUT_LOAD='(-0.01,0.01)';
      OUTPUT_LOAD='(1.0,-1.0)';
      PINUSE='BI';
    'MIB_DATA1':
      PIN_NUMBER='(0,0,0,0,0,0,0,0,CC21,0,0,0,0,0,0,0,0,0,0,0,0,0,0,0,0,0,0,0,0,~
0,0,0,0,0,0,0,0,0,0,0)';
      BIDIRECTIONAL='TRUE';
      INPUT_LOAD='(-0.01,0.01)';
      OUTPUT_LOAD='(1.0,-1.0)';
      PINUSE='BI';
    'MIB0_CS_L0':
      PIN_NUMBER='(0,0,0,0,0,0,0,0,BM21,0,0,0,0,0,0,0,0,0,0,0,0,0,0,0,0,0,0,0,0,~
0,0,0,0,0,0,0,0,0,0,0)';
      OUTPUT_LOAD='(1.0,-1.0)';
      PINUSE='OUT';
    'MIA_DQS_L0':
      PIN_NUMBER='(0,0,0,0,0,0,0,0,H20,0,0,0,0,0,0,0,0,0,0,0,0,0,0,0,0,0,0,0,0,0~
,0,0,0,0,0,0,0,0,0,0)';
      BIDIRECTIONAL='TRUE';
      INPUT_LOAD='(-0.01,0.01)';
      OUTPUT_LOAD='(1.0,-1.0)';
      PINUSE='BI';
    'MIA_DATA24':
      PIN_NUMBER='(0,0,0,0,0,0,0,0,AC19,0,0,0,0,0,0,0,0,0,0,0,0,0,0,0,0,0,0,0,0,~
0,0,0,0,0,0,0,0,0,0,0)';
      BIDIRECTIONAL='TRUE';
      INPUT_LOAD='(-0.01,0.01)';
      OUTPUT_LOAD='(1.0,-1.0)';
      PINUSE='BI';
    'MIA_DATA13':
      PIN_NUMBER='(0,0,0,0,0,0,0,0,T21,0,0,0,0,0,0,0,0,0,0,0,0,0,0,0,0,0,0,0,0,0~
,0,0,0,0,0,0,0,0,0,0)';
      BIDIRECTIONAL='TRUE';
      INPUT_LOAD='(-0.01,0.01)';
      OUTPUT_LOAD='(1.0,-1.0)';
      PINUSE='BI';
    'MIA_DATA1':
      PIN_NUMBER='(0,0,0,0,0,0,0,0,F21,0,0,0,0,0,0,0,0,0,0,0,0,0,0,0,0,0,0,0,0,0~
,0,0,0,0,0,0,0,0,0,0)';
      BIDIRECTIONAL='TRUE';
      INPUT_LOAD='(-0.01,0.01)';
      OUTPUT_LOAD='(1.0,-1.0)';
      PINUSE='BI';
    'MIA_CHECK4':
      PIN_NUMBER='(0,0,0,0,0,0,0,0,AN19,0,0,0,0,0,0,0,0,0,0,0,0,0,0,0,0,0,0,0,0,~
0,0,0,0,0,0,0,0,0,0,0)';
      BIDIRECTIONAL='TRUE';
      INPUT_LOAD='(-0.01,0.01)';
      OUTPUT_LOAD='(1.0,-1.0)';
      PINUSE='BI';
    'MIB_DQS_H8':
      PIN_NUMBER='(0,0,0,0,0,0,0,0,DD21,0,0,0,0,0,0,0,0,0,0,0,0,0,0,0,0,0,0,0,0,~
0,0,0,0,0,0,0,0,0,0,0)';
      BIDIRECTIONAL='TRUE';
      INPUT_LOAD='(-0.01,0.01)';
      OUTPUT_LOAD='(1.0,-1.0)';
      PINUSE='BI';
    'MIB_DATA30':
      PIN_NUMBER='(0,0,0,0,0,0,0,0,DE19,0,0,0,0,0,0,0,0,0,0,0,0,0,0,0,0,0,0,0,0,~
0,0,0,0,0,0,0,0,0,0,0)';
      BIDIRECTIONAL='TRUE';
      INPUT_LOAD='(-0.01,0.01)';
      OUTPUT_LOAD='(1.0,-1.0)';
      PINUSE='BI';
    'MIB_DATA2':
      PIN_NUMBER='(0,0,0,0,0,0,0,0,CC19,0,0,0,0,0,0,0,0,0,0,0,0,0,0,0,0,0,0,0,0,~
0,0,0,0,0,0,0,0,0,0,0)';
      BIDIRECTIONAL='TRUE';
      INPUT_LOAD='(-0.01,0.01)';
      OUTPUT_LOAD='(1.0,-1.0)';
      PINUSE='BI';
    'MIB1_CS_L0':
      PIN_NUMBER='(0,0,0,0,0,0,0,0,BL19,0,0,0,0,0,0,0,0,0,0,0,0,0,0,0,0,0,0,0,0,~
0,0,0,0,0,0,0,0,0,0,0)';
      OUTPUT_LOAD='(1.0,-1.0)';
      PINUSE='OUT';
    'MIB0_CS_L1':
      PIN_NUMBER='(0,0,0,0,0,0,0,0,BN19,0,0,0,0,0,0,0,0,0,0,0,0,0,0,0,0,0,0,0,0,~
0,0,0,0,0,0,0,0,0,0,0)';
      OUTPUT_LOAD='(1.0,-1.0)';
      PINUSE='OUT';
    'MIA_DQS_L1':
      PIN_NUMBER='(0,0,0,0,0,0,0,0,P20,0,0,0,0,0,0,0,0,0,0,0,0,0,0,0,0,0,0,0,0,0~
,0,0,0,0,0,0,0,0,0,0)';
      BIDIRECTIONAL='TRUE';
      INPUT_LOAD='(-0.01,0.01)';
      OUTPUT_LOAD='(1.0,-1.0)';
      PINUSE='BI';
    'MIA_DATA25':
      PIN_NUMBER='(0,0,0,0,0,0,0,0,AD21,0,0,0,0,0,0,0,0,0,0,0,0,0,0,0,0,0,0,0,0,~
0,0,0,0,0,0,0,0,0,0,0)';
      BIDIRECTIONAL='TRUE';
      INPUT_LOAD='(-0.01,0.01)';
      OUTPUT_LOAD='(1.0,-1.0)';
      PINUSE='BI';
    'MIA_DATA14':
      PIN_NUMBER='(0,0,0,0,0,0,0,0,T20,0,0,0,0,0,0,0,0,0,0,0,0,0,0,0,0,0,0,0,0,0~
,0,0,0,0,0,0,0,0,0,0)';
      BIDIRECTIONAL='TRUE';
      INPUT_LOAD='(-0.01,0.01)';
      OUTPUT_LOAD='(1.0,-1.0)';
      PINUSE='BI';
    'MIA_DATA2':
      PIN_NUMBER='(0,0,0,0,0,0,0,0,F20,0,0,0,0,0,0,0,0,0,0,0,0,0,0,0,0,0,0,0,0,0~
,0,0,0,0,0,0,0,0,0,0)';
      BIDIRECTIONAL='TRUE';
      INPUT_LOAD='(-0.01,0.01)';
      OUTPUT_LOAD='(1.0,-1.0)';
      PINUSE='BI';
    'MIA_CHECK5':
      PIN_NUMBER='(0,0,0,0,0,0,0,0,AP21,0,0,0,0,0,0,0,0,0,0,0,0,0,0,0,0,0,0,0,0,~
0,0,0,0,0,0,0,0,0,0,0)';
      BIDIRECTIONAL='TRUE';
      INPUT_LOAD='(-0.01,0.01)';
      OUTPUT_LOAD='(1.0,-1.0)';
      PINUSE='BI';
    'MIB_DQS_H9':
      PIN_NUMBER='(0,0,0,0,0,0,0,0,BV20,0,0,0,0,0,0,0,0,0,0,0,0,0,0,0,0,0,0,0,0,~
0,0,0,0,0,0,0,0,0,0,0)';
      BIDIRECTIONAL='TRUE';
      INPUT_LOAD='(-0.01,0.01)';
      OUTPUT_LOAD='(1.0,-1.0)';
      PINUSE='BI';
    'MIB_DATA31':
      PIN_NUMBER='(0,0,0,0,0,0,0,0,DF21,0,0,0,0,0,0,0,0,0,0,0,0,0,0,0,0,0,0,0,0,~
0,0,0,0,0,0,0,0,0,0,0)';
      BIDIRECTIONAL='TRUE';
      INPUT_LOAD='(-0.01,0.01)';
      OUTPUT_LOAD='(1.0,-1.0)';
      PINUSE='BI';
    'MIB_DATA20':
      PIN_NUMBER='(0,0,0,0,0,0,0,0,CV20,0,0,0,0,0,0,0,0,0,0,0,0,0,0,0,0,0,0,0,0,~
0,0,0,0,0,0,0,0,0,0,0)';
      BIDIRECTIONAL='TRUE';
      INPUT_LOAD='(-0.01,0.01)';
      OUTPUT_LOAD='(1.0,-1.0)';
      PINUSE='BI';
    'MIB_DATA3':
      PIN_NUMBER='(0,0,0,0,0,0,0,0,CD21,0,0,0,0,0,0,0,0,0,0,0,0,0,0,0,0,0,0,0,0,~
0,0,0,0,0,0,0,0,0,0,0)';
      BIDIRECTIONAL='TRUE';
      INPUT_LOAD='(-0.01,0.01)';
      OUTPUT_LOAD='(1.0,-1.0)';
      PINUSE='BI';
    'MIB_CHECK0':
      PIN_NUMBER='(0,0,0,0,0,0,0,0,BY20,0,0,0,0,0,0,0,0,0,0,0,0,0,0,0,0,0,0,0,0,~
0,0,0,0,0,0,0,0,0,0,0)';
      BIDIRECTIONAL='TRUE';
      INPUT_LOAD='(-0.01,0.01)';
      OUTPUT_LOAD='(1.0,-1.0)';
      PINUSE='BI';
    'MIB1_CS_L1':
      PIN_NUMBER='(0,0,0,0,0,0,0,0,BM20,0,0,0,0,0,0,0,0,0,0,0,0,0,0,0,0,0,0,0,0,~
0,0,0,0,0,0,0,0,0,0,0)';
      OUTPUT_LOAD='(1.0,-1.0)';
      PINUSE='OUT';
    'MIA_PAR':
      PIN_NUMBER='(0,0,0,0,0,0,0,0,BC21,0,0,0,0,0,0,0,0,0,0,0,0,0,0,0,0,0,0,0,0,~
0,0,0,0,0,0,0,0,0,0,0)';
      OUTPUT_LOAD='(1.0,-1.0)';
      PINUSE='OUT';
    'MIA_DQS_L2':
      PIN_NUMBER='(0,0,0,0,0,0,0,0,Y20,0,0,0,0,0,0,0,0,0,0,0,0,0,0,0,0,0,0,0,0,0~
,0,0,0,0,0,0,0,0,0,0)';
      BIDIRECTIONAL='TRUE';
      INPUT_LOAD='(-0.01,0.01)';
      OUTPUT_LOAD='(1.0,-1.0)';
      PINUSE='BI';
    'MIA_DATA26':
      PIN_NUMBER='(0,0,0,0,0,0,0,0,AD20,0,0,0,0,0,0,0,0,0,0,0,0,0,0,0,0,0,0,0,0,~
0,0,0,0,0,0,0,0,0,0,0)';
      BIDIRECTIONAL='TRUE';
      INPUT_LOAD='(-0.01,0.01)';
      OUTPUT_LOAD='(1.0,-1.0)';
      PINUSE='BI';
    'MIA_DATA15':
      PIN_NUMBER='(0,0,0,0,0,0,0,0,U21,0,0,0,0,0,0,0,0,0,0,0,0,0,0,0,0,0,0,0,0,0~
,0,0,0,0,0,0,0,0,0,0)';
      BIDIRECTIONAL='TRUE';
      INPUT_LOAD='(-0.01,0.01)';
      OUTPUT_LOAD='(1.0,-1.0)';
      PINUSE='BI';
    'MIA_DATA3':
      PIN_NUMBER='(0,0,0,0,0,0,0,0,G21,0,0,0,0,0,0,0,0,0,0,0,0,0,0,0,0,0,0,0,0,0~
,0,0,0,0,0,0,0,0,0,0)';
      BIDIRECTIONAL='TRUE';
      INPUT_LOAD='(-0.01,0.01)';
      OUTPUT_LOAD='(1.0,-1.0)';
      PINUSE='BI';
    'MIA_CHECK6':
      PIN_NUMBER='(0,0,0,0,0,0,0,0,AP20,0,0,0,0,0,0,0,0,0,0,0,0,0,0,0,0,0,0,0,0,~
0,0,0,0,0,0,0,0,0,0,0)';
      BIDIRECTIONAL='TRUE';
      INPUT_LOAD='(-0.01,0.01)';
      OUTPUT_LOAD='(1.0,-1.0)';
      PINUSE='BI';
    'MIB_PAR':
      PIN_NUMBER='(0,0,0,0,0,0,0,0,BL21,0,0,0,0,0,0,0,0,0,0,0,0,0,0,0,0,0,0,0,0,~
0,0,0,0,0,0,0,0,0,0,0)';
      OUTPUT_LOAD='(1.0,-1.0)';
      PINUSE='OUT';
    'MIB_DATA21':
      PIN_NUMBER='(0,0,0,0,0,0,0,0,CW21,0,0,0,0,0,0,0,0,0,0,0,0,0,0,0,0,0,0,0,0,~
0,0,0,0,0,0,0,0,0,0,0)';
      BIDIRECTIONAL='TRUE';
      INPUT_LOAD='(-0.01,0.01)';
      OUTPUT_LOAD='(1.0,-1.0)';
      PINUSE='BI';
    'MIB_DATA10':
      PIN_NUMBER='(0,0,0,0,0,0,0,0,CJ19,0,0,0,0,0,0,0,0,0,0,0,0,0,0,0,0,0,0,0,0,~
0,0,0,0,0,0,0,0,0,0,0)';
      BIDIRECTIONAL='TRUE';
      INPUT_LOAD='(-0.01,0.01)';
      OUTPUT_LOAD='(1.0,-1.0)';
      PINUSE='BI';
    'MIB_DATA4':
      PIN_NUMBER='(0,0,0,0,0,0,0,0,CF20,0,0,0,0,0,0,0,0,0,0,0,0,0,0,0,0,0,0,0,0,~
0,0,0,0,0,0,0,0,0,0,0)';
      BIDIRECTIONAL='TRUE';
      INPUT_LOAD='(-0.01,0.01)';
      OUTPUT_LOAD='(1.0,-1.0)';
      PINUSE='BI';
    'MIB_CHECK1':
      PIN_NUMBER='(0,0,0,0,0,0,0,0,CA21,0,0,0,0,0,0,0,0,0,0,0,0,0,0,0,0,0,0,0,0,~
0,0,0,0,0,0,0,0,0,0,0)';
      BIDIRECTIONAL='TRUE';
      INPUT_LOAD='(-0.01,0.01)';
      OUTPUT_LOAD='(1.0,-1.0)';
      PINUSE='BI';
    'MIA_DQS_L3':
      PIN_NUMBER='(0,0,0,0,0,0,0,0,AF20,0,0,0,0,0,0,0,0,0,0,0,0,0,0,0,0,0,0,0,0,~
0,0,0,0,0,0,0,0,0,0,0)';
      BIDIRECTIONAL='TRUE';
      INPUT_LOAD='(-0.01,0.01)';
      OUTPUT_LOAD='(1.0,-1.0)';
      PINUSE='BI';
    'MIA_DATA27':
      PIN_NUMBER='(0,0,0,0,0,0,0,0,AE21,0,0,0,0,0,0,0,0,0,0,0,0,0,0,0,0,0,0,0,0,~
0,0,0,0,0,0,0,0,0,0,0)';
      BIDIRECTIONAL='TRUE';
      INPUT_LOAD='(-0.01,0.01)';
      OUTPUT_LOAD='(1.0,-1.0)';
      PINUSE='BI';
    'MIA_DATA16':
      PIN_NUMBER='(0,0,0,0,0,0,0,0,U19,0,0,0,0,0,0,0,0,0,0,0,0,0,0,0,0,0,0,0,0,0~
,0,0,0,0,0,0,0,0,0,0)';
      BIDIRECTIONAL='TRUE';
      INPUT_LOAD='(-0.01,0.01)';
      OUTPUT_LOAD='(1.0,-1.0)';
      PINUSE='BI';
    'MIA_DATA4':
      PIN_NUMBER='(0,0,0,0,0,0,0,0,J19,0,0,0,0,0,0,0,0,0,0,0,0,0,0,0,0,0,0,0,0,0~
,0,0,0,0,0,0,0,0,0,0)';
      BIDIRECTIONAL='TRUE';
      INPUT_LOAD='(-0.01,0.01)';
      OUTPUT_LOAD='(1.0,-1.0)';
      PINUSE='BI';
    'MIA_CHECK7':
      PIN_NUMBER='(0,0,0,0,0,0,0,0,AR21,0,0,0,0,0,0,0,0,0,0,0,0,0,0,0,0,0,0,0,0,~
0,0,0,0,0,0,0,0,0,0,0)';
      BIDIRECTIONAL='TRUE';
      INPUT_LOAD='(-0.01,0.01)';
      OUTPUT_LOAD='(1.0,-1.0)';
      PINUSE='BI';
    'MIA1_RSP_L':
      PIN_NUMBER='(0,0,0,0,0,0,0,0,BP21,0,0,0,0,0,0,0,0,0,0,0,0,0,0,0,0,0,0,0,0,~
0,0,0,0,0,0,0,0,0,0,0)';
      INPUT_LOAD='(-0.01,0.01)';
      PINUSE='IN';
    'MIA0_RSP_L':
      PIN_NUMBER='(0,0,0,0,0,0,0,0,BN21,0,0,0,0,0,0,0,0,0,0,0,0,0,0,0,0,0,0,0,0,~
0,0,0,0,0,0,0,0,0,0,0)';
      INPUT_LOAD='(-0.01,0.01)';
      PINUSE='IN';
    'MI_ALERT_L':
      PIN_NUMBER='(0,0,0,0,0,0,0,0,AT21,0,0,0,0,0,0,0,0,0,0,0,0,0,0,0,0,0,0,0,0,~
0,0,0,0,0,0,0,0,0,0,0)';
      INPUT_LOAD='(-0.01,0.01)';
      PINUSE='IN';
    'MIB_DATA22':
      PIN_NUMBER='(0,0,0,0,0,0,0,0,CW19,0,0,0,0,0,0,0,0,0,0,0,0,0,0,0,0,0,0,0,0,~
0,0,0,0,0,0,0,0,0,0,0)';
      BIDIRECTIONAL='TRUE';
      INPUT_LOAD='(-0.01,0.01)';
      OUTPUT_LOAD='(1.0,-1.0)';
      PINUSE='BI';
    'MIB_DATA11':
      PIN_NUMBER='(0,0,0,0,0,0,0,0,CK21,0,0,0,0,0,0,0,0,0,0,0,0,0,0,0,0,0,0,0,0,~
0,0,0,0,0,0,0,0,0,0,0)';
      BIDIRECTIONAL='TRUE';
      INPUT_LOAD='(-0.01,0.01)';
      OUTPUT_LOAD='(1.0,-1.0)';
      PINUSE='BI';
    'MIB_DATA5':
      PIN_NUMBER='(0,0,0,0,0,0,0,0,CG21,0,0,0,0,0,0,0,0,0,0,0,0,0,0,0,0,0,0,0,0,~
0,0,0,0,0,0,0,0,0,0,0)';
      BIDIRECTIONAL='TRUE';
      INPUT_LOAD='(-0.01,0.01)';
      OUTPUT_LOAD='(1.0,-1.0)';
      PINUSE='BI';
    'MIB_CHECK2':
      PIN_NUMBER='(0,0,0,0,0,0,0,0,CA19,0,0,0,0,0,0,0,0,0,0,0,0,0,0,0,0,0,0,0,0,~
0,0,0,0,0,0,0,0,0,0,0)';
      BIDIRECTIONAL='TRUE';
      INPUT_LOAD='(-0.01,0.01)';
      OUTPUT_LOAD='(1.0,-1.0)';
      PINUSE='BI';
    'MIA_DQS_L4':
      PIN_NUMBER='(0,0,0,0,0,0,0,0,AM20,0,0,0,0,0,0,0,0,0,0,0,0,0,0,0,0,0,0,0,0,~
0,0,0,0,0,0,0,0,0,0,0)';
      BIDIRECTIONAL='TRUE';
      INPUT_LOAD='(-0.01,0.01)';
      OUTPUT_LOAD='(1.0,-1.0)';
      PINUSE='BI';
    'MIA_DQS_H0':
      PIN_NUMBER='(0,0,0,0,0,0,0,0,G19,0,0,0,0,0,0,0,0,0,0,0,0,0,0,0,0,0,0,0,0,0~
,0,0,0,0,0,0,0,0,0,0)';
      BIDIRECTIONAL='TRUE';
      INPUT_LOAD='(-0.01,0.01)';
      OUTPUT_LOAD='(1.0,-1.0)';
      PINUSE='BI';
    'MIA_DATA28':
      PIN_NUMBER='(0,0,0,0,0,0,0,0,AG19,0,0,0,0,0,0,0,0,0,0,0,0,0,0,0,0,0,0,0,0,~
0,0,0,0,0,0,0,0,0,0,0)';
      BIDIRECTIONAL='TRUE';
      INPUT_LOAD='(-0.01,0.01)';
      OUTPUT_LOAD='(1.0,-1.0)';
      PINUSE='BI';
    'MIA_DATA17':
      PIN_NUMBER='(0,0,0,0,0,0,0,0,V21,0,0,0,0,0,0,0,0,0,0,0,0,0,0,0,0,0,0,0,0,0~
,0,0,0,0,0,0,0,0,0,0)';
      BIDIRECTIONAL='TRUE';
      INPUT_LOAD='(-0.01,0.01)';
      OUTPUT_LOAD='(1.0,-1.0)';
      PINUSE='BI';
    'MIA_DATA5':
      PIN_NUMBER='(0,0,0,0,0,0,0,0,K21,0,0,0,0,0,0,0,0,0,0,0,0,0,0,0,0,0,0,0,0,0~
,0,0,0,0,0,0,0,0,0,0)';
      BIDIRECTIONAL='TRUE';
      INPUT_LOAD='(-0.01,0.01)';
      OUTPUT_LOAD='(1.0,-1.0)';
      PINUSE='BI';
    'TEST39I':
      PIN_NUMBER='(0,0,0,0,0,0,0,0,BF21,0,0,0,0,0,0,0,0,0,0,0,0,0,0,0,0,0,0,0,0,~
0,0,0,0,0,0,0,0,0,0,0)';
      OUTPUT_LOAD='(1.0,-1.0)';
      PINUSE='OUT';
    'MJ_RESET_L':
      PIN_NUMBER='(0,0,0,0,0,0,0,0,0,AU17,0,0,0,0,0,0,0,0,0,0,0,0,0,0,0,0,0,0,0,~
0,0,0,0,0,0,0,0,0,0,0)';
      OUTPUT_LOAD='(1.0,-1.0)';
      PINUSE='OUT';
    'MJ_ALERT_L':
      PIN_NUMBER='(0,0,0,0,0,0,0,0,0,AT18,0,0,0,0,0,0,0,0,0,0,0,0,0,0,0,0,0,0,0,~
0,0,0,0,0,0,0,0,0,0,0)';
      INPUT_LOAD='(-0.01,0.01)';
      PINUSE='IN';
    'MJB_PAR':
      PIN_NUMBER='(0,0,0,0,0,0,0,0,0,BL17,0,0,0,0,0,0,0,0,0,0,0,0,0,0,0,0,0,0,0,~
0,0,0,0,0,0,0,0,0,0,0)';
      OUTPUT_LOAD='(1.0,-1.0)';
      PINUSE='OUT';
    'MJB_DQS_L9':
      PIN_NUMBER='(0,0,0,0,0,0,0,0,0,BW16,0,0,0,0,0,0,0,0,0,0,0,0,0,0,0,0,0,0,0,~
0,0,0,0,0,0,0,0,0,0,0)';
      BIDIRECTIONAL='TRUE';
      INPUT_LOAD='(-0.01,0.01)';
      OUTPUT_LOAD='(1.0,-1.0)';
      PINUSE='BI';
    'MJB_DQS_L8':
      PIN_NUMBER='(0,0,0,0,0,0,0,0,0,DC17,0,0,0,0,0,0,0,0,0,0,0,0,0,0,0,0,0,0,0,~
0,0,0,0,0,0,0,0,0,0,0)';
      BIDIRECTIONAL='TRUE';
      INPUT_LOAD='(-0.01,0.01)';
      OUTPUT_LOAD='(1.0,-1.0)';
      PINUSE='BI';
    'MJB_DQS_L7':
      PIN_NUMBER='(0,0,0,0,0,0,0,0,0,CU17,0,0,0,0,0,0,0,0,0,0,0,0,0,0,0,0,0,0,0,~
0,0,0,0,0,0,0,0,0,0,0)';
      BIDIRECTIONAL='TRUE';
      INPUT_LOAD='(-0.01,0.01)';
      OUTPUT_LOAD='(1.0,-1.0)';
      PINUSE='BI';
    'MJB_DQS_L6':
      PIN_NUMBER='(0,0,0,0,0,0,0,0,0,CL17,0,0,0,0,0,0,0,0,0,0,0,0,0,0,0,0,0,0,0,~
0,0,0,0,0,0,0,0,0,0,0)';
      BIDIRECTIONAL='TRUE';
      INPUT_LOAD='(-0.01,0.01)';
      OUTPUT_LOAD='(1.0,-1.0)';
      PINUSE='BI';
    'MJB_DQS_L5':
      PIN_NUMBER='(0,0,0,0,0,0,0,0,0,CE17,0,0,0,0,0,0,0,0,0,0,0,0,0,0,0,0,0,0,0,~
0,0,0,0,0,0,0,0,0,0,0)';
      BIDIRECTIONAL='TRUE';
      INPUT_LOAD='(-0.01,0.01)';
      OUTPUT_LOAD='(1.0,-1.0)';
      PINUSE='BI';
    'MJB_DQS_L3':
      PIN_NUMBER='(0,0,0,0,0,0,0,0,0,DC16,0,0,0,0,0,0,0,0,0,0,0,0,0,0,0,0,0,0,0,~
0,0,0,0,0,0,0,0,0,0,0)';
      BIDIRECTIONAL='TRUE';
      INPUT_LOAD='(-0.01,0.01)';
      OUTPUT_LOAD='(1.0,-1.0)';
      PINUSE='BI';
    'MJB_DQS_L2':
      PIN_NUMBER='(0,0,0,0,0,0,0,0,0,CU16,0,0,0,0,0,0,0,0,0,0,0,0,0,0,0,0,0,0,0,~
0,0,0,0,0,0,0,0,0,0,0)';
      BIDIRECTIONAL='TRUE';
      INPUT_LOAD='(-0.01,0.01)';
      OUTPUT_LOAD='(1.0,-1.0)';
      PINUSE='BI';
    'MJB_DQS_L1':
      PIN_NUMBER='(0,0,0,0,0,0,0,0,0,CL16,0,0,0,0,0,0,0,0,0,0,0,0,0,0,0,0,0,0,0,~
0,0,0,0,0,0,0,0,0,0,0)';
      BIDIRECTIONAL='TRUE';
      INPUT_LOAD='(-0.01,0.01)';
      OUTPUT_LOAD='(1.0,-1.0)';
      PINUSE='BI';
    'MJB_DQS_H9':
      PIN_NUMBER='(0,0,0,0,0,0,0,0,0,BV16,0,0,0,0,0,0,0,0,0,0,0,0,0,0,0,0,0,0,0,~
0,0,0,0,0,0,0,0,0,0,0)';
      BIDIRECTIONAL='TRUE';
      INPUT_LOAD='(-0.01,0.01)';
      OUTPUT_LOAD='(1.0,-1.0)';
      PINUSE='BI';
    'MJB_DQS_H8':
      PIN_NUMBER='(0,0,0,0,0,0,0,0,0,DD18,0,0,0,0,0,0,0,0,0,0,0,0,0,0,0,0,0,0,0,~
0,0,0,0,0,0,0,0,0,0,0)';
      BIDIRECTIONAL='TRUE';
      INPUT_LOAD='(-0.01,0.01)';
      OUTPUT_LOAD='(1.0,-1.0)';
      PINUSE='BI';
    'MJB_DQS_H7':
      PIN_NUMBER='(0,0,0,0,0,0,0,0,0,CV18,0,0,0,0,0,0,0,0,0,0,0,0,0,0,0,0,0,0,0,~
0,0,0,0,0,0,0,0,0,0,0)';
      BIDIRECTIONAL='TRUE';
      INPUT_LOAD='(-0.01,0.01)';
      OUTPUT_LOAD='(1.0,-1.0)';
      PINUSE='BI';
    'MJB_DQS_H6':
      PIN_NUMBER='(0,0,0,0,0,0,0,0,0,CM18,0,0,0,0,0,0,0,0,0,0,0,0,0,0,0,0,0,0,0,~
0,0,0,0,0,0,0,0,0,0,0)';
      BIDIRECTIONAL='TRUE';
      INPUT_LOAD='(-0.01,0.01)';
      OUTPUT_LOAD='(1.0,-1.0)';
      PINUSE='BI';
    'MJB_DQS_H4':
      PIN_NUMBER='(0,0,0,0,0,0,0,0,0,BY18,0,0,0,0,0,0,0,0,0,0,0,0,0,0,0,0,0,0,0,~
0,0,0,0,0,0,0,0,0,0,0)';
      BIDIRECTIONAL='TRUE';
      INPUT_LOAD='(-0.01,0.01)';
      OUTPUT_LOAD='(1.0,-1.0)';
      PINUSE='BI';
    'MJB_DQS_H3':
      PIN_NUMBER='(0,0,0,0,0,0,0,0,0,DB16,0,0,0,0,0,0,0,0,0,0,0,0,0,0,0,0,0,0,0,~
0,0,0,0,0,0,0,0,0,0,0)';
      BIDIRECTIONAL='TRUE';
      INPUT_LOAD='(-0.01,0.01)';
      OUTPUT_LOAD='(1.0,-1.0)';
      PINUSE='BI';
    'MJB_DQS_H2':
      PIN_NUMBER='(0,0,0,0,0,0,0,0,0,CT16,0,0,0,0,0,0,0,0,0,0,0,0,0,0,0,0,0,0,0,~
0,0,0,0,0,0,0,0,0,0,0)';
      BIDIRECTIONAL='TRUE';
      INPUT_LOAD='(-0.01,0.01)';
      OUTPUT_LOAD='(1.0,-1.0)';
      PINUSE='BI';
    'MJB_DQS_H1':
      PIN_NUMBER='(0,0,0,0,0,0,0,0,0,CK16,0,0,0,0,0,0,0,0,0,0,0,0,0,0,0,0,0,0,0,~
0,0,0,0,0,0,0,0,0,0,0)';
      BIDIRECTIONAL='TRUE';
      INPUT_LOAD='(-0.01,0.01)';
      OUTPUT_LOAD='(1.0,-1.0)';
      PINUSE='BI';
    'MJB_DQS_H0':
      PIN_NUMBER='(0,0,0,0,0,0,0,0,0,CD16,0,0,0,0,0,0,0,0,0,0,0,0,0,0,0,0,0,0,0,~
0,0,0,0,0,0,0,0,0,0,0)';
      BIDIRECTIONAL='TRUE';
      INPUT_LOAD='(-0.01,0.01)';
      OUTPUT_LOAD='(1.0,-1.0)';
      PINUSE='BI';
    'MJB_DATA31':
      PIN_NUMBER='(0,0,0,0,0,0,0,0,0,DF16,0,0,0,0,0,0,0,0,0,0,0,0,0,0,0,0,0,0,0,~
0,0,0,0,0,0,0,0,0,0,0)';
      BIDIRECTIONAL='TRUE';
      INPUT_LOAD='(-0.01,0.01)';
      OUTPUT_LOAD='(1.0,-1.0)';
      PINUSE='BI';
    'MJB_DATA30':
      PIN_NUMBER='(0,0,0,0,0,0,0,0,0,DE16,0,0,0,0,0,0,0,0,0,0,0,0,0,0,0,0,0,0,0,~
0,0,0,0,0,0,0,0,0,0,0)';
      BIDIRECTIONAL='TRUE';
      INPUT_LOAD='(-0.01,0.01)';
      OUTPUT_LOAD='(1.0,-1.0)';
      PINUSE='BI';
    'MJB_DATA29':
      PIN_NUMBER='(0,0,0,0,0,0,0,0,0,DE17,0,0,0,0,0,0,0,0,0,0,0,0,0,0,0,0,0,0,0,~
0,0,0,0,0,0,0,0,0,0,0)';
      BIDIRECTIONAL='TRUE';
      INPUT_LOAD='(-0.01,0.01)';
      OUTPUT_LOAD='(1.0,-1.0)';
      PINUSE='BI';
    'MJB_DATA28':
      PIN_NUMBER='(0,0,0,0,0,0,0,0,0,DD16,0,0,0,0,0,0,0,0,0,0,0,0,0,0,0,0,0,0,0,~
0,0,0,0,0,0,0,0,0,0,0)';
      BIDIRECTIONAL='TRUE';
      INPUT_LOAD='(-0.01,0.01)';
      OUTPUT_LOAD='(1.0,-1.0)';
      PINUSE='BI';
    'MJB_DATA27':
      PIN_NUMBER='(0,0,0,0,0,0,0,0,0,DB18,0,0,0,0,0,0,0,0,0,0,0,0,0,0,0,0,0,0,0,~
0,0,0,0,0,0,0,0,0,0,0)';
      BIDIRECTIONAL='TRUE';
      INPUT_LOAD='(-0.01,0.01)';
      OUTPUT_LOAD='(1.0,-1.0)';
      PINUSE='BI';
    'MJB_DATA26':
      PIN_NUMBER='(0,0,0,0,0,0,0,0,0,DA16,0,0,0,0,0,0,0,0,0,0,0,0,0,0,0,0,0,0,0,~
0,0,0,0,0,0,0,0,0,0,0)';
      BIDIRECTIONAL='TRUE';
      INPUT_LOAD='(-0.01,0.01)';
      OUTPUT_LOAD='(1.0,-1.0)';
      PINUSE='BI';
    'MJB_DATA25':
      PIN_NUMBER='(0,0,0,0,0,0,0,0,0,DA17,0,0,0,0,0,0,0,0,0,0,0,0,0,0,0,0,0,0,0,~
0,0,0,0,0,0,0,0,0,0,0)';
      BIDIRECTIONAL='TRUE';
      INPUT_LOAD='(-0.01,0.01)';
      OUTPUT_LOAD='(1.0,-1.0)';
      PINUSE='BI';
    'MJB_DATA24':
      PIN_NUMBER='(0,0,0,0,0,0,0,0,0,CY16,0,0,0,0,0,0,0,0,0,0,0,0,0,0,0,0,0,0,0,~
0,0,0,0,0,0,0,0,0,0,0)';
      BIDIRECTIONAL='TRUE';
      INPUT_LOAD='(-0.01,0.01)';
      OUTPUT_LOAD='(1.0,-1.0)';
      PINUSE='BI';
    'MJB_DATA23':
      PIN_NUMBER='(0,0,0,0,0,0,0,0,0,CY18,0,0,0,0,0,0,0,0,0,0,0,0,0,0,0,0,0,0,0,~
0,0,0,0,0,0,0,0,0,0,0)';
      BIDIRECTIONAL='TRUE';
      INPUT_LOAD='(-0.01,0.01)';
      OUTPUT_LOAD='(1.0,-1.0)';
      PINUSE='BI';
    'MJB_DATA22':
      PIN_NUMBER='(0,0,0,0,0,0,0,0,0,CW16,0,0,0,0,0,0,0,0,0,0,0,0,0,0,0,0,0,0,0,~
0,0,0,0,0,0,0,0,0,0,0)';
      BIDIRECTIONAL='TRUE';
      INPUT_LOAD='(-0.01,0.01)';
      OUTPUT_LOAD='(1.0,-1.0)';
      PINUSE='BI';
    'MJB_DATA21':
      PIN_NUMBER='(0,0,0,0,0,0,0,0,0,CW17,0,0,0,0,0,0,0,0,0,0,0,0,0,0,0,0,0,0,0,~
0,0,0,0,0,0,0,0,0,0,0)';
      BIDIRECTIONAL='TRUE';
      INPUT_LOAD='(-0.01,0.01)';
      OUTPUT_LOAD='(1.0,-1.0)';
      PINUSE='BI';
    'MJB_DATA20':
      PIN_NUMBER='(0,0,0,0,0,0,0,0,0,CV16,0,0,0,0,0,0,0,0,0,0,0,0,0,0,0,0,0,0,0,~
0,0,0,0,0,0,0,0,0,0,0)';
      BIDIRECTIONAL='TRUE';
      INPUT_LOAD='(-0.01,0.01)';
      OUTPUT_LOAD='(1.0,-1.0)';
      PINUSE='BI';
    'MJB_DATA19':
      PIN_NUMBER='(0,0,0,0,0,0,0,0,0,CT18,0,0,0,0,0,0,0,0,0,0,0,0,0,0,0,0,0,0,0,~
0,0,0,0,0,0,0,0,0,0,0)';
      BIDIRECTIONAL='TRUE';
      INPUT_LOAD='(-0.01,0.01)';
      OUTPUT_LOAD='(1.0,-1.0)';
      PINUSE='BI';
    'MJB_DATA18':
      PIN_NUMBER='(0,0,0,0,0,0,0,0,0,CR16,0,0,0,0,0,0,0,0,0,0,0,0,0,0,0,0,0,0,0,~
0,0,0,0,0,0,0,0,0,0,0)';
      BIDIRECTIONAL='TRUE';
      INPUT_LOAD='(-0.01,0.01)';
      OUTPUT_LOAD='(1.0,-1.0)';
      PINUSE='BI';
    'MJB_DATA17':
      PIN_NUMBER='(0,0,0,0,0,0,0,0,0,CR17,0,0,0,0,0,0,0,0,0,0,0,0,0,0,0,0,0,0,0,~
0,0,0,0,0,0,0,0,0,0,0)';
      BIDIRECTIONAL='TRUE';
      INPUT_LOAD='(-0.01,0.01)';
      OUTPUT_LOAD='(1.0,-1.0)';
      PINUSE='BI';
    'MJB_DATA16':
      PIN_NUMBER='(0,0,0,0,0,0,0,0,0,CP16,0,0,0,0,0,0,0,0,0,0,0,0,0,0,0,0,0,0,0,~
0,0,0,0,0,0,0,0,0,0,0)';
      BIDIRECTIONAL='TRUE';
      INPUT_LOAD='(-0.01,0.01)';
      OUTPUT_LOAD='(1.0,-1.0)';
      PINUSE='BI';
    'MJB_DATA15':
      PIN_NUMBER='(0,0,0,0,0,0,0,0,0,CP18,0,0,0,0,0,0,0,0,0,0,0,0,0,0,0,0,0,0,0,~
0,0,0,0,0,0,0,0,0,0,0)';
      BIDIRECTIONAL='TRUE';
      INPUT_LOAD='(-0.01,0.01)';
      OUTPUT_LOAD='(1.0,-1.0)';
      PINUSE='BI';
    'MJB_DATA14':
      PIN_NUMBER='(0,0,0,0,0,0,0,0,0,CN16,0,0,0,0,0,0,0,0,0,0,0,0,0,0,0,0,0,0,0,~
0,0,0,0,0,0,0,0,0,0,0)';
      BIDIRECTIONAL='TRUE';
      INPUT_LOAD='(-0.01,0.01)';
      OUTPUT_LOAD='(1.0,-1.0)';
      PINUSE='BI';
    'MJB_DATA13':
      PIN_NUMBER='(0,0,0,0,0,0,0,0,0,CN17,0,0,0,0,0,0,0,0,0,0,0,0,0,0,0,0,0,0,0,~
0,0,0,0,0,0,0,0,0,0,0)';
      BIDIRECTIONAL='TRUE';
      INPUT_LOAD='(-0.01,0.01)';
      OUTPUT_LOAD='(1.0,-1.0)';
      PINUSE='BI';
    'MJB_DATA12':
      PIN_NUMBER='(0,0,0,0,0,0,0,0,0,CM16,0,0,0,0,0,0,0,0,0,0,0,0,0,0,0,0,0,0,0,~
0,0,0,0,0,0,0,0,0,0,0)';
      BIDIRECTIONAL='TRUE';
      INPUT_LOAD='(-0.01,0.01)';
      OUTPUT_LOAD='(1.0,-1.0)';
      PINUSE='BI';
    'MJB_DATA11':
      PIN_NUMBER='(0,0,0,0,0,0,0,0,0,CK18,0,0,0,0,0,0,0,0,0,0,0,0,0,0,0,0,0,0,0,~
0,0,0,0,0,0,0,0,0,0,0)';
      BIDIRECTIONAL='TRUE';
      INPUT_LOAD='(-0.01,0.01)';
      OUTPUT_LOAD='(1.0,-1.0)';
      PINUSE='BI';
    'MJB_DATA10':
      PIN_NUMBER='(0,0,0,0,0,0,0,0,0,CJ16,0,0,0,0,0,0,0,0,0,0,0,0,0,0,0,0,0,0,0,~
0,0,0,0,0,0,0,0,0,0,0)';
      BIDIRECTIONAL='TRUE';
      INPUT_LOAD='(-0.01,0.01)';
      OUTPUT_LOAD='(1.0,-1.0)';
      PINUSE='BI';
    'MJB_DATA9':
      PIN_NUMBER='(0,0,0,0,0,0,0,0,0,CJ17,0,0,0,0,0,0,0,0,0,0,0,0,0,0,0,0,0,0,0,~
0,0,0,0,0,0,0,0,0,0,0)';
      BIDIRECTIONAL='TRUE';
      INPUT_LOAD='(-0.01,0.01)';
      OUTPUT_LOAD='(1.0,-1.0)';
      PINUSE='BI';
    'MJB_DATA8':
      PIN_NUMBER='(0,0,0,0,0,0,0,0,0,CH16,0,0,0,0,0,0,0,0,0,0,0,0,0,0,0,0,0,0,0,~
0,0,0,0,0,0,0,0,0,0,0)';
      BIDIRECTIONAL='TRUE';
      INPUT_LOAD='(-0.01,0.01)';
      OUTPUT_LOAD='(1.0,-1.0)';
      PINUSE='BI';
    'MJB_DATA2':
      PIN_NUMBER='(0,0,0,0,0,0,0,0,0,CC16,0,0,0,0,0,0,0,0,0,0,0,0,0,0,0,0,0,0,0,~
0,0,0,0,0,0,0,0,0,0,0)';
      BIDIRECTIONAL='TRUE';
      INPUT_LOAD='(-0.01,0.01)';
      OUTPUT_LOAD='(1.0,-1.0)';
      PINUSE='BI';
    'MJB_DATA1':
      PIN_NUMBER='(0,0,0,0,0,0,0,0,0,CC17,0,0,0,0,0,0,0,0,0,0,0,0,0,0,0,0,0,0,0,~
0,0,0,0,0,0,0,0,0,0,0)';
      BIDIRECTIONAL='TRUE';
      INPUT_LOAD='(-0.01,0.01)';
      OUTPUT_LOAD='(1.0,-1.0)';
      PINUSE='BI';
    'MJB_CHECK7':
      PIN_NUMBER='(0,0,0,0,0,0,0,0,0,BV18,0,0,0,0,0,0,0,0,0,0,0,0,0,0,0,0,0,0,0,~
0,0,0,0,0,0,0,0,0,0,0)';
      BIDIRECTIONAL='TRUE';
      INPUT_LOAD='(-0.01,0.01)';
      OUTPUT_LOAD='(1.0,-1.0)';
      PINUSE='BI';
    'MJB_CHECK6':
      PIN_NUMBER='(0,0,0,0,0,0,0,0,0,BU16,0,0,0,0,0,0,0,0,0,0,0,0,0,0,0,0,0,0,0,~
0,0,0,0,0,0,0,0,0,0,0)';
      BIDIRECTIONAL='TRUE';
      INPUT_LOAD='(-0.01,0.01)';
      OUTPUT_LOAD='(1.0,-1.0)';
      PINUSE='BI';
    'MJB_CHECK5':
      PIN_NUMBER='(0,0,0,0,0,0,0,0,0,BU17,0,0,0,0,0,0,0,0,0,0,0,0,0,0,0,0,0,0,0,~
0,0,0,0,0,0,0,0,0,0,0)';
      BIDIRECTIONAL='TRUE';
      INPUT_LOAD='(-0.01,0.01)';
      OUTPUT_LOAD='(1.0,-1.0)';
      PINUSE='BI';
    'MJB_CHECK4':
      PIN_NUMBER='(0,0,0,0,0,0,0,0,0,BT16,0,0,0,0,0,0,0,0,0,0,0,0,0,0,0,0,0,0,0,~
0,0,0,0,0,0,0,0,0,0,0)';
      BIDIRECTIONAL='TRUE';
      INPUT_LOAD='(-0.01,0.01)';
      OUTPUT_LOAD='(1.0,-1.0)';
      PINUSE='BI';
    'MJB_CHECK3':
      PIN_NUMBER='(0,0,0,0,0,0,0,0,0,CB18,0,0,0,0,0,0,0,0,0,0,0,0,0,0,0,0,0,0,0,~
0,0,0,0,0,0,0,0,0,0,0)';
      BIDIRECTIONAL='TRUE';
      INPUT_LOAD='(-0.01,0.01)';
      OUTPUT_LOAD='(1.0,-1.0)';
      PINUSE='BI';
    'MJB_CHECK2':
      PIN_NUMBER='(0,0,0,0,0,0,0,0,0,CA16,0,0,0,0,0,0,0,0,0,0,0,0,0,0,0,0,0,0,0,~
0,0,0,0,0,0,0,0,0,0,0)';
      BIDIRECTIONAL='TRUE';
      INPUT_LOAD='(-0.01,0.01)';
      OUTPUT_LOAD='(1.0,-1.0)';
      PINUSE='BI';
    'MJB_CHECK1':
      PIN_NUMBER='(0,0,0,0,0,0,0,0,0,CA17,0,0,0,0,0,0,0,0,0,0,0,0,0,0,0,0,0,0,0,~
0,0,0,0,0,0,0,0,0,0,0)';
      BIDIRECTIONAL='TRUE';
      INPUT_LOAD='(-0.01,0.01)';
      OUTPUT_LOAD='(1.0,-1.0)';
      PINUSE='BI';
    'MJB_CHECK0':
      PIN_NUMBER='(0,0,0,0,0,0,0,0,0,BY16,0,0,0,0,0,0,0,0,0,0,0,0,0,0,0,0,0,0,0,~
0,0,0,0,0,0,0,0,0,0,0)';
      BIDIRECTIONAL='TRUE';
      INPUT_LOAD='(-0.01,0.01)';
      OUTPUT_LOAD='(1.0,-1.0)';
      PINUSE='BI';
    'MJB_CA6':
      PIN_NUMBER='(0,0,0,0,0,0,0,0,0,BK16,0,0,0,0,0,0,0,0,0,0,0,0,0,0,0,0,0,0,0,~
0,0,0,0,0,0,0,0,0,0,0)';
      OUTPUT_LOAD='(1.0,-1.0)';
      PINUSE='OUT';
    'MJB_CA5':
      PIN_NUMBER='(0,0,0,0,0,0,0,0,0,BK18,0,0,0,0,0,0,0,0,0,0,0,0,0,0,0,0,0,0,0,~
0,0,0,0,0,0,0,0,0,0,0)';
      OUTPUT_LOAD='(1.0,-1.0)';
      PINUSE='OUT';
    'MJB_CA4':
      PIN_NUMBER='(0,0,0,0,0,0,0,0,0,BJ17,0,0,0,0,0,0,0,0,0,0,0,0,0,0,0,0,0,0,0,~
0,0,0,0,0,0,0,0,0,0,0)';
      OUTPUT_LOAD='(1.0,-1.0)';
      PINUSE='OUT';
    'MJB_CA3':
      PIN_NUMBER='(0,0,0,0,0,0,0,0,0,BJ16,0,0,0,0,0,0,0,0,0,0,0,0,0,0,0,0,0,0,0,~
0,0,0,0,0,0,0,0,0,0,0)';
      OUTPUT_LOAD='(1.0,-1.0)';
      PINUSE='OUT';
    'MJB_CA2':
      PIN_NUMBER='(0,0,0,0,0,0,0,0,0,BH16,0,0,0,0,0,0,0,0,0,0,0,0,0,0,0,0,0,0,0,~
0,0,0,0,0,0,0,0,0,0,0)';
      OUTPUT_LOAD='(1.0,-1.0)';
      PINUSE='OUT';
    'MJB_CA1':
      PIN_NUMBER='(0,0,0,0,0,0,0,0,0,BH18,0,0,0,0,0,0,0,0,0,0,0,0,0,0,0,0,0,0,0,~
0,0,0,0,0,0,0,0,0,0,0)';
      OUTPUT_LOAD='(1.0,-1.0)';
      PINUSE='OUT';
    'MJB_CA0':
      PIN_NUMBER='(0,0,0,0,0,0,0,0,0,BG17,0,0,0,0,0,0,0,0,0,0,0,0,0,0,0,0,0,0,0,~
0,0,0,0,0,0,0,0,0,0,0)';
      OUTPUT_LOAD='(1.0,-1.0)';
      PINUSE='OUT';
    'MJB1_RSP_L':
      PIN_NUMBER='(0,0,0,0,0,0,0,0,0,BR16,0,0,0,0,0,0,0,0,0,0,0,0,0,0,0,0,0,0,0,~
0,0,0,0,0,0,0,0,0,0,0)';
      INPUT_LOAD='(-0.01,0.01)';
      PINUSE='IN';
    'MJB1_CS_L1':
      PIN_NUMBER='(0,0,0,0,0,0,0,0,0,BM16,0,0,0,0,0,0,0,0,0,0,0,0,0,0,0,0,0,0,0,~
0,0,0,0,0,0,0,0,0,0,0)';
      OUTPUT_LOAD='(1.0,-1.0)';
      PINUSE='OUT';
    'MJB1_CS_L0':
      PIN_NUMBER='(0,0,0,0,0,0,0,0,0,BL16,0,0,0,0,0,0,0,0,0,0,0,0,0,0,0,0,0,0,0,~
0,0,0,0,0,0,0,0,0,0,0)';
      OUTPUT_LOAD='(1.0,-1.0)';
      PINUSE='OUT';
    'MJB0_RSP_L':
      PIN_NUMBER='(0,0,0,0,0,0,0,0,0,BP16,0,0,0,0,0,0,0,0,0,0,0,0,0,0,0,0,0,0,0,~
0,0,0,0,0,0,0,0,0,0,0)';
      INPUT_LOAD='(-0.01,0.01)';
      PINUSE='IN';
    'MJB0_CS_L1':
      PIN_NUMBER='(0,0,0,0,0,0,0,0,0,BN16,0,0,0,0,0,0,0,0,0,0,0,0,0,0,0,0,0,0,0,~
0,0,0,0,0,0,0,0,0,0,0)';
      OUTPUT_LOAD='(1.0,-1.0)';
      PINUSE='OUT';
    'MJB0_CS_L0':
      PIN_NUMBER='(0,0,0,0,0,0,0,0,0,BM18,0,0,0,0,0,0,0,0,0,0,0,0,0,0,0,0,0,0,0,~
0,0,0,0,0,0,0,0,0,0,0)';
      OUTPUT_LOAD='(1.0,-1.0)';
      PINUSE='OUT';
    'MJA_PAR':
      PIN_NUMBER='(0,0,0,0,0,0,0,0,0,BC17,0,0,0,0,0,0,0,0,0,0,0,0,0,0,0,0,0,0,0,~
0,0,0,0,0,0,0,0,0,0,0)';
      OUTPUT_LOAD='(1.0,-1.0)';
      PINUSE='OUT';
    'MJA_DQS_L9':
      PIN_NUMBER='(0,0,0,0,0,0,0,0,0,AM18,0,0,0,0,0,0,0,0,0,0,0,0,0,0,0,0,0,0,0,~
0,0,0,0,0,0,0,0,0,0,0)';
      BIDIRECTIONAL='TRUE';
      INPUT_LOAD='(-0.01,0.01)';
      OUTPUT_LOAD='(1.0,-1.0)';
      PINUSE='BI';
    'MJA_DQS_L8':
      PIN_NUMBER='(0,0,0,0,0,0,0,0,0,AF18,0,0,0,0,0,0,0,0,0,0,0,0,0,0,0,0,0,0,0,~
0,0,0,0,0,0,0,0,0,0,0)';
      BIDIRECTIONAL='TRUE';
      INPUT_LOAD='(-0.01,0.01)';
      OUTPUT_LOAD='(1.0,-1.0)';
      PINUSE='BI';
    'MJA_DQS_L6':
      PIN_NUMBER='(0,0,0,0,0,0,0,0,0,P18,0,0,0,0,0,0,0,0,0,0,0,0,0,0,0,0,0,0,0,0~
,0,0,0,0,0,0,0,0,0,0)';
      BIDIRECTIONAL='TRUE';
      INPUT_LOAD='(-0.01,0.01)';
      OUTPUT_LOAD='(1.0,-1.0)';
      PINUSE='BI';
    'MJA_DQS_L3':
      PIN_NUMBER='(0,0,0,0,0,0,0,0,0,AF16,0,0,0,0,0,0,0,0,0,0,0,0,0,0,0,0,0,0,0,~
0,0,0,0,0,0,0,0,0,0,0)';
      BIDIRECTIONAL='TRUE';
      INPUT_LOAD='(-0.01,0.01)';
      OUTPUT_LOAD='(1.0,-1.0)';
      PINUSE='BI';
    'MJA_DQS_L2':
      PIN_NUMBER='(0,0,0,0,0,0,0,0,0,Y16,0,0,0,0,0,0,0,0,0,0,0,0,0,0,0,0,0,0,0,0~
,0,0,0,0,0,0,0,0,0,0)';
      BIDIRECTIONAL='TRUE';
      INPUT_LOAD='(-0.01,0.01)';
      OUTPUT_LOAD='(1.0,-1.0)';
      PINUSE='BI';
    'MJA_DQS_L1':
      PIN_NUMBER='(0,0,0,0,0,0,0,0,0,P16,0,0,0,0,0,0,0,0,0,0,0,0,0,0,0,0,0,0,0,0~
,0,0,0,0,0,0,0,0,0,0)';
      BIDIRECTIONAL='TRUE';
      INPUT_LOAD='(-0.01,0.01)';
      OUTPUT_LOAD='(1.0,-1.0)';
      PINUSE='BI';
    'MJA_DQS_L0':
      PIN_NUMBER='(0,0,0,0,0,0,0,0,0,H16,0,0,0,0,0,0,0,0,0,0,0,0,0,0,0,0,0,0,0,0~
,0,0,0,0,0,0,0,0,0,0)';
      BIDIRECTIONAL='TRUE';
      INPUT_LOAD='(-0.01,0.01)';
      OUTPUT_LOAD='(1.0,-1.0)';
      PINUSE='BI';
    'MJA_DQS_H9':
      PIN_NUMBER='(0,0,0,0,0,0,0,0,0,AN17,0,0,0,0,0,0,0,0,0,0,0,0,0,0,0,0,0,0,0,~
0,0,0,0,0,0,0,0,0,0,0)';
      BIDIRECTIONAL='TRUE';
      INPUT_LOAD='(-0.01,0.01)';
      OUTPUT_LOAD='(1.0,-1.0)';
      PINUSE='BI';
    'MJA_DQS_H7':
      PIN_NUMBER='(0,0,0,0,0,0,0,0,0,AA17,0,0,0,0,0,0,0,0,0,0,0,0,0,0,0,0,0,0,0,~
0,0,0,0,0,0,0,0,0,0,0)';
      BIDIRECTIONAL='TRUE';
      INPUT_LOAD='(-0.01,0.01)';
      OUTPUT_LOAD='(1.0,-1.0)';
      PINUSE='BI';
    'MJA_DQS_H6':
      PIN_NUMBER='(0,0,0,0,0,0,0,0,0,R17,0,0,0,0,0,0,0,0,0,0,0,0,0,0,0,0,0,0,0,0~
,0,0,0,0,0,0,0,0,0,0)';
      BIDIRECTIONAL='TRUE';
      INPUT_LOAD='(-0.01,0.01)';
      OUTPUT_LOAD='(1.0,-1.0)';
      PINUSE='BI';
    'MJA_DQS_H5':
      PIN_NUMBER='(0,0,0,0,0,0,0,0,0,J17,0,0,0,0,0,0,0,0,0,0,0,0,0,0,0,0,0,0,0,0~
,0,0,0,0,0,0,0,0,0,0)';
      BIDIRECTIONAL='TRUE';
      INPUT_LOAD='(-0.01,0.01)';
      OUTPUT_LOAD='(1.0,-1.0)';
      PINUSE='BI';
    'MJA_DQS_H3':
      PIN_NUMBER='(0,0,0,0,0,0,0,0,0,AE16,0,0,0,0,0,0,0,0,0,0,0,0,0,0,0,0,0,0,0,~
0,0,0,0,0,0,0,0,0,0,0)';
      BIDIRECTIONAL='TRUE';
      INPUT_LOAD='(-0.01,0.01)';
      OUTPUT_LOAD='(1.0,-1.0)';
      PINUSE='BI';
    'MJA_DQS_H2':
      PIN_NUMBER='(0,0,0,0,0,0,0,0,0,W16,0,0,0,0,0,0,0,0,0,0,0,0,0,0,0,0,0,0,0,0~
,0,0,0,0,0,0,0,0,0,0)';
      BIDIRECTIONAL='TRUE';
      INPUT_LOAD='(-0.01,0.01)';
      OUTPUT_LOAD='(1.0,-1.0)';
      PINUSE='BI';
    'MJA_DQS_H1':
      PIN_NUMBER='(0,0,0,0,0,0,0,0,0,N16,0,0,0,0,0,0,0,0,0,0,0,0,0,0,0,0,0,0,0,0~
,0,0,0,0,0,0,0,0,0,0)';
      BIDIRECTIONAL='TRUE';
      INPUT_LOAD='(-0.01,0.01)';
      OUTPUT_LOAD='(1.0,-1.0)';
      PINUSE='BI';
    'MJA_DQS_H0':
      PIN_NUMBER='(0,0,0,0,0,0,0,0,0,G16,0,0,0,0,0,0,0,0,0,0,0,0,0,0,0,0,0,0,0,0~
,0,0,0,0,0,0,0,0,0,0)';
      BIDIRECTIONAL='TRUE';
      INPUT_LOAD='(-0.01,0.01)';
      OUTPUT_LOAD='(1.0,-1.0)';
      PINUSE='BI';
    'MJA_DATA30':
      PIN_NUMBER='(0,0,0,0,0,0,0,0,0,AH16,0,0,0,0,0,0,0,0,0,0,0,0,0,0,0,0,0,0,0,~
0,0,0,0,0,0,0,0,0,0,0)';
      BIDIRECTIONAL='TRUE';
      INPUT_LOAD='(-0.01,0.01)';
      OUTPUT_LOAD='(1.0,-1.0)';
      PINUSE='BI';
    'MJA_DATA29':
      PIN_NUMBER='(0,0,0,0,0,0,0,0,0,AH18,0,0,0,0,0,0,0,0,0,0,0,0,0,0,0,0,0,0,0,~
0,0,0,0,0,0,0,0,0,0,0)';
      BIDIRECTIONAL='TRUE';
      INPUT_LOAD='(-0.01,0.01)';
      OUTPUT_LOAD='(1.0,-1.0)';
      PINUSE='BI';
    'MJA_DATA28':
      PIN_NUMBER='(0,0,0,0,0,0,0,0,0,AG16,0,0,0,0,0,0,0,0,0,0,0,0,0,0,0,0,0,0,0,~
0,0,0,0,0,0,0,0,0,0,0)';
      BIDIRECTIONAL='TRUE';
      INPUT_LOAD='(-0.01,0.01)';
      OUTPUT_LOAD='(1.0,-1.0)';
      PINUSE='BI';
    'MJA_DATA27':
      PIN_NUMBER='(0,0,0,0,0,0,0,0,0,AE17,0,0,0,0,0,0,0,0,0,0,0,0,0,0,0,0,0,0,0,~
0,0,0,0,0,0,0,0,0,0,0)';
      BIDIRECTIONAL='TRUE';
      INPUT_LOAD='(-0.01,0.01)';
      OUTPUT_LOAD='(1.0,-1.0)';
      PINUSE='BI';
    'MJA_DATA26':
      PIN_NUMBER='(0,0,0,0,0,0,0,0,0,AD16,0,0,0,0,0,0,0,0,0,0,0,0,0,0,0,0,0,0,0,~
0,0,0,0,0,0,0,0,0,0,0)';
      BIDIRECTIONAL='TRUE';
      INPUT_LOAD='(-0.01,0.01)';
      OUTPUT_LOAD='(1.0,-1.0)';
      PINUSE='BI';
    'MJA_DATA25':
      PIN_NUMBER='(0,0,0,0,0,0,0,0,0,AD18,0,0,0,0,0,0,0,0,0,0,0,0,0,0,0,0,0,0,0,~
0,0,0,0,0,0,0,0,0,0,0)';
      BIDIRECTIONAL='TRUE';
      INPUT_LOAD='(-0.01,0.01)';
      OUTPUT_LOAD='(1.0,-1.0)';
      PINUSE='BI';
    'MJA_DATA24':
      PIN_NUMBER='(0,0,0,0,0,0,0,0,0,AC16,0,0,0,0,0,0,0,0,0,0,0,0,0,0,0,0,0,0,0,~
0,0,0,0,0,0,0,0,0,0,0)';
      BIDIRECTIONAL='TRUE';
      INPUT_LOAD='(-0.01,0.01)';
      OUTPUT_LOAD='(1.0,-1.0)';
      PINUSE='BI';
    'MJA_DATA23':
      PIN_NUMBER='(0,0,0,0,0,0,0,0,0,AC17,0,0,0,0,0,0,0,0,0,0,0,0,0,0,0,0,0,0,0,~
0,0,0,0,0,0,0,0,0,0,0)';
      BIDIRECTIONAL='TRUE';
      INPUT_LOAD='(-0.01,0.01)';
      OUTPUT_LOAD='(1.0,-1.0)';
      PINUSE='BI';
    'MJA_DATA21':
      PIN_NUMBER='(0,0,0,0,0,0,0,0,0,AB18,0,0,0,0,0,0,0,0,0,0,0,0,0,0,0,0,0,0,0,~
0,0,0,0,0,0,0,0,0,0,0)';
      BIDIRECTIONAL='TRUE';
      INPUT_LOAD='(-0.01,0.01)';
      OUTPUT_LOAD='(1.0,-1.0)';
      PINUSE='BI';
    'MJA_DATA20':
      PIN_NUMBER='(0,0,0,0,0,0,0,0,0,AA16,0,0,0,0,0,0,0,0,0,0,0,0,0,0,0,0,0,0,0,~
0,0,0,0,0,0,0,0,0,0,0)';
      BIDIRECTIONAL='TRUE';
      INPUT_LOAD='(-0.01,0.01)';
      OUTPUT_LOAD='(1.0,-1.0)';
      PINUSE='BI';
    'MJA_DATA19':
      PIN_NUMBER='(0,0,0,0,0,0,0,0,0,W17,0,0,0,0,0,0,0,0,0,0,0,0,0,0,0,0,0,0,0,0~
,0,0,0,0,0,0,0,0,0,0)';
      BIDIRECTIONAL='TRUE';
      INPUT_LOAD='(-0.01,0.01)';
      OUTPUT_LOAD='(1.0,-1.0)';
      PINUSE='BI';
    'MJA_DATA18':
      PIN_NUMBER='(0,0,0,0,0,0,0,0,0,V16,0,0,0,0,0,0,0,0,0,0,0,0,0,0,0,0,0,0,0,0~
,0,0,0,0,0,0,0,0,0,0)';
      BIDIRECTIONAL='TRUE';
      INPUT_LOAD='(-0.01,0.01)';
      OUTPUT_LOAD='(1.0,-1.0)';
      PINUSE='BI';
    'MJA_DATA17':
      PIN_NUMBER='(0,0,0,0,0,0,0,0,0,V18,0,0,0,0,0,0,0,0,0,0,0,0,0,0,0,0,0,0,0,0~
,0,0,0,0,0,0,0,0,0,0)';
      BIDIRECTIONAL='TRUE';
      INPUT_LOAD='(-0.01,0.01)';
      OUTPUT_LOAD='(1.0,-1.0)';
      PINUSE='BI';
    'MJA_DATA16':
      PIN_NUMBER='(0,0,0,0,0,0,0,0,0,U16,0,0,0,0,0,0,0,0,0,0,0,0,0,0,0,0,0,0,0,0~
,0,0,0,0,0,0,0,0,0,0)';
      BIDIRECTIONAL='TRUE';
      INPUT_LOAD='(-0.01,0.01)';
      OUTPUT_LOAD='(1.0,-1.0)';
      PINUSE='BI';
    'MJA_DATA15':
      PIN_NUMBER='(0,0,0,0,0,0,0,0,0,U17,0,0,0,0,0,0,0,0,0,0,0,0,0,0,0,0,0,0,0,0~
,0,0,0,0,0,0,0,0,0,0)';
      BIDIRECTIONAL='TRUE';
      INPUT_LOAD='(-0.01,0.01)';
      OUTPUT_LOAD='(1.0,-1.0)';
      PINUSE='BI';
    'MJA_DATA14':
      PIN_NUMBER='(0,0,0,0,0,0,0,0,0,T16,0,0,0,0,0,0,0,0,0,0,0,0,0,0,0,0,0,0,0,0~
,0,0,0,0,0,0,0,0,0,0)';
      BIDIRECTIONAL='TRUE';
      INPUT_LOAD='(-0.01,0.01)';
      OUTPUT_LOAD='(1.0,-1.0)';
      PINUSE='BI';
    'MJA_DATA13':
      PIN_NUMBER='(0,0,0,0,0,0,0,0,0,T18,0,0,0,0,0,0,0,0,0,0,0,0,0,0,0,0,0,0,0,0~
,0,0,0,0,0,0,0,0,0,0)';
      BIDIRECTIONAL='TRUE';
      INPUT_LOAD='(-0.01,0.01)';
      OUTPUT_LOAD='(1.0,-1.0)';
      PINUSE='BI';
    'MJA_DATA12':
      PIN_NUMBER='(0,0,0,0,0,0,0,0,0,R16,0,0,0,0,0,0,0,0,0,0,0,0,0,0,0,0,0,0,0,0~
,0,0,0,0,0,0,0,0,0,0)';
      BIDIRECTIONAL='TRUE';
      INPUT_LOAD='(-0.01,0.01)';
      OUTPUT_LOAD='(1.0,-1.0)';
      PINUSE='BI';
    'MJA_DATA11':
      PIN_NUMBER='(0,0,0,0,0,0,0,0,0,N17,0,0,0,0,0,0,0,0,0,0,0,0,0,0,0,0,0,0,0,0~
,0,0,0,0,0,0,0,0,0,0)';
      BIDIRECTIONAL='TRUE';
      INPUT_LOAD='(-0.01,0.01)';
      OUTPUT_LOAD='(1.0,-1.0)';
      PINUSE='BI';
    'MJA_DATA10':
      PIN_NUMBER='(0,0,0,0,0,0,0,0,0,M16,0,0,0,0,0,0,0,0,0,0,0,0,0,0,0,0,0,0,0,0~
,0,0,0,0,0,0,0,0,0,0)';
      BIDIRECTIONAL='TRUE';
      INPUT_LOAD='(-0.01,0.01)';
      OUTPUT_LOAD='(1.0,-1.0)';
      PINUSE='BI';
    'MJA_DATA9':
      PIN_NUMBER='(0,0,0,0,0,0,0,0,0,M18,0,0,0,0,0,0,0,0,0,0,0,0,0,0,0,0,0,0,0,0~
,0,0,0,0,0,0,0,0,0,0)';
      BIDIRECTIONAL='TRUE';
      INPUT_LOAD='(-0.01,0.01)';
      OUTPUT_LOAD='(1.0,-1.0)';
      PINUSE='BI';
    'MJA_DATA8':
      PIN_NUMBER='(0,0,0,0,0,0,0,0,0,L16,0,0,0,0,0,0,0,0,0,0,0,0,0,0,0,0,0,0,0,0~
,0,0,0,0,0,0,0,0,0,0)';
      BIDIRECTIONAL='TRUE';
      INPUT_LOAD='(-0.01,0.01)';
      OUTPUT_LOAD='(1.0,-1.0)';
      PINUSE='BI';
    'MJA_DATA7':
      PIN_NUMBER='(0,0,0,0,0,0,0,0,0,L17,0,0,0,0,0,0,0,0,0,0,0,0,0,0,0,0,0,0,0,0~
,0,0,0,0,0,0,0,0,0,0)';
      BIDIRECTIONAL='TRUE';
      INPUT_LOAD='(-0.01,0.01)';
      OUTPUT_LOAD='(1.0,-1.0)';
      PINUSE='BI';
    'MJA_DATA6':
      PIN_NUMBER='(0,0,0,0,0,0,0,0,0,K16,0,0,0,0,0,0,0,0,0,0,0,0,0,0,0,0,0,0,0,0~
,0,0,0,0,0,0,0,0,0,0)';
      BIDIRECTIONAL='TRUE';
      INPUT_LOAD='(-0.01,0.01)';
      OUTPUT_LOAD='(1.0,-1.0)';
      PINUSE='BI';
    'MJA_DATA5':
      PIN_NUMBER='(0,0,0,0,0,0,0,0,0,K18,0,0,0,0,0,0,0,0,0,0,0,0,0,0,0,0,0,0,0,0~
,0,0,0,0,0,0,0,0,0,0)';
      BIDIRECTIONAL='TRUE';
      INPUT_LOAD='(-0.01,0.01)';
      OUTPUT_LOAD='(1.0,-1.0)';
      PINUSE='BI';
    'MJA_DATA4':
      PIN_NUMBER='(0,0,0,0,0,0,0,0,0,J16,0,0,0,0,0,0,0,0,0,0,0,0,0,0,0,0,0,0,0,0~
,0,0,0,0,0,0,0,0,0,0)';
      BIDIRECTIONAL='TRUE';
      INPUT_LOAD='(-0.01,0.01)';
      OUTPUT_LOAD='(1.0,-1.0)';
      PINUSE='BI';
    'MJA_DATA3':
      PIN_NUMBER='(0,0,0,0,0,0,0,0,0,G17,0,0,0,0,0,0,0,0,0,0,0,0,0,0,0,0,0,0,0,0~
,0,0,0,0,0,0,0,0,0,0)';
      BIDIRECTIONAL='TRUE';
      INPUT_LOAD='(-0.01,0.01)';
      OUTPUT_LOAD='(1.0,-1.0)';
      PINUSE='BI';
    'MJA_DATA2':
      PIN_NUMBER='(0,0,0,0,0,0,0,0,0,F16,0,0,0,0,0,0,0,0,0,0,0,0,0,0,0,0,0,0,0,0~
,0,0,0,0,0,0,0,0,0,0)';
      BIDIRECTIONAL='TRUE';
      INPUT_LOAD='(-0.01,0.01)';
      OUTPUT_LOAD='(1.0,-1.0)';
      PINUSE='BI';
    'MJA_DATA1':
      PIN_NUMBER='(0,0,0,0,0,0,0,0,0,F18,0,0,0,0,0,0,0,0,0,0,0,0,0,0,0,0,0,0,0,0~
,0,0,0,0,0,0,0,0,0,0)';
      BIDIRECTIONAL='TRUE';
      INPUT_LOAD='(-0.01,0.01)';
      OUTPUT_LOAD='(1.0,-1.0)';
      PINUSE='BI';
    'MJA_DATA0':
      PIN_NUMBER='(0,0,0,0,0,0,0,0,0,E16,0,0,0,0,0,0,0,0,0,0,0,0,0,0,0,0,0,0,0,0~
,0,0,0,0,0,0,0,0,0,0)';
      BIDIRECTIONAL='TRUE';
      INPUT_LOAD='(-0.01,0.01)';
      OUTPUT_LOAD='(1.0,-1.0)';
      PINUSE='BI';
    'MJA_CHECK7':
      PIN_NUMBER='(0,0,0,0,0,0,0,0,0,AR17,0,0,0,0,0,0,0,0,0,0,0,0,0,0,0,0,0,0,0,~
0,0,0,0,0,0,0,0,0,0,0)';
      BIDIRECTIONAL='TRUE';
      INPUT_LOAD='(-0.01,0.01)';
      OUTPUT_LOAD='(1.0,-1.0)';
      PINUSE='BI';
    'MJA_CHECK6':
      PIN_NUMBER='(0,0,0,0,0,0,0,0,0,AP16,0,0,0,0,0,0,0,0,0,0,0,0,0,0,0,0,0,0,0,~
0,0,0,0,0,0,0,0,0,0,0)';
      BIDIRECTIONAL='TRUE';
      INPUT_LOAD='(-0.01,0.01)';
      OUTPUT_LOAD='(1.0,-1.0)';
      PINUSE='BI';
    'MJA_CHECK5':
      PIN_NUMBER='(0,0,0,0,0,0,0,0,0,AP18,0,0,0,0,0,0,0,0,0,0,0,0,0,0,0,0,0,0,0,~
0,0,0,0,0,0,0,0,0,0,0)';
      BIDIRECTIONAL='TRUE';
      INPUT_LOAD='(-0.01,0.01)';
      OUTPUT_LOAD='(1.0,-1.0)';
      PINUSE='BI';
    'MJA_CHECK4':
      PIN_NUMBER='(0,0,0,0,0,0,0,0,0,AN16,0,0,0,0,0,0,0,0,0,0,0,0,0,0,0,0,0,0,0,~
0,0,0,0,0,0,0,0,0,0,0)';
      BIDIRECTIONAL='TRUE';
      INPUT_LOAD='(-0.01,0.01)';
      OUTPUT_LOAD='(1.0,-1.0)';
      PINUSE='BI';
    'MJA_CHECK3':
      PIN_NUMBER='(0,0,0,0,0,0,0,0,0,AL17,0,0,0,0,0,0,0,0,0,0,0,0,0,0,0,0,0,0,0,~
0,0,0,0,0,0,0,0,0,0,0)';
      BIDIRECTIONAL='TRUE';
      INPUT_LOAD='(-0.01,0.01)';
      OUTPUT_LOAD='(1.0,-1.0)';
      PINUSE='BI';
    'MJA_CHECK2':
      PIN_NUMBER='(0,0,0,0,0,0,0,0,0,AK16,0,0,0,0,0,0,0,0,0,0,0,0,0,0,0,0,0,0,0,~
0,0,0,0,0,0,0,0,0,0,0)';
      BIDIRECTIONAL='TRUE';
      INPUT_LOAD='(-0.01,0.01)';
      OUTPUT_LOAD='(1.0,-1.0)';
      PINUSE='BI';
    'MJA_CHECK1':
      PIN_NUMBER='(0,0,0,0,0,0,0,0,0,AK18,0,0,0,0,0,0,0,0,0,0,0,0,0,0,0,0,0,0,0,~
0,0,0,0,0,0,0,0,0,0,0)';
      BIDIRECTIONAL='TRUE';
      INPUT_LOAD='(-0.01,0.01)';
      OUTPUT_LOAD='(1.0,-1.0)';
      PINUSE='BI';
    'MJA_CHECK0':
      PIN_NUMBER='(0,0,0,0,0,0,0,0,0,AJ16,0,0,0,0,0,0,0,0,0,0,0,0,0,0,0,0,0,0,0,~
0,0,0,0,0,0,0,0,0,0,0)';
      BIDIRECTIONAL='TRUE';
      INPUT_LOAD='(-0.01,0.01)';
      OUTPUT_LOAD='(1.0,-1.0)';
      PINUSE='BI';
    'MJA_CA4':
      PIN_NUMBER='(0,0,0,0,0,0,0,0,0,BA16,0,0,0,0,0,0,0,0,0,0,0,0,0,0,0,0,0,0,0,~
0,0,0,0,0,0,0,0,0,0,0)';
      OUTPUT_LOAD='(1.0,-1.0)';
      PINUSE='OUT';
    'MJA_CA3':
      PIN_NUMBER='(0,0,0,0,0,0,0,0,0,BA17,0,0,0,0,0,0,0,0,0,0,0,0,0,0,0,0,0,0,0,~
0,0,0,0,0,0,0,0,0,0,0)';
      OUTPUT_LOAD='(1.0,-1.0)';
      PINUSE='OUT';
    'MJA_CA2':
      PIN_NUMBER='(0,0,0,0,0,0,0,0,0,AY18,0,0,0,0,0,0,0,0,0,0,0,0,0,0,0,0,0,0,0,~
0,0,0,0,0,0,0,0,0,0,0)';
      OUTPUT_LOAD='(1.0,-1.0)';
      PINUSE='OUT';
    'MJA_CA1':
      PIN_NUMBER='(0,0,0,0,0,0,0,0,0,AY16,0,0,0,0,0,0,0,0,0,0,0,0,0,0,0,0,0,0,0,~
0,0,0,0,0,0,0,0,0,0,0)';
      OUTPUT_LOAD='(1.0,-1.0)';
      PINUSE='OUT';
    'MJA_CA0':
      PIN_NUMBER='(0,0,0,0,0,0,0,0,0,AW16,0,0,0,0,0,0,0,0,0,0,0,0,0,0,0,0,0,0,0,~
0,0,0,0,0,0,0,0,0,0,0)';
      OUTPUT_LOAD='(1.0,-1.0)';
      PINUSE='OUT';
    'MJA1_RSP_L':
      PIN_NUMBER='(0,0,0,0,0,0,0,0,0,BP18,0,0,0,0,0,0,0,0,0,0,0,0,0,0,0,0,0,0,0,~
0,0,0,0,0,0,0,0,0,0,0)';
      INPUT_LOAD='(-0.01,0.01)';
      PINUSE='IN';
    'MJA1_CS_L1':
      PIN_NUMBER='(0,0,0,0,0,0,0,0,0,AW17,0,0,0,0,0,0,0,0,0,0,0,0,0,0,0,0,0,0,0,~
0,0,0,0,0,0,0,0,0,0,0)';
      OUTPUT_LOAD='(1.0,-1.0)';
      PINUSE='OUT';
    'MJA1_CS_L0':
      PIN_NUMBER='(0,0,0,0,0,0,0,0,0,AV16,0,0,0,0,0,0,0,0,0,0,0,0,0,0,0,0,0,0,0,~
0,0,0,0,0,0,0,0,0,0,0)';
      OUTPUT_LOAD='(1.0,-1.0)';
      PINUSE='OUT';
    'MJA0_RSP_L':
      PIN_NUMBER='(0,0,0,0,0,0,0,0,0,BN17,0,0,0,0,0,0,0,0,0,0,0,0,0,0,0,0,0,0,0,~
0,0,0,0,0,0,0,0,0,0,0)';
      INPUT_LOAD='(-0.01,0.01)';
      PINUSE='IN';
    'MJA0_CS_L1':
      PIN_NUMBER='(0,0,0,0,0,0,0,0,0,AV18,0,0,0,0,0,0,0,0,0,0,0,0,0,0,0,0,0,0,0,~
0,0,0,0,0,0,0,0,0,0,0)';
      OUTPUT_LOAD='(1.0,-1.0)';
      PINUSE='OUT';
    'MJA0_CS_L0':
      PIN_NUMBER='(0,0,0,0,0,0,0,0,0,AU16,0,0,0,0,0,0,0,0,0,0,0,0,0,0,0,0,0,0,0,~
0,0,0,0,0,0,0,0,0,0,0)';
      OUTPUT_LOAD='(1.0,-1.0)';
      PINUSE='OUT';
    'MJ1_CLK_L':
      PIN_NUMBER='(0,0,0,0,0,0,0,0,0,BG16,0,0,0,0,0,0,0,0,0,0,0,0,0,0,0,0,0,0,0,~
0,0,0,0,0,0,0,0,0,0,0)';
      OUTPUT_LOAD='(1.0,-1.0)';
      PINUSE='OUT';
    'MJ1_CLK_H':
      PIN_NUMBER='(0,0,0,0,0,0,0,0,0,BF16,0,0,0,0,0,0,0,0,0,0,0,0,0,0,0,0,0,0,0,~
0,0,0,0,0,0,0,0,0,0,0)';
      OUTPUT_LOAD='(1.0,-1.0)';
      PINUSE='OUT';
    'MJ0_CLK_L':
      PIN_NUMBER='(0,0,0,0,0,0,0,0,0,BD16,0,0,0,0,0,0,0,0,0,0,0,0,0,0,0,0,0,0,0,~
0,0,0,0,0,0,0,0,0,0,0)';
      OUTPUT_LOAD='(1.0,-1.0)';
      PINUSE='OUT';
    'MJ0_CLK_H':
      PIN_NUMBER='(0,0,0,0,0,0,0,0,0,BC16,0,0,0,0,0,0,0,0,0,0,0,0,0,0,0,0,0,0,0,~
0,0,0,0,0,0,0,0,0,0,0)';
      OUTPUT_LOAD='(1.0,-1.0)';
      PINUSE='OUT';
    'MJA_CA6':
      PIN_NUMBER='(0,0,0,0,0,0,0,0,0,BB18,0,0,0,0,0,0,0,0,0,0,0,0,0,0,0,0,0,0,0,~
0,0,0,0,0,0,0,0,0,0,0)';
      OUTPUT_LOAD='(1.0,-1.0)';
      PINUSE='OUT';
    'MJA_CA5':
      PIN_NUMBER='(0,0,0,0,0,0,0,0,0,BB16,0,0,0,0,0,0,0,0,0,0,0,0,0,0,0,0,0,0,0,~
0,0,0,0,0,0,0,0,0,0,0)';
      OUTPUT_LOAD='(1.0,-1.0)';
      PINUSE='OUT';
    'MJA_DATA22':
      PIN_NUMBER='(0,0,0,0,0,0,0,0,0,AB16,0,0,0,0,0,0,0,0,0,0,0,0,0,0,0,0,0,0,0,~
0,0,0,0,0,0,0,0,0,0,0)';
      BIDIRECTIONAL='TRUE';
      INPUT_LOAD='(-0.01,0.01)';
      OUTPUT_LOAD='(1.0,-1.0)';
      PINUSE='BI';
    'MJA_DQS_L7':
      PIN_NUMBER='(0,0,0,0,0,0,0,0,0,Y18,0,0,0,0,0,0,0,0,0,0,0,0,0,0,0,0,0,0,0,0~
,0,0,0,0,0,0,0,0,0,0)';
      BIDIRECTIONAL='TRUE';
      INPUT_LOAD='(-0.01,0.01)';
      OUTPUT_LOAD='(1.0,-1.0)';
      PINUSE='BI';
    'MJA_DQS_L5':
      PIN_NUMBER='(0,0,0,0,0,0,0,0,0,H18,0,0,0,0,0,0,0,0,0,0,0,0,0,0,0,0,0,0,0,0~
,0,0,0,0,0,0,0,0,0,0)';
      BIDIRECTIONAL='TRUE';
      INPUT_LOAD='(-0.01,0.01)';
      OUTPUT_LOAD='(1.0,-1.0)';
      PINUSE='BI';
    'MJA_DQS_L4':
      PIN_NUMBER='(0,0,0,0,0,0,0,0,0,AM16,0,0,0,0,0,0,0,0,0,0,0,0,0,0,0,0,0,0,0,~
0,0,0,0,0,0,0,0,0,0,0)';
      BIDIRECTIONAL='TRUE';
      INPUT_LOAD='(-0.01,0.01)';
      OUTPUT_LOAD='(1.0,-1.0)';
      PINUSE='BI';
    'MJA_DQS_H8':
      PIN_NUMBER='(0,0,0,0,0,0,0,0,0,AG17,0,0,0,0,0,0,0,0,0,0,0,0,0,0,0,0,0,0,0,~
0,0,0,0,0,0,0,0,0,0,0)';
      BIDIRECTIONAL='TRUE';
      INPUT_LOAD='(-0.01,0.01)';
      OUTPUT_LOAD='(1.0,-1.0)';
      PINUSE='BI';
    'MJA_DQS_H4':
      PIN_NUMBER='(0,0,0,0,0,0,0,0,0,AL16,0,0,0,0,0,0,0,0,0,0,0,0,0,0,0,0,0,0,0,~
0,0,0,0,0,0,0,0,0,0,0)';
      BIDIRECTIONAL='TRUE';
      INPUT_LOAD='(-0.01,0.01)';
      OUTPUT_LOAD='(1.0,-1.0)';
      PINUSE='BI';
    'MJB_DATA4':
      PIN_NUMBER='(0,0,0,0,0,0,0,0,0,CF16,0,0,0,0,0,0,0,0,0,0,0,0,0,0,0,0,0,0,0,~
0,0,0,0,0,0,0,0,0,0,0)';
      BIDIRECTIONAL='TRUE';
      INPUT_LOAD='(-0.01,0.01)';
      OUTPUT_LOAD='(1.0,-1.0)';
      PINUSE='BI';
    'MJB_DATA3':
      PIN_NUMBER='(0,0,0,0,0,0,0,0,0,CD18,0,0,0,0,0,0,0,0,0,0,0,0,0,0,0,0,0,0,0,~
0,0,0,0,0,0,0,0,0,0,0)';
      BIDIRECTIONAL='TRUE';
      INPUT_LOAD='(-0.01,0.01)';
      OUTPUT_LOAD='(1.0,-1.0)';
      PINUSE='BI';
    'MJB_DATA0':
      PIN_NUMBER='(0,0,0,0,0,0,0,0,0,CB16,0,0,0,0,0,0,0,0,0,0,0,0,0,0,0,0,0,0,0,~
0,0,0,0,0,0,0,0,0,0,0)';
      BIDIRECTIONAL='TRUE';
      INPUT_LOAD='(-0.01,0.01)';
      OUTPUT_LOAD='(1.0,-1.0)';
      PINUSE='BI';
    'MJA_DATA31':
      PIN_NUMBER='(0,0,0,0,0,0,0,0,0,AJ17,0,0,0,0,0,0,0,0,0,0,0,0,0,0,0,0,0,0,0,~
0,0,0,0,0,0,0,0,0,0,0)';
      BIDIRECTIONAL='TRUE';
      INPUT_LOAD='(-0.01,0.01)';
      OUTPUT_LOAD='(1.0,-1.0)';
      PINUSE='BI';
    'MJB_DQS_L0':
      PIN_NUMBER='(0,0,0,0,0,0,0,0,0,CE16,0,0,0,0,0,0,0,0,0,0,0,0,0,0,0,0,0,0,0,~
0,0,0,0,0,0,0,0,0,0,0)';
      BIDIRECTIONAL='TRUE';
      INPUT_LOAD='(-0.01,0.01)';
      OUTPUT_LOAD='(1.0,-1.0)';
      PINUSE='BI';
    'MJB_DQS_L4':
      PIN_NUMBER='(0,0,0,0,0,0,0,0,0,BW17,0,0,0,0,0,0,0,0,0,0,0,0,0,0,0,0,0,0,0,~
0,0,0,0,0,0,0,0,0,0,0)';
      BIDIRECTIONAL='TRUE';
      INPUT_LOAD='(-0.01,0.01)';
      OUTPUT_LOAD='(1.0,-1.0)';
      PINUSE='BI';
    'MJB_DQS_H5':
      PIN_NUMBER='(0,0,0,0,0,0,0,0,0,CF18,0,0,0,0,0,0,0,0,0,0,0,0,0,0,0,0,0,0,0,~
0,0,0,0,0,0,0,0,0,0,0)';
      BIDIRECTIONAL='TRUE';
      INPUT_LOAD='(-0.01,0.01)';
      OUTPUT_LOAD='(1.0,-1.0)';
      PINUSE='BI';
    'MJB_DATA5':
      PIN_NUMBER='(0,0,0,0,0,0,0,0,0,CG17,0,0,0,0,0,0,0,0,0,0,0,0,0,0,0,0,0,0,0,~
0,0,0,0,0,0,0,0,0,0,0)';
      BIDIRECTIONAL='TRUE';
      INPUT_LOAD='(-0.01,0.01)';
      OUTPUT_LOAD='(1.0,-1.0)';
      PINUSE='BI';
    'MJB_DATA6':
      PIN_NUMBER='(0,0,0,0,0,0,0,0,0,CG16,0,0,0,0,0,0,0,0,0,0,0,0,0,0,0,0,0,0,0,~
0,0,0,0,0,0,0,0,0,0,0)';
      BIDIRECTIONAL='TRUE';
      INPUT_LOAD='(-0.01,0.01)';
      OUTPUT_LOAD='(1.0,-1.0)';
      PINUSE='BI';
    'MJB_DATA7':
      PIN_NUMBER='(0,0,0,0,0,0,0,0,0,CH18,0,0,0,0,0,0,0,0,0,0,0,0,0,0,0,0,0,0,0,~
0,0,0,0,0,0,0,0,0,0,0)';
      BIDIRECTIONAL='TRUE';
      INPUT_LOAD='(-0.01,0.01)';
      OUTPUT_LOAD='(1.0,-1.0)';
      PINUSE='BI';
    'TEST39J':
      PIN_NUMBER='(0,0,0,0,0,0,0,0,0,BF18,0,0,0,0,0,0,0,0,0,0,0,0,0,0,0,0,0,0,0,~
0,0,0,0,0,0,0,0,0,0,0)';
      OUTPUT_LOAD='(1.0,-1.0)';
      PINUSE='OUT';
    'G0_RXN0':
      PIN_NUMBER='(0,0,0,0,0,0,0,0,0,0,M40,0,0,0,0,0,0,0,0,0,0,0,0,0,0,0,0,0,0,0~
,0,0,0,0,0,0,0,0,0,0)';
      INPUT_LOAD='(-0.01,0.01)';
      PINUSE='IN';
    'G0_RXN1':
      PIN_NUMBER='(0,0,0,0,0,0,0,0,0,0,K40,0,0,0,0,0,0,0,0,0,0,0,0,0,0,0,0,0,0,0~
,0,0,0,0,0,0,0,0,0,0)';
      INPUT_LOAD='(-0.01,0.01)';
      PINUSE='IN';
    'G0_RXN2':
      PIN_NUMBER='(0,0,0,0,0,0,0,0,0,0,H40,0,0,0,0,0,0,0,0,0,0,0,0,0,0,0,0,0,0,0~
,0,0,0,0,0,0,0,0,0,0)';
      INPUT_LOAD='(-0.01,0.01)';
      PINUSE='IN';
    'G0_RXN3':
      PIN_NUMBER='(0,0,0,0,0,0,0,0,0,0,L43,0,0,0,0,0,0,0,0,0,0,0,0,0,0,0,0,0,0,0~
,0,0,0,0,0,0,0,0,0,0)';
      INPUT_LOAD='(-0.01,0.01)';
      PINUSE='IN';
    'G0_RXN4':
      PIN_NUMBER='(0,0,0,0,0,0,0,0,0,0,G43,0,0,0,0,0,0,0,0,0,0,0,0,0,0,0,0,0,0,0~
,0,0,0,0,0,0,0,0,0,0)';
      INPUT_LOAD='(-0.01,0.01)';
      PINUSE='IN';
    'G0_RXN5':
      PIN_NUMBER='(0,0,0,0,0,0,0,0,0,0,J43,0,0,0,0,0,0,0,0,0,0,0,0,0,0,0,0,0,0,0~
,0,0,0,0,0,0,0,0,0,0)';
      INPUT_LOAD='(-0.01,0.01)';
      PINUSE='IN';
    'G0_RXN6':
      PIN_NUMBER='(0,0,0,0,0,0,0,0,0,0,L46,0,0,0,0,0,0,0,0,0,0,0,0,0,0,0,0,0,0,0~
,0,0,0,0,0,0,0,0,0,0)';
      INPUT_LOAD='(-0.01,0.01)';
      PINUSE='IN';
    'G0_RXN7':
      PIN_NUMBER='(0,0,0,0,0,0,0,0,0,0,G46,0,0,0,0,0,0,0,0,0,0,0,0,0,0,0,0,0,0,0~
,0,0,0,0,0,0,0,0,0,0)';
      INPUT_LOAD='(-0.01,0.01)';
      PINUSE='IN';
    'G0_RXN8':
      PIN_NUMBER='(0,0,0,0,0,0,0,0,0,0,J46,0,0,0,0,0,0,0,0,0,0,0,0,0,0,0,0,0,0,0~
,0,0,0,0,0,0,0,0,0,0)';
      INPUT_LOAD='(-0.01,0.01)';
      PINUSE='IN';
    'G0_RXN9':
      PIN_NUMBER='(0,0,0,0,0,0,0,0,0,0,L49,0,0,0,0,0,0,0,0,0,0,0,0,0,0,0,0,0,0,0~
,0,0,0,0,0,0,0,0,0,0)';
      INPUT_LOAD='(-0.01,0.01)';
      PINUSE='IN';
    'G0_RXN10':
      PIN_NUMBER='(0,0,0,0,0,0,0,0,0,0,G49,0,0,0,0,0,0,0,0,0,0,0,0,0,0,0,0,0,0,0~
,0,0,0,0,0,0,0,0,0,0)';
      INPUT_LOAD='(-0.01,0.01)';
      PINUSE='IN';
    'G0_RXN11':
      PIN_NUMBER='(0,0,0,0,0,0,0,0,0,0,J49,0,0,0,0,0,0,0,0,0,0,0,0,0,0,0,0,0,0,0~
,0,0,0,0,0,0,0,0,0,0)';
      INPUT_LOAD='(-0.01,0.01)';
      PINUSE='IN';
    'G0_RXN12':
      PIN_NUMBER='(0,0,0,0,0,0,0,0,0,0,L52,0,0,0,0,0,0,0,0,0,0,0,0,0,0,0,0,0,0,0~
,0,0,0,0,0,0,0,0,0,0)';
      INPUT_LOAD='(-0.01,0.01)';
      PINUSE='IN';
    'G0_RXN13':
      PIN_NUMBER='(0,0,0,0,0,0,0,0,0,0,G52,0,0,0,0,0,0,0,0,0,0,0,0,0,0,0,0,0,0,0~
,0,0,0,0,0,0,0,0,0,0)';
      INPUT_LOAD='(-0.01,0.01)';
      PINUSE='IN';
    'G0_RXN14':
      PIN_NUMBER='(0,0,0,0,0,0,0,0,0,0,J52,0,0,0,0,0,0,0,0,0,0,0,0,0,0,0,0,0,0,0~
,0,0,0,0,0,0,0,0,0,0)';
      INPUT_LOAD='(-0.01,0.01)';
      PINUSE='IN';
    'G0_RXN15':
      PIN_NUMBER='(0,0,0,0,0,0,0,0,0,0,N52,0,0,0,0,0,0,0,0,0,0,0,0,0,0,0,0,0,0,0~
,0,0,0,0,0,0,0,0,0,0)';
      INPUT_LOAD='(-0.01,0.01)';
      PINUSE='IN';
    'G0_RXP0':
      PIN_NUMBER='(0,0,0,0,0,0,0,0,0,0,M41,0,0,0,0,0,0,0,0,0,0,0,0,0,0,0,0,0,0,0~
,0,0,0,0,0,0,0,0,0,0)';
      INPUT_LOAD='(-0.01,0.01)';
      PINUSE='IN';
    'G0_RXP1':
      PIN_NUMBER='(0,0,0,0,0,0,0,0,0,0,K41,0,0,0,0,0,0,0,0,0,0,0,0,0,0,0,0,0,0,0~
,0,0,0,0,0,0,0,0,0,0)';
      INPUT_LOAD='(-0.01,0.01)';
      PINUSE='IN';
    'G0_RXP2':
      PIN_NUMBER='(0,0,0,0,0,0,0,0,0,0,H41,0,0,0,0,0,0,0,0,0,0,0,0,0,0,0,0,0,0,0~
,0,0,0,0,0,0,0,0,0,0)';
      INPUT_LOAD='(-0.01,0.01)';
      PINUSE='IN';
    'G0_RXP3':
      PIN_NUMBER='(0,0,0,0,0,0,0,0,0,0,L44,0,0,0,0,0,0,0,0,0,0,0,0,0,0,0,0,0,0,0~
,0,0,0,0,0,0,0,0,0,0)';
      INPUT_LOAD='(-0.01,0.01)';
      PINUSE='IN';
    'G0_RXP4':
      PIN_NUMBER='(0,0,0,0,0,0,0,0,0,0,G44,0,0,0,0,0,0,0,0,0,0,0,0,0,0,0,0,0,0,0~
,0,0,0,0,0,0,0,0,0,0)';
      INPUT_LOAD='(-0.01,0.01)';
      PINUSE='IN';
    'G0_RXP5':
      PIN_NUMBER='(0,0,0,0,0,0,0,0,0,0,J44,0,0,0,0,0,0,0,0,0,0,0,0,0,0,0,0,0,0,0~
,0,0,0,0,0,0,0,0,0,0)';
      INPUT_LOAD='(-0.01,0.01)';
      PINUSE='IN';
    'G0_RXP6':
      PIN_NUMBER='(0,0,0,0,0,0,0,0,0,0,L47,0,0,0,0,0,0,0,0,0,0,0,0,0,0,0,0,0,0,0~
,0,0,0,0,0,0,0,0,0,0)';
      INPUT_LOAD='(-0.01,0.01)';
      PINUSE='IN';
    'G0_RXP7':
      PIN_NUMBER='(0,0,0,0,0,0,0,0,0,0,G47,0,0,0,0,0,0,0,0,0,0,0,0,0,0,0,0,0,0,0~
,0,0,0,0,0,0,0,0,0,0)';
      INPUT_LOAD='(-0.01,0.01)';
      PINUSE='IN';
    'G0_RXP8':
      PIN_NUMBER='(0,0,0,0,0,0,0,0,0,0,J47,0,0,0,0,0,0,0,0,0,0,0,0,0,0,0,0,0,0,0~
,0,0,0,0,0,0,0,0,0,0)';
      INPUT_LOAD='(-0.01,0.01)';
      PINUSE='IN';
    'G0_RXP9':
      PIN_NUMBER='(0,0,0,0,0,0,0,0,0,0,L50,0,0,0,0,0,0,0,0,0,0,0,0,0,0,0,0,0,0,0~
,0,0,0,0,0,0,0,0,0,0)';
      INPUT_LOAD='(-0.01,0.01)';
      PINUSE='IN';
    'G0_RXP10':
      PIN_NUMBER='(0,0,0,0,0,0,0,0,0,0,G50,0,0,0,0,0,0,0,0,0,0,0,0,0,0,0,0,0,0,0~
,0,0,0,0,0,0,0,0,0,0)';
      INPUT_LOAD='(-0.01,0.01)';
      PINUSE='IN';
    'G0_RXP11':
      PIN_NUMBER='(0,0,0,0,0,0,0,0,0,0,J50,0,0,0,0,0,0,0,0,0,0,0,0,0,0,0,0,0,0,0~
,0,0,0,0,0,0,0,0,0,0)';
      INPUT_LOAD='(-0.01,0.01)';
      PINUSE='IN';
    'G0_RXP12':
      PIN_NUMBER='(0,0,0,0,0,0,0,0,0,0,L53,0,0,0,0,0,0,0,0,0,0,0,0,0,0,0,0,0,0,0~
,0,0,0,0,0,0,0,0,0,0)';
      INPUT_LOAD='(-0.01,0.01)';
      PINUSE='IN';
    'G0_RXP13':
      PIN_NUMBER='(0,0,0,0,0,0,0,0,0,0,G53,0,0,0,0,0,0,0,0,0,0,0,0,0,0,0,0,0,0,0~
,0,0,0,0,0,0,0,0,0,0)';
      INPUT_LOAD='(-0.01,0.01)';
      PINUSE='IN';
    'G0_RXP14':
      PIN_NUMBER='(0,0,0,0,0,0,0,0,0,0,J53,0,0,0,0,0,0,0,0,0,0,0,0,0,0,0,0,0,0,0~
,0,0,0,0,0,0,0,0,0,0)';
      INPUT_LOAD='(-0.01,0.01)';
      PINUSE='IN';
    'G0_RXP15':
      PIN_NUMBER='(0,0,0,0,0,0,0,0,0,0,N53,0,0,0,0,0,0,0,0,0,0,0,0,0,0,0,0,0,0,0~
,0,0,0,0,0,0,0,0,0,0)';
      INPUT_LOAD='(-0.01,0.01)';
      PINUSE='IN';
    'G0_TXN0':
      PIN_NUMBER='(0,0,0,0,0,0,0,0,0,0,AF41,0,0,0,0,0,0,0,0,0,0,0,0,0,0,0,0,0,0,~
0,0,0,0,0,0,0,0,0,0,0)';
      OUTPUT_LOAD='(1.0,-1.0)';
      PINUSE='OUT';
    'G0_TXN1':
      PIN_NUMBER='(0,0,0,0,0,0,0,0,0,0,AD41,0,0,0,0,0,0,0,0,0,0,0,0,0,0,0,0,0,0,~
0,0,0,0,0,0,0,0,0,0,0)';
      OUTPUT_LOAD='(1.0,-1.0)';
      PINUSE='OUT';
    'G0_TXN2':
      PIN_NUMBER='(0,0,0,0,0,0,0,0,0,0,AB41,0,0,0,0,0,0,0,0,0,0,0,0,0,0,0,0,0,0,~
0,0,0,0,0,0,0,0,0,0,0)';
      OUTPUT_LOAD='(1.0,-1.0)';
      PINUSE='OUT';
    'G0_TXN3':
      PIN_NUMBER='(0,0,0,0,0,0,0,0,0,0,AG44,0,0,0,0,0,0,0,0,0,0,0,0,0,0,0,0,0,0,~
0,0,0,0,0,0,0,0,0,0,0)';
      OUTPUT_LOAD='(1.0,-1.0)';
      PINUSE='OUT';
    'G0_TXN4':
      PIN_NUMBER='(0,0,0,0,0,0,0,0,0,0,AA44,0,0,0,0,0,0,0,0,0,0,0,0,0,0,0,0,0,0,~
0,0,0,0,0,0,0,0,0,0,0)';
      OUTPUT_LOAD='(1.0,-1.0)';
      PINUSE='OUT';
    'G0_TXN5':
      PIN_NUMBER='(0,0,0,0,0,0,0,0,0,0,AC44,0,0,0,0,0,0,0,0,0,0,0,0,0,0,0,0,0,0,~
0,0,0,0,0,0,0,0,0,0,0)';
      OUTPUT_LOAD='(1.0,-1.0)';
      PINUSE='OUT';
    'G0_TXN6':
      PIN_NUMBER='(0,0,0,0,0,0,0,0,0,0,AE44,0,0,0,0,0,0,0,0,0,0,0,0,0,0,0,0,0,0,~
0,0,0,0,0,0,0,0,0,0,0)';
      OUTPUT_LOAD='(1.0,-1.0)';
      PINUSE='OUT';
    'G0_TXN7':
      PIN_NUMBER='(0,0,0,0,0,0,0,0,0,0,AG47,0,0,0,0,0,0,0,0,0,0,0,0,0,0,0,0,0,0,~
0,0,0,0,0,0,0,0,0,0,0)';
      OUTPUT_LOAD='(1.0,-1.0)';
      PINUSE='OUT';
    'G0_TXN8':
      PIN_NUMBER='(0,0,0,0,0,0,0,0,0,0,AC47,0,0,0,0,0,0,0,0,0,0,0,0,0,0,0,0,0,0,~
0,0,0,0,0,0,0,0,0,0,0)';
      OUTPUT_LOAD='(1.0,-1.0)';
      PINUSE='OUT';
    'G0_TXN9':
      PIN_NUMBER='(0,0,0,0,0,0,0,0,0,0,AE47,0,0,0,0,0,0,0,0,0,0,0,0,0,0,0,0,0,0,~
0,0,0,0,0,0,0,0,0,0,0)';
      OUTPUT_LOAD='(1.0,-1.0)';
      PINUSE='OUT';
    'G0_TXN10':
      PIN_NUMBER='(0,0,0,0,0,0,0,0,0,0,AG50,0,0,0,0,0,0,0,0,0,0,0,0,0,0,0,0,0,0,~
0,0,0,0,0,0,0,0,0,0,0)';
      OUTPUT_LOAD='(1.0,-1.0)';
      PINUSE='OUT';
    'G0_TXN11':
      PIN_NUMBER='(0,0,0,0,0,0,0,0,0,0,AC50,0,0,0,0,0,0,0,0,0,0,0,0,0,0,0,0,0,0,~
0,0,0,0,0,0,0,0,0,0,0)';
      OUTPUT_LOAD='(1.0,-1.0)';
      PINUSE='OUT';
    'G0_TXN12':
      PIN_NUMBER='(0,0,0,0,0,0,0,0,0,0,AE50,0,0,0,0,0,0,0,0,0,0,0,0,0,0,0,0,0,0,~
0,0,0,0,0,0,0,0,0,0,0)';
      OUTPUT_LOAD='(1.0,-1.0)';
      PINUSE='OUT';
    'G0_TXN13':
      PIN_NUMBER='(0,0,0,0,0,0,0,0,0,0,AG53,0,0,0,0,0,0,0,0,0,0,0,0,0,0,0,0,0,0,~
0,0,0,0,0,0,0,0,0,0,0)';
      OUTPUT_LOAD='(1.0,-1.0)';
      PINUSE='OUT';
    'G0_TXN14':
      PIN_NUMBER='(0,0,0,0,0,0,0,0,0,0,AC53,0,0,0,0,0,0,0,0,0,0,0,0,0,0,0,0,0,0,~
0,0,0,0,0,0,0,0,0,0,0)';
      OUTPUT_LOAD='(1.0,-1.0)';
      PINUSE='OUT';
    'G0_TXN15':
      PIN_NUMBER='(0,0,0,0,0,0,0,0,0,0,AE53,0,0,0,0,0,0,0,0,0,0,0,0,0,0,0,0,0,0,~
0,0,0,0,0,0,0,0,0,0,0)';
      OUTPUT_LOAD='(1.0,-1.0)';
      PINUSE='OUT';
    'G0_TXP0':
      PIN_NUMBER='(0,0,0,0,0,0,0,0,0,0,AF40,0,0,0,0,0,0,0,0,0,0,0,0,0,0,0,0,0,0,~
0,0,0,0,0,0,0,0,0,0,0)';
      OUTPUT_LOAD='(1.0,-1.0)';
      PINUSE='OUT';
    'G0_TXP1':
      PIN_NUMBER='(0,0,0,0,0,0,0,0,0,0,AD40,0,0,0,0,0,0,0,0,0,0,0,0,0,0,0,0,0,0,~
0,0,0,0,0,0,0,0,0,0,0)';
      OUTPUT_LOAD='(1.0,-1.0)';
      PINUSE='OUT';
    'G0_TXP2':
      PIN_NUMBER='(0,0,0,0,0,0,0,0,0,0,AB40,0,0,0,0,0,0,0,0,0,0,0,0,0,0,0,0,0,0,~
0,0,0,0,0,0,0,0,0,0,0)';
      OUTPUT_LOAD='(1.0,-1.0)';
      PINUSE='OUT';
    'G0_TXP3':
      PIN_NUMBER='(0,0,0,0,0,0,0,0,0,0,AG43,0,0,0,0,0,0,0,0,0,0,0,0,0,0,0,0,0,0,~
0,0,0,0,0,0,0,0,0,0,0)';
      OUTPUT_LOAD='(1.0,-1.0)';
      PINUSE='OUT';
    'G0_TXP4':
      PIN_NUMBER='(0,0,0,0,0,0,0,0,0,0,AA43,0,0,0,0,0,0,0,0,0,0,0,0,0,0,0,0,0,0,~
0,0,0,0,0,0,0,0,0,0,0)';
      OUTPUT_LOAD='(1.0,-1.0)';
      PINUSE='OUT';
    'G0_TXP5':
      PIN_NUMBER='(0,0,0,0,0,0,0,0,0,0,AC43,0,0,0,0,0,0,0,0,0,0,0,0,0,0,0,0,0,0,~
0,0,0,0,0,0,0,0,0,0,0)';
      OUTPUT_LOAD='(1.0,-1.0)';
      PINUSE='OUT';
    'G0_TXP6':
      PIN_NUMBER='(0,0,0,0,0,0,0,0,0,0,AE43,0,0,0,0,0,0,0,0,0,0,0,0,0,0,0,0,0,0,~
0,0,0,0,0,0,0,0,0,0,0)';
      OUTPUT_LOAD='(1.0,-1.0)';
      PINUSE='OUT';
    'G0_TXP7':
      PIN_NUMBER='(0,0,0,0,0,0,0,0,0,0,AG46,0,0,0,0,0,0,0,0,0,0,0,0,0,0,0,0,0,0,~
0,0,0,0,0,0,0,0,0,0,0)';
      OUTPUT_LOAD='(1.0,-1.0)';
      PINUSE='OUT';
    'G0_TXP8':
      PIN_NUMBER='(0,0,0,0,0,0,0,0,0,0,AC46,0,0,0,0,0,0,0,0,0,0,0,0,0,0,0,0,0,0,~
0,0,0,0,0,0,0,0,0,0,0)';
      OUTPUT_LOAD='(1.0,-1.0)';
      PINUSE='OUT';
    'G0_TXP9':
      PIN_NUMBER='(0,0,0,0,0,0,0,0,0,0,AE46,0,0,0,0,0,0,0,0,0,0,0,0,0,0,0,0,0,0,~
0,0,0,0,0,0,0,0,0,0,0)';
      OUTPUT_LOAD='(1.0,-1.0)';
      PINUSE='OUT';
    'G0_TXP10':
      PIN_NUMBER='(0,0,0,0,0,0,0,0,0,0,AG49,0,0,0,0,0,0,0,0,0,0,0,0,0,0,0,0,0,0,~
0,0,0,0,0,0,0,0,0,0,0)';
      OUTPUT_LOAD='(1.0,-1.0)';
      PINUSE='OUT';
    'G0_TXP11':
      PIN_NUMBER='(0,0,0,0,0,0,0,0,0,0,AC49,0,0,0,0,0,0,0,0,0,0,0,0,0,0,0,0,0,0,~
0,0,0,0,0,0,0,0,0,0,0)';
      OUTPUT_LOAD='(1.0,-1.0)';
      PINUSE='OUT';
    'G0_TXP12':
      PIN_NUMBER='(0,0,0,0,0,0,0,0,0,0,AE49,0,0,0,0,0,0,0,0,0,0,0,0,0,0,0,0,0,0,~
0,0,0,0,0,0,0,0,0,0,0)';
      OUTPUT_LOAD='(1.0,-1.0)';
      PINUSE='OUT';
    'G0_TXP13':
      PIN_NUMBER='(0,0,0,0,0,0,0,0,0,0,AG52,0,0,0,0,0,0,0,0,0,0,0,0,0,0,0,0,0,0,~
0,0,0,0,0,0,0,0,0,0,0)';
      OUTPUT_LOAD='(1.0,-1.0)';
      PINUSE='OUT';
    'G0_TXP14':
      PIN_NUMBER='(0,0,0,0,0,0,0,0,0,0,AC52,0,0,0,0,0,0,0,0,0,0,0,0,0,0,0,0,0,0,~
0,0,0,0,0,0,0,0,0,0,0)';
      OUTPUT_LOAD='(1.0,-1.0)';
      PINUSE='OUT';
    'G0_TXP15':
      PIN_NUMBER='(0,0,0,0,0,0,0,0,0,0,AE52,0,0,0,0,0,0,0,0,0,0,0,0,0,0,0,0,0,0,~
0,0,0,0,0,0,0,0,0,0,0)';
      OUTPUT_LOAD='(1.0,-1.0)';
      PINUSE='OUT';
    'G1_TXP15':
      PIN_NUMBER='(0,0,0,0,0,0,0,0,0,0,0,AL52,0,0,0,0,0,0,0,0,0,0,0,0,0,0,0,0,0,~
0,0,0,0,0,0,0,0,0,0,0)';
      OUTPUT_LOAD='(1.0,-1.0)';
      PINUSE='OUT';
    'G1_TXP14':
      PIN_NUMBER='(0,0,0,0,0,0,0,0,0,0,0,AJ52,0,0,0,0,0,0,0,0,0,0,0,0,0,0,0,0,0,~
0,0,0,0,0,0,0,0,0,0,0)';
      OUTPUT_LOAD='(1.0,-1.0)';
      PINUSE='OUT';
    'G1_TXP13':
      PIN_NUMBER='(0,0,0,0,0,0,0,0,0,0,0,AN52,0,0,0,0,0,0,0,0,0,0,0,0,0,0,0,0,0,~
0,0,0,0,0,0,0,0,0,0,0)';
      OUTPUT_LOAD='(1.0,-1.0)';
      PINUSE='OUT';
    'G1_TXP12':
      PIN_NUMBER='(0,0,0,0,0,0,0,0,0,0,0,AL49,0,0,0,0,0,0,0,0,0,0,0,0,0,0,0,0,0,~
0,0,0,0,0,0,0,0,0,0,0)';
      OUTPUT_LOAD='(1.0,-1.0)';
      PINUSE='OUT';
    'G1_TXP11':
      PIN_NUMBER='(0,0,0,0,0,0,0,0,0,0,0,AJ49,0,0,0,0,0,0,0,0,0,0,0,0,0,0,0,0,0,~
0,0,0,0,0,0,0,0,0,0,0)';
      OUTPUT_LOAD='(1.0,-1.0)';
      PINUSE='OUT';
    'G1_TXP10':
      PIN_NUMBER='(0,0,0,0,0,0,0,0,0,0,0,AN49,0,0,0,0,0,0,0,0,0,0,0,0,0,0,0,0,0,~
0,0,0,0,0,0,0,0,0,0,0)';
      OUTPUT_LOAD='(1.0,-1.0)';
      PINUSE='OUT';
    'G1_TXP9':
      PIN_NUMBER='(0,0,0,0,0,0,0,0,0,0,0,AL46,0,0,0,0,0,0,0,0,0,0,0,0,0,0,0,0,0,~
0,0,0,0,0,0,0,0,0,0,0)';
      OUTPUT_LOAD='(1.0,-1.0)';
      PINUSE='OUT';
    'G1_TXP8':
      PIN_NUMBER='(0,0,0,0,0,0,0,0,0,0,0,AJ46,0,0,0,0,0,0,0,0,0,0,0,0,0,0,0,0,0,~
0,0,0,0,0,0,0,0,0,0,0)';
      OUTPUT_LOAD='(1.0,-1.0)';
      PINUSE='OUT';
    'G1_TXN15':
      PIN_NUMBER='(0,0,0,0,0,0,0,0,0,0,0,AL53,0,0,0,0,0,0,0,0,0,0,0,0,0,0,0,0,0,~
0,0,0,0,0,0,0,0,0,0,0)';
      OUTPUT_LOAD='(1.0,-1.0)';
      PINUSE='OUT';
    'G1_TXN14':
      PIN_NUMBER='(0,0,0,0,0,0,0,0,0,0,0,AJ53,0,0,0,0,0,0,0,0,0,0,0,0,0,0,0,0,0,~
0,0,0,0,0,0,0,0,0,0,0)';
      OUTPUT_LOAD='(1.0,-1.0)';
      PINUSE='OUT';
    'G1_TXN13':
      PIN_NUMBER='(0,0,0,0,0,0,0,0,0,0,0,AN53,0,0,0,0,0,0,0,0,0,0,0,0,0,0,0,0,0,~
0,0,0,0,0,0,0,0,0,0,0)';
      OUTPUT_LOAD='(1.0,-1.0)';
      PINUSE='OUT';
    'G1_TXN12':
      PIN_NUMBER='(0,0,0,0,0,0,0,0,0,0,0,AL50,0,0,0,0,0,0,0,0,0,0,0,0,0,0,0,0,0,~
0,0,0,0,0,0,0,0,0,0,0)';
      OUTPUT_LOAD='(1.0,-1.0)';
      PINUSE='OUT';
    'G1_TXN11':
      PIN_NUMBER='(0,0,0,0,0,0,0,0,0,0,0,AJ50,0,0,0,0,0,0,0,0,0,0,0,0,0,0,0,0,0,~
0,0,0,0,0,0,0,0,0,0,0)';
      OUTPUT_LOAD='(1.0,-1.0)';
      PINUSE='OUT';
    'G1_TXN10':
      PIN_NUMBER='(0,0,0,0,0,0,0,0,0,0,0,AN50,0,0,0,0,0,0,0,0,0,0,0,0,0,0,0,0,0,~
0,0,0,0,0,0,0,0,0,0,0)';
      OUTPUT_LOAD='(1.0,-1.0)';
      PINUSE='OUT';
    'G1_TXN9':
      PIN_NUMBER='(0,0,0,0,0,0,0,0,0,0,0,AL47,0,0,0,0,0,0,0,0,0,0,0,0,0,0,0,0,0,~
0,0,0,0,0,0,0,0,0,0,0)';
      OUTPUT_LOAD='(1.0,-1.0)';
      PINUSE='OUT';
    'G1_TXN8':
      PIN_NUMBER='(0,0,0,0,0,0,0,0,0,0,0,AJ47,0,0,0,0,0,0,0,0,0,0,0,0,0,0,0,0,0,~
0,0,0,0,0,0,0,0,0,0,0)';
      OUTPUT_LOAD='(1.0,-1.0)';
      PINUSE='OUT';
    'G1_RXP15':
      PIN_NUMBER='(0,0,0,0,0,0,0,0,0,0,0,U53,0,0,0,0,0,0,0,0,0,0,0,0,0,0,0,0,0,0~
,0,0,0,0,0,0,0,0,0,0)';
      INPUT_LOAD='(-0.01,0.01)';
      PINUSE='IN';
    'G1_RXP14':
      PIN_NUMBER='(0,0,0,0,0,0,0,0,0,0,0,R53,0,0,0,0,0,0,0,0,0,0,0,0,0,0,0,0,0,0~
,0,0,0,0,0,0,0,0,0,0)';
      INPUT_LOAD='(-0.01,0.01)';
      PINUSE='IN';
    'G1_RXP13':
      PIN_NUMBER='(0,0,0,0,0,0,0,0,0,0,0,W53,0,0,0,0,0,0,0,0,0,0,0,0,0,0,0,0,0,0~
,0,0,0,0,0,0,0,0,0,0)';
      INPUT_LOAD='(-0.01,0.01)';
      PINUSE='IN';
    'G1_RXP12':
      PIN_NUMBER='(0,0,0,0,0,0,0,0,0,0,0,U50,0,0,0,0,0,0,0,0,0,0,0,0,0,0,0,0,0,0~
,0,0,0,0,0,0,0,0,0,0)';
      INPUT_LOAD='(-0.01,0.01)';
      PINUSE='IN';
    'G1_RXP11':
      PIN_NUMBER='(0,0,0,0,0,0,0,0,0,0,0,R50,0,0,0,0,0,0,0,0,0,0,0,0,0,0,0,0,0,0~
,0,0,0,0,0,0,0,0,0,0)';
      INPUT_LOAD='(-0.01,0.01)';
      PINUSE='IN';
    'G1_RXP10':
      PIN_NUMBER='(0,0,0,0,0,0,0,0,0,0,0,N50,0,0,0,0,0,0,0,0,0,0,0,0,0,0,0,0,0,0~
,0,0,0,0,0,0,0,0,0,0)';
      INPUT_LOAD='(-0.01,0.01)';
      PINUSE='IN';
    'G1_RXP9':
      PIN_NUMBER='(0,0,0,0,0,0,0,0,0,0,0,W50,0,0,0,0,0,0,0,0,0,0,0,0,0,0,0,0,0,0~
,0,0,0,0,0,0,0,0,0,0)';
      INPUT_LOAD='(-0.01,0.01)';
      PINUSE='IN';
    'G1_RXP8':
      PIN_NUMBER='(0,0,0,0,0,0,0,0,0,0,0,R47,0,0,0,0,0,0,0,0,0,0,0,0,0,0,0,0,0,0~
,0,0,0,0,0,0,0,0,0,0)';
      INPUT_LOAD='(-0.01,0.01)';
      PINUSE='IN';
    'G1_RXN15':
      PIN_NUMBER='(0,0,0,0,0,0,0,0,0,0,0,U52,0,0,0,0,0,0,0,0,0,0,0,0,0,0,0,0,0,0~
,0,0,0,0,0,0,0,0,0,0)';
      INPUT_LOAD='(-0.01,0.01)';
      PINUSE='IN';
    'G1_RXN14':
      PIN_NUMBER='(0,0,0,0,0,0,0,0,0,0,0,R52,0,0,0,0,0,0,0,0,0,0,0,0,0,0,0,0,0,0~
,0,0,0,0,0,0,0,0,0,0)';
      INPUT_LOAD='(-0.01,0.01)';
      PINUSE='IN';
    'G1_RXN13':
      PIN_NUMBER='(0,0,0,0,0,0,0,0,0,0,0,W52,0,0,0,0,0,0,0,0,0,0,0,0,0,0,0,0,0,0~
,0,0,0,0,0,0,0,0,0,0)';
      INPUT_LOAD='(-0.01,0.01)';
      PINUSE='IN';
    'G1_RXN12':
      PIN_NUMBER='(0,0,0,0,0,0,0,0,0,0,0,U49,0,0,0,0,0,0,0,0,0,0,0,0,0,0,0,0,0,0~
,0,0,0,0,0,0,0,0,0,0)';
      INPUT_LOAD='(-0.01,0.01)';
      PINUSE='IN';
    'G1_RXN11':
      PIN_NUMBER='(0,0,0,0,0,0,0,0,0,0,0,R49,0,0,0,0,0,0,0,0,0,0,0,0,0,0,0,0,0,0~
,0,0,0,0,0,0,0,0,0,0)';
      INPUT_LOAD='(-0.01,0.01)';
      PINUSE='IN';
    'G1_RXN10':
      PIN_NUMBER='(0,0,0,0,0,0,0,0,0,0,0,N49,0,0,0,0,0,0,0,0,0,0,0,0,0,0,0,0,0,0~
,0,0,0,0,0,0,0,0,0,0)';
      INPUT_LOAD='(-0.01,0.01)';
      PINUSE='IN';
    'G1_RXN9':
      PIN_NUMBER='(0,0,0,0,0,0,0,0,0,0,0,W49,0,0,0,0,0,0,0,0,0,0,0,0,0,0,0,0,0,0~
,0,0,0,0,0,0,0,0,0,0)';
      INPUT_LOAD='(-0.01,0.01)';
      PINUSE='IN';
    'G1_RXN8':
      PIN_NUMBER='(0,0,0,0,0,0,0,0,0,0,0,R46,0,0,0,0,0,0,0,0,0,0,0,0,0,0,0,0,0,0~
,0,0,0,0,0,0,0,0,0,0)';
      INPUT_LOAD='(-0.01,0.01)';
      PINUSE='IN';
    'G1_TXP0':
      PIN_NUMBER='(0,0,0,0,0,0,0,0,0,0,0,AP40,0,0,0,0,0,0,0,0,0,0,0,0,0,0,0,0,0,~
0,0,0,0,0,0,0,0,0,0,0)';
      OUTPUT_LOAD='(1.0,-1.0)';
      PINUSE='OUT';
    'G1_TXP1':
      PIN_NUMBER='(0,0,0,0,0,0,0,0,0,0,0,AM40,0,0,0,0,0,0,0,0,0,0,0,0,0,0,0,0,0,~
0,0,0,0,0,0,0,0,0,0,0)';
      OUTPUT_LOAD='(1.0,-1.0)';
      PINUSE='OUT';
    'G1_TXP2':
      PIN_NUMBER='(0,0,0,0,0,0,0,0,0,0,0,AH40,0,0,0,0,0,0,0,0,0,0,0,0,0,0,0,0,0,~
0,0,0,0,0,0,0,0,0,0,0)';
      OUTPUT_LOAD='(1.0,-1.0)';
      PINUSE='OUT';
    'G1_TXN0':
      PIN_NUMBER='(0,0,0,0,0,0,0,0,0,0,0,AP41,0,0,0,0,0,0,0,0,0,0,0,0,0,0,0,0,0,~
0,0,0,0,0,0,0,0,0,0,0)';
      OUTPUT_LOAD='(1.0,-1.0)';
      PINUSE='OUT';
    'G1_RXP0':
      PIN_NUMBER='(0,0,0,0,0,0,0,0,0,0,0,V41,0,0,0,0,0,0,0,0,0,0,0,0,0,0,0,0,0,0~
,0,0,0,0,0,0,0,0,0,0)';
      INPUT_LOAD='(-0.01,0.01)';
      PINUSE='IN';
    'G1_TXP3':
      PIN_NUMBER='(0,0,0,0,0,0,0,0,0,0,0,AK40,0,0,0,0,0,0,0,0,0,0,0,0,0,0,0,0,0,~
0,0,0,0,0,0,0,0,0,0,0)';
      OUTPUT_LOAD='(1.0,-1.0)';
      PINUSE='OUT';
    'G1_TXN1':
      PIN_NUMBER='(0,0,0,0,0,0,0,0,0,0,0,AM41,0,0,0,0,0,0,0,0,0,0,0,0,0,0,0,0,0,~
0,0,0,0,0,0,0,0,0,0,0)';
      OUTPUT_LOAD='(1.0,-1.0)';
      PINUSE='OUT';
    'G1_RXP1':
      PIN_NUMBER='(0,0,0,0,0,0,0,0,0,0,0,T41,0,0,0,0,0,0,0,0,0,0,0,0,0,0,0,0,0,0~
,0,0,0,0,0,0,0,0,0,0)';
      INPUT_LOAD='(-0.01,0.01)';
      PINUSE='IN';
    'G1_TXP4':
      PIN_NUMBER='(0,0,0,0,0,0,0,0,0,0,0,AN43,0,0,0,0,0,0,0,0,0,0,0,0,0,0,0,0,0,~
0,0,0,0,0,0,0,0,0,0,0)';
      OUTPUT_LOAD='(1.0,-1.0)';
      PINUSE='OUT';
    'G1_TXN2':
      PIN_NUMBER='(0,0,0,0,0,0,0,0,0,0,0,AH41,0,0,0,0,0,0,0,0,0,0,0,0,0,0,0,0,0,~
0,0,0,0,0,0,0,0,0,0,0)';
      OUTPUT_LOAD='(1.0,-1.0)';
      PINUSE='OUT';
    'G1_RXP2':
      PIN_NUMBER='(0,0,0,0,0,0,0,0,0,0,0,P41,0,0,0,0,0,0,0,0,0,0,0,0,0,0,0,0,0,0~
,0,0,0,0,0,0,0,0,0,0)';
      INPUT_LOAD='(-0.01,0.01)';
      PINUSE='IN';
    'G1_RXN0':
      PIN_NUMBER='(0,0,0,0,0,0,0,0,0,0,0,V40,0,0,0,0,0,0,0,0,0,0,0,0,0,0,0,0,0,0~
,0,0,0,0,0,0,0,0,0,0)';
      INPUT_LOAD='(-0.01,0.01)';
      PINUSE='IN';
    'G1_TXP5':
      PIN_NUMBER='(0,0,0,0,0,0,0,0,0,0,0,AJ43,0,0,0,0,0,0,0,0,0,0,0,0,0,0,0,0,0,~
0,0,0,0,0,0,0,0,0,0,0)';
      OUTPUT_LOAD='(1.0,-1.0)';
      PINUSE='OUT';
    'G1_TXN3':
      PIN_NUMBER='(0,0,0,0,0,0,0,0,0,0,0,AK41,0,0,0,0,0,0,0,0,0,0,0,0,0,0,0,0,0,~
0,0,0,0,0,0,0,0,0,0,0)';
      OUTPUT_LOAD='(1.0,-1.0)';
      PINUSE='OUT';
    'G1_RXP3':
      PIN_NUMBER='(0,0,0,0,0,0,0,0,0,0,0,U44,0,0,0,0,0,0,0,0,0,0,0,0,0,0,0,0,0,0~
,0,0,0,0,0,0,0,0,0,0)';
      INPUT_LOAD='(-0.01,0.01)';
      PINUSE='IN';
    'G1_RXN1':
      PIN_NUMBER='(0,0,0,0,0,0,0,0,0,0,0,T40,0,0,0,0,0,0,0,0,0,0,0,0,0,0,0,0,0,0~
,0,0,0,0,0,0,0,0,0,0)';
      INPUT_LOAD='(-0.01,0.01)';
      PINUSE='IN';
    'G1_TXP6':
      PIN_NUMBER='(0,0,0,0,0,0,0,0,0,0,0,AL43,0,0,0,0,0,0,0,0,0,0,0,0,0,0,0,0,0,~
0,0,0,0,0,0,0,0,0,0,0)';
      OUTPUT_LOAD='(1.0,-1.0)';
      PINUSE='OUT';
    'G1_TXN4':
      PIN_NUMBER='(0,0,0,0,0,0,0,0,0,0,0,AN44,0,0,0,0,0,0,0,0,0,0,0,0,0,0,0,0,0,~
0,0,0,0,0,0,0,0,0,0,0)';
      OUTPUT_LOAD='(1.0,-1.0)';
      PINUSE='OUT';
    'G1_RXP4':
      PIN_NUMBER='(0,0,0,0,0,0,0,0,0,0,0,N44,0,0,0,0,0,0,0,0,0,0,0,0,0,0,0,0,0,0~
,0,0,0,0,0,0,0,0,0,0)';
      INPUT_LOAD='(-0.01,0.01)';
      PINUSE='IN';
    'G1_RXN2':
      PIN_NUMBER='(0,0,0,0,0,0,0,0,0,0,0,P40,0,0,0,0,0,0,0,0,0,0,0,0,0,0,0,0,0,0~
,0,0,0,0,0,0,0,0,0,0)';
      INPUT_LOAD='(-0.01,0.01)';
      PINUSE='IN';
    'G1_TXP7':
      PIN_NUMBER='(0,0,0,0,0,0,0,0,0,0,0,AN46,0,0,0,0,0,0,0,0,0,0,0,0,0,0,0,0,0,~
0,0,0,0,0,0,0,0,0,0,0)';
      OUTPUT_LOAD='(1.0,-1.0)';
      PINUSE='OUT';
    'G1_TXN5':
      PIN_NUMBER='(0,0,0,0,0,0,0,0,0,0,0,AJ44,0,0,0,0,0,0,0,0,0,0,0,0,0,0,0,0,0,~
0,0,0,0,0,0,0,0,0,0,0)';
      OUTPUT_LOAD='(1.0,-1.0)';
      PINUSE='OUT';
    'G1_RXP5':
      PIN_NUMBER='(0,0,0,0,0,0,0,0,0,0,0,R44,0,0,0,0,0,0,0,0,0,0,0,0,0,0,0,0,0,0~
,0,0,0,0,0,0,0,0,0,0)';
      INPUT_LOAD='(-0.01,0.01)';
      PINUSE='IN';
    'G1_RXN3':
      PIN_NUMBER='(0,0,0,0,0,0,0,0,0,0,0,U43,0,0,0,0,0,0,0,0,0,0,0,0,0,0,0,0,0,0~
,0,0,0,0,0,0,0,0,0,0)';
      INPUT_LOAD='(-0.01,0.01)';
      PINUSE='IN';
    'G1_TXN6':
      PIN_NUMBER='(0,0,0,0,0,0,0,0,0,0,0,AL44,0,0,0,0,0,0,0,0,0,0,0,0,0,0,0,0,0,~
0,0,0,0,0,0,0,0,0,0,0)';
      OUTPUT_LOAD='(1.0,-1.0)';
      PINUSE='OUT';
    'G1_RXP6':
      PIN_NUMBER='(0,0,0,0,0,0,0,0,0,0,0,U47,0,0,0,0,0,0,0,0,0,0,0,0,0,0,0,0,0,0~
,0,0,0,0,0,0,0,0,0,0)';
      INPUT_LOAD='(-0.01,0.01)';
      PINUSE='IN';
    'G1_RXN4':
      PIN_NUMBER='(0,0,0,0,0,0,0,0,0,0,0,N43,0,0,0,0,0,0,0,0,0,0,0,0,0,0,0,0,0,0~
,0,0,0,0,0,0,0,0,0,0)';
      INPUT_LOAD='(-0.01,0.01)';
      PINUSE='IN';
    'G1_TXN7':
      PIN_NUMBER='(0,0,0,0,0,0,0,0,0,0,0,AN47,0,0,0,0,0,0,0,0,0,0,0,0,0,0,0,0,0,~
0,0,0,0,0,0,0,0,0,0,0)';
      OUTPUT_LOAD='(1.0,-1.0)';
      PINUSE='OUT';
    'G1_RXP7':
      PIN_NUMBER='(0,0,0,0,0,0,0,0,0,0,0,N47,0,0,0,0,0,0,0,0,0,0,0,0,0,0,0,0,0,0~
,0,0,0,0,0,0,0,0,0,0)';
      INPUT_LOAD='(-0.01,0.01)';
      PINUSE='IN';
    'G1_RXN5':
      PIN_NUMBER='(0,0,0,0,0,0,0,0,0,0,0,R43,0,0,0,0,0,0,0,0,0,0,0,0,0,0,0,0,0,0~
,0,0,0,0,0,0,0,0,0,0)';
      INPUT_LOAD='(-0.01,0.01)';
      PINUSE='IN';
    'G1_RXN6':
      PIN_NUMBER='(0,0,0,0,0,0,0,0,0,0,0,U46,0,0,0,0,0,0,0,0,0,0,0,0,0,0,0,0,0,0~
,0,0,0,0,0,0,0,0,0,0)';
      INPUT_LOAD='(-0.01,0.01)';
      PINUSE='IN';
    'G1_RXN7':
      PIN_NUMBER='(0,0,0,0,0,0,0,0,0,0,0,N46,0,0,0,0,0,0,0,0,0,0,0,0,0,0,0,0,0,0~
,0,0,0,0,0,0,0,0,0,0)';
      INPUT_LOAD='(-0.01,0.01)';
      PINUSE='IN';
    'G2_TXP8':
      PIN_NUMBER='(0,0,0,0,0,0,0,0,0,0,0,0,G29,0,0,0,0,0,0,0,0,0,0,0,0,0,0,0,0,0~
,0,0,0,0,0,0,0,0,0,0)';
      OUTPUT_LOAD='(1.0,-1.0)';
      PINUSE='OUT';
    'G2_TXN8':
      PIN_NUMBER='(0,0,0,0,0,0,0,0,0,0,0,0,G30,0,0,0,0,0,0,0,0,0,0,0,0,0,0,0,0,0~
,0,0,0,0,0,0,0,0,0,0)';
      OUTPUT_LOAD='(1.0,-1.0)';
      PINUSE='OUT';
    'G2_TXP10':
      PIN_NUMBER='(0,0,0,0,0,0,0,0,0,0,0,0,J32,0,0,0,0,0,0,0,0,0,0,0,0,0,0,0,0,0~
,0,0,0,0,0,0,0,0,0,0)';
      OUTPUT_LOAD='(1.0,-1.0)';
      PINUSE='OUT';
    'G2_TXN10':
      PIN_NUMBER='(0,0,0,0,0,0,0,0,0,0,0,0,J33,0,0,0,0,0,0,0,0,0,0,0,0,0,0,0,0,0~
,0,0,0,0,0,0,0,0,0,0)';
      OUTPUT_LOAD='(1.0,-1.0)';
      PINUSE='OUT';
    'G2_TXP12':
      PIN_NUMBER='(0,0,0,0,0,0,0,0,0,0,0,0,L32,0,0,0,0,0,0,0,0,0,0,0,0,0,0,0,0,0~
,0,0,0,0,0,0,0,0,0,0)';
      OUTPUT_LOAD='(1.0,-1.0)';
      PINUSE='OUT';
    'G2_TXN12':
      PIN_NUMBER='(0,0,0,0,0,0,0,0,0,0,0,0,L33,0,0,0,0,0,0,0,0,0,0,0,0,0,0,0,0,0~
,0,0,0,0,0,0,0,0,0,0)';
      OUTPUT_LOAD='(1.0,-1.0)';
      PINUSE='OUT';
    'G2_TXP14':
      PIN_NUMBER='(0,0,0,0,0,0,0,0,0,0,0,0,K35,0,0,0,0,0,0,0,0,0,0,0,0,0,0,0,0,0~
,0,0,0,0,0,0,0,0,0,0)';
      OUTPUT_LOAD='(1.0,-1.0)';
      PINUSE='OUT';
    'G2_TXN14':
      PIN_NUMBER='(0,0,0,0,0,0,0,0,0,0,0,0,K36,0,0,0,0,0,0,0,0,0,0,0,0,0,0,0,0,0~
,0,0,0,0,0,0,0,0,0,0)';
      OUTPUT_LOAD='(1.0,-1.0)';
      PINUSE='OUT';
    'G2_TXP9':
      PIN_NUMBER='(0,0,0,0,0,0,0,0,0,0,0,0,L29,0,0,0,0,0,0,0,0,0,0,0,0,0,0,0,0,0~
,0,0,0,0,0,0,0,0,0,0)';
      OUTPUT_LOAD='(1.0,-1.0)';
      PINUSE='OUT';
    'G2_TXN9':
      PIN_NUMBER='(0,0,0,0,0,0,0,0,0,0,0,0,L30,0,0,0,0,0,0,0,0,0,0,0,0,0,0,0,0,0~
,0,0,0,0,0,0,0,0,0,0)';
      OUTPUT_LOAD='(1.0,-1.0)';
      PINUSE='OUT';
    'G2_TXP11':
      PIN_NUMBER='(0,0,0,0,0,0,0,0,0,0,0,0,G32,0,0,0,0,0,0,0,0,0,0,0,0,0,0,0,0,0~
,0,0,0,0,0,0,0,0,0,0)';
      OUTPUT_LOAD='(1.0,-1.0)';
      PINUSE='OUT';
    'G2_TXN11':
      PIN_NUMBER='(0,0,0,0,0,0,0,0,0,0,0,0,G33,0,0,0,0,0,0,0,0,0,0,0,0,0,0,0,0,0~
,0,0,0,0,0,0,0,0,0,0)';
      OUTPUT_LOAD='(1.0,-1.0)';
      PINUSE='OUT';
    'G2_TXP13':
      PIN_NUMBER='(0,0,0,0,0,0,0,0,0,0,0,0,H35,0,0,0,0,0,0,0,0,0,0,0,0,0,0,0,0,0~
,0,0,0,0,0,0,0,0,0,0)';
      OUTPUT_LOAD='(1.0,-1.0)';
      PINUSE='OUT';
    'G2_TXN13':
      PIN_NUMBER='(0,0,0,0,0,0,0,0,0,0,0,0,H36,0,0,0,0,0,0,0,0,0,0,0,0,0,0,0,0,0~
,0,0,0,0,0,0,0,0,0,0)';
      OUTPUT_LOAD='(1.0,-1.0)';
      PINUSE='OUT';
    'G2_TXP15':
      PIN_NUMBER='(0,0,0,0,0,0,0,0,0,0,0,0,M35,0,0,0,0,0,0,0,0,0,0,0,0,0,0,0,0,0~
,0,0,0,0,0,0,0,0,0,0)';
      OUTPUT_LOAD='(1.0,-1.0)';
      PINUSE='OUT';
    'G2_TXN15':
      PIN_NUMBER='(0,0,0,0,0,0,0,0,0,0,0,0,M36,0,0,0,0,0,0,0,0,0,0,0,0,0,0,0,0,0~
,0,0,0,0,0,0,0,0,0,0)';
      OUTPUT_LOAD='(1.0,-1.0)';
      PINUSE='OUT';
    'G2_RXP8':
      PIN_NUMBER='(0,0,0,0,0,0,0,0,0,0,0,0,AG30,0,0,0,0,0,0,0,0,0,0,0,0,0,0,0,0,~
0,0,0,0,0,0,0,0,0,0,0)';
      INPUT_LOAD='(-0.01,0.01)';
      PINUSE='IN';
    'G2_RXN8':
      PIN_NUMBER='(0,0,0,0,0,0,0,0,0,0,0,0,AG29,0,0,0,0,0,0,0,0,0,0,0,0,0,0,0,0,~
0,0,0,0,0,0,0,0,0,0,0)';
      INPUT_LOAD='(-0.01,0.01)';
      PINUSE='IN';
    'G2_RXP10':
      PIN_NUMBER='(0,0,0,0,0,0,0,0,0,0,0,0,AC33,0,0,0,0,0,0,0,0,0,0,0,0,0,0,0,0,~
0,0,0,0,0,0,0,0,0,0,0)';
      INPUT_LOAD='(-0.01,0.01)';
      PINUSE='IN';
    'G2_RXN10':
      PIN_NUMBER='(0,0,0,0,0,0,0,0,0,0,0,0,AC32,0,0,0,0,0,0,0,0,0,0,0,0,0,0,0,0,~
0,0,0,0,0,0,0,0,0,0,0)';
      INPUT_LOAD='(-0.01,0.01)';
      PINUSE='IN';
    'G2_RXP12':
      PIN_NUMBER='(0,0,0,0,0,0,0,0,0,0,0,0,AG33,0,0,0,0,0,0,0,0,0,0,0,0,0,0,0,0,~
0,0,0,0,0,0,0,0,0,0,0)';
      INPUT_LOAD='(-0.01,0.01)';
      PINUSE='IN';
    'G2_RXN12':
      PIN_NUMBER='(0,0,0,0,0,0,0,0,0,0,0,0,AG32,0,0,0,0,0,0,0,0,0,0,0,0,0,0,0,0,~
0,0,0,0,0,0,0,0,0,0,0)';
      INPUT_LOAD='(-0.01,0.01)';
      PINUSE='IN';
    'G2_RXP14':
      PIN_NUMBER='(0,0,0,0,0,0,0,0,0,0,0,0,AD36,0,0,0,0,0,0,0,0,0,0,0,0,0,0,0,0,~
0,0,0,0,0,0,0,0,0,0,0)';
      INPUT_LOAD='(-0.01,0.01)';
      PINUSE='IN';
    'G2_RXN14':
      PIN_NUMBER='(0,0,0,0,0,0,0,0,0,0,0,0,AD35,0,0,0,0,0,0,0,0,0,0,0,0,0,0,0,0,~
0,0,0,0,0,0,0,0,0,0,0)';
      INPUT_LOAD='(-0.01,0.01)';
      PINUSE='IN';
    'G2_RXP9':
      PIN_NUMBER='(0,0,0,0,0,0,0,0,0,0,0,0,AE33,0,0,0,0,0,0,0,0,0,0,0,0,0,0,0,0,~
0,0,0,0,0,0,0,0,0,0,0)';
      INPUT_LOAD='(-0.01,0.01)';
      PINUSE='IN';
    'G2_RXN9':
      PIN_NUMBER='(0,0,0,0,0,0,0,0,0,0,0,0,AE32,0,0,0,0,0,0,0,0,0,0,0,0,0,0,0,0,~
0,0,0,0,0,0,0,0,0,0,0)';
      INPUT_LOAD='(-0.01,0.01)';
      PINUSE='IN';
    'G2_RXP11':
      PIN_NUMBER='(0,0,0,0,0,0,0,0,0,0,0,0,AA33,0,0,0,0,0,0,0,0,0,0,0,0,0,0,0,0,~
0,0,0,0,0,0,0,0,0,0,0)';
      INPUT_LOAD='(-0.01,0.01)';
      PINUSE='IN';
    'G2_RXN11':
      PIN_NUMBER='(0,0,0,0,0,0,0,0,0,0,0,0,AA32,0,0,0,0,0,0,0,0,0,0,0,0,0,0,0,0,~
0,0,0,0,0,0,0,0,0,0,0)';
      INPUT_LOAD='(-0.01,0.01)';
      PINUSE='IN';
    'G2_RXP13':
      PIN_NUMBER='(0,0,0,0,0,0,0,0,0,0,0,0,AB36,0,0,0,0,0,0,0,0,0,0,0,0,0,0,0,0,~
0,0,0,0,0,0,0,0,0,0,0)';
      INPUT_LOAD='(-0.01,0.01)';
      PINUSE='IN';
    'G2_RXN13':
      PIN_NUMBER='(0,0,0,0,0,0,0,0,0,0,0,0,AB35,0,0,0,0,0,0,0,0,0,0,0,0,0,0,0,0,~
0,0,0,0,0,0,0,0,0,0,0)';
      INPUT_LOAD='(-0.01,0.01)';
      PINUSE='IN';
    'G2_RXP15':
      PIN_NUMBER='(0,0,0,0,0,0,0,0,0,0,0,0,AF36,0,0,0,0,0,0,0,0,0,0,0,0,0,0,0,0,~
0,0,0,0,0,0,0,0,0,0,0)';
      INPUT_LOAD='(-0.01,0.01)';
      PINUSE='IN';
    'G2_RXN15':
      PIN_NUMBER='(0,0,0,0,0,0,0,0,0,0,0,0,AF35,0,0,0,0,0,0,0,0,0,0,0,0,0,0,0,0,~
0,0,0,0,0,0,0,0,0,0,0)';
      INPUT_LOAD='(-0.01,0.01)';
      PINUSE='IN';
    'G2_TXP1':
      PIN_NUMBER='(0,0,0,0,0,0,0,0,0,0,0,0,J23,0,0,0,0,0,0,0,0,0,0,0,0,0,0,0,0,0~
,0,0,0,0,0,0,0,0,0,0)';
      OUTPUT_LOAD='(1.0,-1.0)';
      PINUSE='OUT';
    'G2_TXP2':
      PIN_NUMBER='(0,0,0,0,0,0,0,0,0,0,0,0,G23,0,0,0,0,0,0,0,0,0,0,0,0,0,0,0,0,0~
,0,0,0,0,0,0,0,0,0,0)';
      OUTPUT_LOAD='(1.0,-1.0)';
      PINUSE='OUT';
    'G2_TXN0':
      PIN_NUMBER='(0,0,0,0,0,0,0,0,0,0,0,0,N24,0,0,0,0,0,0,0,0,0,0,0,0,0,0,0,0,0~
,0,0,0,0,0,0,0,0,0,0)';
      OUTPUT_LOAD='(1.0,-1.0)';
      PINUSE='OUT';
    'G2_RXP0':
      PIN_NUMBER='(0,0,0,0,0,0,0,0,0,0,0,0,AE24,0,0,0,0,0,0,0,0,0,0,0,0,0,0,0,0,~
0,0,0,0,0,0,0,0,0,0,0)';
      INPUT_LOAD='(-0.01,0.01)';
      PINUSE='IN';
    'G2_TXP3':
      PIN_NUMBER='(0,0,0,0,0,0,0,0,0,0,0,0,L23,0,0,0,0,0,0,0,0,0,0,0,0,0,0,0,0,0~
,0,0,0,0,0,0,0,0,0,0)';
      OUTPUT_LOAD='(1.0,-1.0)';
      PINUSE='OUT';
    'G2_TXN1':
      PIN_NUMBER='(0,0,0,0,0,0,0,0,0,0,0,0,J24,0,0,0,0,0,0,0,0,0,0,0,0,0,0,0,0,0~
,0,0,0,0,0,0,0,0,0,0)';
      OUTPUT_LOAD='(1.0,-1.0)';
      PINUSE='OUT';
    'G2_RXP1':
      PIN_NUMBER='(0,0,0,0,0,0,0,0,0,0,0,0,AC24,0,0,0,0,0,0,0,0,0,0,0,0,0,0,0,0,~
0,0,0,0,0,0,0,0,0,0,0)';
      INPUT_LOAD='(-0.01,0.01)';
      PINUSE='IN';
    'G2_TXP4':
      PIN_NUMBER='(0,0,0,0,0,0,0,0,0,0,0,0,J26,0,0,0,0,0,0,0,0,0,0,0,0,0,0,0,0,0~
,0,0,0,0,0,0,0,0,0,0)';
      OUTPUT_LOAD='(1.0,-1.0)';
      PINUSE='OUT';
    'G2_TXN2':
      PIN_NUMBER='(0,0,0,0,0,0,0,0,0,0,0,0,G24,0,0,0,0,0,0,0,0,0,0,0,0,0,0,0,0,0~
,0,0,0,0,0,0,0,0,0,0)';
      OUTPUT_LOAD='(1.0,-1.0)';
      PINUSE='OUT';
    'G2_RXP2':
      PIN_NUMBER='(0,0,0,0,0,0,0,0,0,0,0,0,AG24,0,0,0,0,0,0,0,0,0,0,0,0,0,0,0,0,~
0,0,0,0,0,0,0,0,0,0,0)';
      INPUT_LOAD='(-0.01,0.01)';
      PINUSE='IN';
    'G2_RXN0':
      PIN_NUMBER='(0,0,0,0,0,0,0,0,0,0,0,0,AE23,0,0,0,0,0,0,0,0,0,0,0,0,0,0,0,0,~
0,0,0,0,0,0,0,0,0,0,0)';
      INPUT_LOAD='(-0.01,0.01)';
      PINUSE='IN';
    'G2_TXP5':
      PIN_NUMBER='(0,0,0,0,0,0,0,0,0,0,0,0,G26,0,0,0,0,0,0,0,0,0,0,0,0,0,0,0,0,0~
,0,0,0,0,0,0,0,0,0,0)';
      OUTPUT_LOAD='(1.0,-1.0)';
      PINUSE='OUT';
    'G2_TXN3':
      PIN_NUMBER='(0,0,0,0,0,0,0,0,0,0,0,0,L24,0,0,0,0,0,0,0,0,0,0,0,0,0,0,0,0,0~
,0,0,0,0,0,0,0,0,0,0)';
      OUTPUT_LOAD='(1.0,-1.0)';
      PINUSE='OUT';
    'G2_RXP3':
      PIN_NUMBER='(0,0,0,0,0,0,0,0,0,0,0,0,AE27,0,0,0,0,0,0,0,0,0,0,0,0,0,0,0,0,~
0,0,0,0,0,0,0,0,0,0,0)';
      INPUT_LOAD='(-0.01,0.01)';
      PINUSE='IN';
    'G2_RXN1':
      PIN_NUMBER='(0,0,0,0,0,0,0,0,0,0,0,0,AC23,0,0,0,0,0,0,0,0,0,0,0,0,0,0,0,0,~
0,0,0,0,0,0,0,0,0,0,0)';
      INPUT_LOAD='(-0.01,0.01)';
      PINUSE='IN';
    'G2_TXP6':
      PIN_NUMBER='(0,0,0,0,0,0,0,0,0,0,0,0,L26,0,0,0,0,0,0,0,0,0,0,0,0,0,0,0,0,0~
,0,0,0,0,0,0,0,0,0,0)';
      OUTPUT_LOAD='(1.0,-1.0)';
      PINUSE='OUT';
    'G2_TXN4':
      PIN_NUMBER='(0,0,0,0,0,0,0,0,0,0,0,0,J27,0,0,0,0,0,0,0,0,0,0,0,0,0,0,0,0,0~
,0,0,0,0,0,0,0,0,0,0)';
      OUTPUT_LOAD='(1.0,-1.0)';
      PINUSE='OUT';
    'G2_RXP4':
      PIN_NUMBER='(0,0,0,0,0,0,0,0,0,0,0,0,AC27,0,0,0,0,0,0,0,0,0,0,0,0,0,0,0,0,~
0,0,0,0,0,0,0,0,0,0,0)';
      INPUT_LOAD='(-0.01,0.01)';
      PINUSE='IN';
    'G2_RXN2':
      PIN_NUMBER='(0,0,0,0,0,0,0,0,0,0,0,0,AG23,0,0,0,0,0,0,0,0,0,0,0,0,0,0,0,0,~
0,0,0,0,0,0,0,0,0,0,0)';
      INPUT_LOAD='(-0.01,0.01)';
      PINUSE='IN';
    'G2_TXP7':
      PIN_NUMBER='(0,0,0,0,0,0,0,0,0,0,0,0,J29,0,0,0,0,0,0,0,0,0,0,0,0,0,0,0,0,0~
,0,0,0,0,0,0,0,0,0,0)';
      OUTPUT_LOAD='(1.0,-1.0)';
      PINUSE='OUT';
    'G2_TXN5':
      PIN_NUMBER='(0,0,0,0,0,0,0,0,0,0,0,0,G27,0,0,0,0,0,0,0,0,0,0,0,0,0,0,0,0,0~
,0,0,0,0,0,0,0,0,0,0)';
      OUTPUT_LOAD='(1.0,-1.0)';
      PINUSE='OUT';
    'G2_RXP5':
      PIN_NUMBER='(0,0,0,0,0,0,0,0,0,0,0,0,AG27,0,0,0,0,0,0,0,0,0,0,0,0,0,0,0,0,~
0,0,0,0,0,0,0,0,0,0,0)';
      INPUT_LOAD='(-0.01,0.01)';
      PINUSE='IN';
    'G2_RXN3':
      PIN_NUMBER='(0,0,0,0,0,0,0,0,0,0,0,0,AE26,0,0,0,0,0,0,0,0,0,0,0,0,0,0,0,0,~
0,0,0,0,0,0,0,0,0,0,0)';
      INPUT_LOAD='(-0.01,0.01)';
      PINUSE='IN';
    'G2_TXN6':
      PIN_NUMBER='(0,0,0,0,0,0,0,0,0,0,0,0,L27,0,0,0,0,0,0,0,0,0,0,0,0,0,0,0,0,0~
,0,0,0,0,0,0,0,0,0,0)';
      OUTPUT_LOAD='(1.0,-1.0)';
      PINUSE='OUT';
    'G2_RXP6':
      PIN_NUMBER='(0,0,0,0,0,0,0,0,0,0,0,0,AE30,0,0,0,0,0,0,0,0,0,0,0,0,0,0,0,0,~
0,0,0,0,0,0,0,0,0,0,0)';
      INPUT_LOAD='(-0.01,0.01)';
      PINUSE='IN';
    'G2_RXN4':
      PIN_NUMBER='(0,0,0,0,0,0,0,0,0,0,0,0,AC26,0,0,0,0,0,0,0,0,0,0,0,0,0,0,0,0,~
0,0,0,0,0,0,0,0,0,0,0)';
      INPUT_LOAD='(-0.01,0.01)';
      PINUSE='IN';
    'G2_TXN7':
      PIN_NUMBER='(0,0,0,0,0,0,0,0,0,0,0,0,J30,0,0,0,0,0,0,0,0,0,0,0,0,0,0,0,0,0~
,0,0,0,0,0,0,0,0,0,0)';
      OUTPUT_LOAD='(1.0,-1.0)';
      PINUSE='OUT';
    'G2_RXP7':
      PIN_NUMBER='(0,0,0,0,0,0,0,0,0,0,0,0,AC30,0,0,0,0,0,0,0,0,0,0,0,0,0,0,0,0,~
0,0,0,0,0,0,0,0,0,0,0)';
      INPUT_LOAD='(-0.01,0.01)';
      PINUSE='IN';
    'G2_RXN5':
      PIN_NUMBER='(0,0,0,0,0,0,0,0,0,0,0,0,AG26,0,0,0,0,0,0,0,0,0,0,0,0,0,0,0,0,~
0,0,0,0,0,0,0,0,0,0,0)';
      INPUT_LOAD='(-0.01,0.01)';
      PINUSE='IN';
    'G2_RXN6':
      PIN_NUMBER='(0,0,0,0,0,0,0,0,0,0,0,0,AE29,0,0,0,0,0,0,0,0,0,0,0,0,0,0,0,0,~
0,0,0,0,0,0,0,0,0,0,0)';
      INPUT_LOAD='(-0.01,0.01)';
      PINUSE='IN';
    'G2_RXN7':
      PIN_NUMBER='(0,0,0,0,0,0,0,0,0,0,0,0,AC29,0,0,0,0,0,0,0,0,0,0,0,0,0,0,0,0,~
0,0,0,0,0,0,0,0,0,0,0)';
      INPUT_LOAD='(-0.01,0.01)';
      PINUSE='IN';
    'G2_TXP0':
      PIN_NUMBER='(0,0,0,0,0,0,0,0,0,0,0,0,N23,0,0,0,0,0,0,0,0,0,0,0,0,0,0,0,0,0~
,0,0,0,0,0,0,0,0,0,0)';
      OUTPUT_LOAD='(1.0,-1.0)';
      PINUSE='OUT';
    'G3_TXP13||SATA35_TXP':
      PIN_NUMBER='(0,0,0,0,0,0,0,0,0,0,0,0,0,P35,0,0,0,0,0,0,0,0,0,0,0,0,0,0,0,0~
,0,0,0,0,0,0,0,0,0,0)';
      OUTPUT_LOAD='(1.0,-1.0)';
      PINUSE='OUT';
    'G3_TXP10||SATA32_TXP':
      PIN_NUMBER='(0,0,0,0,0,0,0,0,0,0,0,0,0,R32,0,0,0,0,0,0,0,0,0,0,0,0,0,0,0,0~
,0,0,0,0,0,0,0,0,0,0)';
      OUTPUT_LOAD='(1.0,-1.0)';
      PINUSE='OUT';
    'G3_RXN5||SATA25_RXN':
      PIN_NUMBER='(0,0,0,0,0,0,0,0,0,0,0,0,0,AN26,0,0,0,0,0,0,0,0,0,0,0,0,0,0,0,~
0,0,0,0,0,0,0,0,0,0,0)';
      INPUT_LOAD='(-0.01,0.01)';
      PINUSE='IN';
    'G3_TXN2||SATA22_TXN':
      PIN_NUMBER='(0,0,0,0,0,0,0,0,0,0,0,0,0,W24,0,0,0,0,0,0,0,0,0,0,0,0,0,0,0,0~
,0,0,0,0,0,0,0,0,0,0)';
      OUTPUT_LOAD='(1.0,-1.0)';
      PINUSE='OUT';
    'G3_RXP12||SATA34_RXP':
      PIN_NUMBER='(0,0,0,0,0,0,0,0,0,0,0,0,0,AK36,0,0,0,0,0,0,0,0,0,0,0,0,0,0,0,~
0,0,0,0,0,0,0,0,0,0,0)';
      INPUT_LOAD='(-0.01,0.01)';
      PINUSE='IN';
    'G3_RXP0||SATA20_RXP':
      PIN_NUMBER='(0,0,0,0,0,0,0,0,0,0,0,0,0,AL24,0,0,0,0,0,0,0,0,0,0,0,0,0,0,0,~
0,0,0,0,0,0,0,0,0,0,0)';
      INPUT_LOAD='(-0.01,0.01)';
      PINUSE='IN';
    'G3_TXN14||SATA36_TXN':
      PIN_NUMBER='(0,0,0,0,0,0,0,0,0,0,0,0,0,T36,0,0,0,0,0,0,0,0,0,0,0,0,0,0,0,0~
,0,0,0,0,0,0,0,0,0,0)';
      OUTPUT_LOAD='(1.0,-1.0)';
      PINUSE='OUT';
    'G3_TXN11||SATA33_TXN':
      PIN_NUMBER='(0,0,0,0,0,0,0,0,0,0,0,0,0,N33,0,0,0,0,0,0,0,0,0,0,0,0,0,0,0,0~
,0,0,0,0,0,0,0,0,0,0)';
      OUTPUT_LOAD='(1.0,-1.0)';
      PINUSE='OUT';
    'G3_TXN5||SATA25_TXN':
      PIN_NUMBER='(0,0,0,0,0,0,0,0,0,0,0,0,0,N27,0,0,0,0,0,0,0,0,0,0,0,0,0,0,0,0~
,0,0,0,0,0,0,0,0,0,0)';
      OUTPUT_LOAD='(1.0,-1.0)';
      PINUSE='OUT';
    'G3_RXP15||SATA37_RXP':
      PIN_NUMBER='(0,0,0,0,0,0,0,0,0,0,0,0,0,AP36,0,0,0,0,0,0,0,0,0,0,0,0,0,0,0,~
0,0,0,0,0,0,0,0,0,0,0)';
      INPUT_LOAD='(-0.01,0.01)';
      PINUSE='IN';
    'G3_RXP6||SATA26_RXP':
      PIN_NUMBER='(0,0,0,0,0,0,0,0,0,0,0,0,0,AL30,0,0,0,0,0,0,0,0,0,0,0,0,0,0,0,~
0,0,0,0,0,0,0,0,0,0,0)';
      INPUT_LOAD='(-0.01,0.01)';
      PINUSE='IN';
    'G3_RXP3||SATA23_RXP':
      PIN_NUMBER='(0,0,0,0,0,0,0,0,0,0,0,0,0,AL27,0,0,0,0,0,0,0,0,0,0,0,0,0,0,0,~
0,0,0,0,0,0,0,0,0,0,0)';
      INPUT_LOAD='(-0.01,0.01)';
      PINUSE='IN';
    'G3_TXP3||SATA23_TXP':
      PIN_NUMBER='(0,0,0,0,0,0,0,0,0,0,0,0,0,U26,0,0,0,0,0,0,0,0,0,0,0,0,0,0,0,0~
,0,0,0,0,0,0,0,0,0,0)';
      OUTPUT_LOAD='(1.0,-1.0)';
      PINUSE='OUT';
    'G3_TXP0||SATA20_TXP':
      PIN_NUMBER='(0,0,0,0,0,0,0,0,0,0,0,0,0,U23,0,0,0,0,0,0,0,0,0,0,0,0,0,0,0,0~
,0,0,0,0,0,0,0,0,0,0)';
      OUTPUT_LOAD='(1.0,-1.0)';
      PINUSE='OUT';
    'G3_RXN10||SATA32_RXN':
      PIN_NUMBER='(0,0,0,0,0,0,0,0,0,0,0,0,0,AJ32,0,0,0,0,0,0,0,0,0,0,0,0,0,0,0,~
0,0,0,0,0,0,0,0,0,0,0)';
      INPUT_LOAD='(-0.01,0.01)';
      PINUSE='IN';
    'G3_TXP6||SATA26_TXP':
      PIN_NUMBER='(0,0,0,0,0,0,0,0,0,0,0,0,0,W26,0,0,0,0,0,0,0,0,0,0,0,0,0,0,0,0~
,0,0,0,0,0,0,0,0,0,0)';
      OUTPUT_LOAD='(1.0,-1.0)';
      PINUSE='OUT';
    'G3_RXN13||SATA35_RXN':
      PIN_NUMBER='(0,0,0,0,0,0,0,0,0,0,0,0,0,AH35,0,0,0,0,0,0,0,0,0,0,0,0,0,0,0,~
0,0,0,0,0,0,0,0,0,0,0)';
      INPUT_LOAD='(-0.01,0.01)';
      PINUSE='IN';
    'G3_TXP11||SATA33_TXP':
      PIN_NUMBER='(0,0,0,0,0,0,0,0,0,0,0,0,0,N32,0,0,0,0,0,0,0,0,0,0,0,0,0,0,0,0~
,0,0,0,0,0,0,0,0,0,0)';
      OUTPUT_LOAD='(1.0,-1.0)';
      PINUSE='OUT';
    'G3_RXP8||SATA30_RXP':
      PIN_NUMBER='(0,0,0,0,0,0,0,0,0,0,0,0,0,AN30,0,0,0,0,0,0,0,0,0,0,0,0,0,0,0,~
0,0,0,0,0,0,0,0,0,0,0)';
      INPUT_LOAD='(-0.01,0.01)';
      PINUSE='IN';
    'G3_RXN3||SATA23_RXN':
      PIN_NUMBER='(0,0,0,0,0,0,0,0,0,0,0,0,0,AL26,0,0,0,0,0,0,0,0,0,0,0,0,0,0,0,~
0,0,0,0,0,0,0,0,0,0,0)';
      INPUT_LOAD='(-0.01,0.01)';
      PINUSE='IN';
    'G3_RXN0||SATA20_RXN':
      PIN_NUMBER='(0,0,0,0,0,0,0,0,0,0,0,0,0,AL23,0,0,0,0,0,0,0,0,0,0,0,0,0,0,0,~
0,0,0,0,0,0,0,0,0,0,0)';
      INPUT_LOAD='(-0.01,0.01)';
      PINUSE='IN';
    'G3_TXP14||SATA36_TXP':
      PIN_NUMBER='(0,0,0,0,0,0,0,0,0,0,0,0,0,T35,0,0,0,0,0,0,0,0,0,0,0,0,0,0,0,0~
,0,0,0,0,0,0,0,0,0,0)';
      OUTPUT_LOAD='(1.0,-1.0)';
      PINUSE='OUT';
    'G3_TXP8||SATA30_TXP':
      PIN_NUMBER='(0,0,0,0,0,0,0,0,0,0,0,0,0,N29,0,0,0,0,0,0,0,0,0,0,0,0,0,0,0,0~
,0,0,0,0,0,0,0,0,0,0)';
      OUTPUT_LOAD='(1.0,-1.0)';
      PINUSE='OUT';
    'G3_TXN0||SATA20_TXN':
      PIN_NUMBER='(0,0,0,0,0,0,0,0,0,0,0,0,0,U24,0,0,0,0,0,0,0,0,0,0,0,0,0,0,0,0~
,0,0,0,0,0,0,0,0,0,0)';
      OUTPUT_LOAD='(1.0,-1.0)';
      PINUSE='OUT';
    'G3_RXN6||SATA26_RXN':
      PIN_NUMBER='(0,0,0,0,0,0,0,0,0,0,0,0,0,AL29,0,0,0,0,0,0,0,0,0,0,0,0,0,0,0,~
0,0,0,0,0,0,0,0,0,0,0)';
      INPUT_LOAD='(-0.01,0.01)';
      PINUSE='IN';
    'G3_TXN6||SATA26_TXN':
      PIN_NUMBER='(0,0,0,0,0,0,0,0,0,0,0,0,0,W27,0,0,0,0,0,0,0,0,0,0,0,0,0,0,0,0~
,0,0,0,0,0,0,0,0,0,0)';
      OUTPUT_LOAD='(1.0,-1.0)';
      PINUSE='OUT';
    'G3_TXN3||SATA23_TXN':
      PIN_NUMBER='(0,0,0,0,0,0,0,0,0,0,0,0,0,U27,0,0,0,0,0,0,0,0,0,0,0,0,0,0,0,0~
,0,0,0,0,0,0,0,0,0,0)';
      OUTPUT_LOAD='(1.0,-1.0)';
      PINUSE='OUT';
    'G3_RXP13||SATA35_RXP':
      PIN_NUMBER='(0,0,0,0,0,0,0,0,0,0,0,0,0,AH36,0,0,0,0,0,0,0,0,0,0,0,0,0,0,0,~
0,0,0,0,0,0,0,0,0,0,0)';
      INPUT_LOAD='(-0.01,0.01)';
      PINUSE='IN';
    'G3_RXP10||SATA32_RXP':
      PIN_NUMBER='(0,0,0,0,0,0,0,0,0,0,0,0,0,AJ33,0,0,0,0,0,0,0,0,0,0,0,0,0,0,0,~
0,0,0,0,0,0,0,0,0,0,0)';
      INPUT_LOAD='(-0.01,0.01)';
      PINUSE='IN';
    'G3_RXP4||SATA24_RXP':
      PIN_NUMBER='(0,0,0,0,0,0,0,0,0,0,0,0,0,AJ27,0,0,0,0,0,0,0,0,0,0,0,0,0,0,0,~
0,0,0,0,0,0,0,0,0,0,0)';
      INPUT_LOAD='(-0.01,0.01)';
      PINUSE='IN';
    'G3_RXP1||SATA21_RXP':
      PIN_NUMBER='(0,0,0,0,0,0,0,0,0,0,0,0,0,AJ24,0,0,0,0,0,0,0,0,0,0,0,0,0,0,0,~
0,0,0,0,0,0,0,0,0,0,0)';
      INPUT_LOAD='(-0.01,0.01)';
      PINUSE='IN';
    'G3_TXN15||SATA37_TXN':
      PIN_NUMBER='(0,0,0,0,0,0,0,0,0,0,0,0,0,V36,0,0,0,0,0,0,0,0,0,0,0,0,0,0,0,0~
,0,0,0,0,0,0,0,0,0,0)';
      OUTPUT_LOAD='(1.0,-1.0)';
      PINUSE='OUT';
    'G3_TXN12||SATA34_TXN':
      PIN_NUMBER='(0,0,0,0,0,0,0,0,0,0,0,0,0,U33,0,0,0,0,0,0,0,0,0,0,0,0,0,0,0,0~
,0,0,0,0,0,0,0,0,0,0)';
      OUTPUT_LOAD='(1.0,-1.0)';
      PINUSE='OUT';
    'G3_RXN8||SATA30_RXN':
      PIN_NUMBER='(0,0,0,0,0,0,0,0,0,0,0,0,0,AN29,0,0,0,0,0,0,0,0,0,0,0,0,0,0,0,~
0,0,0,0,0,0,0,0,0,0,0)';
      INPUT_LOAD='(-0.01,0.01)';
      PINUSE='IN';
    'G3_RXP7||SATA27_RXP':
      PIN_NUMBER='(0,0,0,0,0,0,0,0,0,0,0,0,0,AJ30,0,0,0,0,0,0,0,0,0,0,0,0,0,0,0,~
0,0,0,0,0,0,0,0,0,0,0)';
      INPUT_LOAD='(-0.01,0.01)';
      PINUSE='IN';
    'G3_TXP4||SATA24_TXP':
      PIN_NUMBER='(0,0,0,0,0,0,0,0,0,0,0,0,0,R26,0,0,0,0,0,0,0,0,0,0,0,0,0,0,0,0~
,0,0,0,0,0,0,0,0,0,0)';
      OUTPUT_LOAD='(1.0,-1.0)';
      PINUSE='OUT';
    'G3_TXP1||SATA21_TXP':
      PIN_NUMBER='(0,0,0,0,0,0,0,0,0,0,0,0,0,R23,0,0,0,0,0,0,0,0,0,0,0,0,0,0,0,0~
,0,0,0,0,0,0,0,0,0,0)';
      OUTPUT_LOAD='(1.0,-1.0)';
      PINUSE='OUT';
    'G3_RXN14||SATA36_RXN':
      PIN_NUMBER='(0,0,0,0,0,0,0,0,0,0,0,0,0,AM35,0,0,0,0,0,0,0,0,0,0,0,0,0,0,0,~
0,0,0,0,0,0,0,0,0,0,0)';
      INPUT_LOAD='(-0.01,0.01)';
      PINUSE='IN';
    'G3_RXN11||SATA33_RXN':
      PIN_NUMBER='(0,0,0,0,0,0,0,0,0,0,0,0,0,AN32,0,0,0,0,0,0,0,0,0,0,0,0,0,0,0,~
0,0,0,0,0,0,0,0,0,0,0)';
      INPUT_LOAD='(-0.01,0.01)';
      PINUSE='IN';
    'G3_TXN8||SATA30_TXN':
      PIN_NUMBER='(0,0,0,0,0,0,0,0,0,0,0,0,0,N30,0,0,0,0,0,0,0,0,0,0,0,0,0,0,0,0~
,0,0,0,0,0,0,0,0,0,0)';
      OUTPUT_LOAD='(1.0,-1.0)';
      PINUSE='OUT';
    'G3_TXP7||SATA27_TXP':
      PIN_NUMBER='(0,0,0,0,0,0,0,0,0,0,0,0,0,R29,0,0,0,0,0,0,0,0,0,0,0,0,0,0,0,0~
,0,0,0,0,0,0,0,0,0,0)';
      OUTPUT_LOAD='(1.0,-1.0)';
      PINUSE='OUT';
    'G3_RXP9||SATA31_RXP':
      PIN_NUMBER='(0,0,0,0,0,0,0,0,0,0,0,0,0,AL33,0,0,0,0,0,0,0,0,0,0,0,0,0,0,0,~
0,0,0,0,0,0,0,0,0,0,0)';
      INPUT_LOAD='(-0.01,0.01)';
      PINUSE='IN';
    'G3_TXP12||SATA34_TXP':
      PIN_NUMBER='(0,0,0,0,0,0,0,0,0,0,0,0,0,U32,0,0,0,0,0,0,0,0,0,0,0,0,0,0,0,0~
,0,0,0,0,0,0,0,0,0,0)';
      OUTPUT_LOAD='(1.0,-1.0)';
      PINUSE='OUT';
    'G3_RXN7||SATA27_RXN':
      PIN_NUMBER='(0,0,0,0,0,0,0,0,0,0,0,0,0,AJ29,0,0,0,0,0,0,0,0,0,0,0,0,0,0,0,~
0,0,0,0,0,0,0,0,0,0,0)';
      INPUT_LOAD='(-0.01,0.01)';
      PINUSE='IN';
    'G3_RXN4||SATA24_RXN':
      PIN_NUMBER='(0,0,0,0,0,0,0,0,0,0,0,0,0,AJ26,0,0,0,0,0,0,0,0,0,0,0,0,0,0,0,~
0,0,0,0,0,0,0,0,0,0,0)';
      INPUT_LOAD='(-0.01,0.01)';
      PINUSE='IN';
    'G3_RXN1||SATA21_RXN':
      PIN_NUMBER='(0,0,0,0,0,0,0,0,0,0,0,0,0,AJ23,0,0,0,0,0,0,0,0,0,0,0,0,0,0,0,~
0,0,0,0,0,0,0,0,0,0,0)';
      INPUT_LOAD='(-0.01,0.01)';
      PINUSE='IN';
    'G3_TXP15||SATA37_TXP':
      PIN_NUMBER='(0,0,0,0,0,0,0,0,0,0,0,0,0,V35,0,0,0,0,0,0,0,0,0,0,0,0,0,0,0,0~
,0,0,0,0,0,0,0,0,0,0)';
      OUTPUT_LOAD='(1.0,-1.0)';
      PINUSE='OUT';
    'G3_TXP9||SATA31_TXP':
      PIN_NUMBER='(0,0,0,0,0,0,0,0,0,0,0,0,0,U29,0,0,0,0,0,0,0,0,0,0,0,0,0,0,0,0~
,0,0,0,0,0,0,0,0,0,0)';
      OUTPUT_LOAD='(1.0,-1.0)';
      PINUSE='OUT';
    'G3_TXN1||SATA21_TXN':
      PIN_NUMBER='(0,0,0,0,0,0,0,0,0,0,0,0,0,R24,0,0,0,0,0,0,0,0,0,0,0,0,0,0,0,0~
,0,0,0,0,0,0,0,0,0,0)';
      OUTPUT_LOAD='(1.0,-1.0)';
      PINUSE='OUT';
    'G3_RXP11||SATA33_RXP':
      PIN_NUMBER='(0,0,0,0,0,0,0,0,0,0,0,0,0,AN33,0,0,0,0,0,0,0,0,0,0,0,0,0,0,0,~
0,0,0,0,0,0,0,0,0,0,0)';
      INPUT_LOAD='(-0.01,0.01)';
      PINUSE='IN';
    'G3_TXN13||SATA35_TXN':
      PIN_NUMBER='(0,0,0,0,0,0,0,0,0,0,0,0,0,P36,0,0,0,0,0,0,0,0,0,0,0,0,0,0,0,0~
,0,0,0,0,0,0,0,0,0,0)';
      OUTPUT_LOAD='(1.0,-1.0)';
      PINUSE='OUT';
    'G3_TXN10||SATA32_TXN':
      PIN_NUMBER='(0,0,0,0,0,0,0,0,0,0,0,0,0,R33,0,0,0,0,0,0,0,0,0,0,0,0,0,0,0,0~
,0,0,0,0,0,0,0,0,0,0)';
      OUTPUT_LOAD='(1.0,-1.0)';
      PINUSE='OUT';
    'G3_TXN7||SATA27_TXN':
      PIN_NUMBER='(0,0,0,0,0,0,0,0,0,0,0,0,0,R30,0,0,0,0,0,0,0,0,0,0,0,0,0,0,0,0~
,0,0,0,0,0,0,0,0,0,0)';
      OUTPUT_LOAD='(1.0,-1.0)';
      PINUSE='OUT';
    'G3_TXN4||SATA24_TXN':
      PIN_NUMBER='(0,0,0,0,0,0,0,0,0,0,0,0,0,R27,0,0,0,0,0,0,0,0,0,0,0,0,0,0,0,0~
,0,0,0,0,0,0,0,0,0,0)';
      OUTPUT_LOAD='(1.0,-1.0)';
      PINUSE='OUT';
    'G3_RXP14||SATA36_RXP':
      PIN_NUMBER='(0,0,0,0,0,0,0,0,0,0,0,0,0,AM36,0,0,0,0,0,0,0,0,0,0,0,0,0,0,0,~
0,0,0,0,0,0,0,0,0,0,0)';
      INPUT_LOAD='(-0.01,0.01)';
      PINUSE='IN';
    'G3_RXP5||SATA25_RXP':
      PIN_NUMBER='(0,0,0,0,0,0,0,0,0,0,0,0,0,AN27,0,0,0,0,0,0,0,0,0,0,0,0,0,0,0,~
0,0,0,0,0,0,0,0,0,0,0)';
      INPUT_LOAD='(-0.01,0.01)';
      PINUSE='IN';
    'G3_RXP2||SATA22_RXP':
      PIN_NUMBER='(0,0,0,0,0,0,0,0,0,0,0,0,0,AN24,0,0,0,0,0,0,0,0,0,0,0,0,0,0,0,~
0,0,0,0,0,0,0,0,0,0,0)';
      INPUT_LOAD='(-0.01,0.01)';
      PINUSE='IN';
    'G3_TXP2||SATA22_TXP':
      PIN_NUMBER='(0,0,0,0,0,0,0,0,0,0,0,0,0,W23,0,0,0,0,0,0,0,0,0,0,0,0,0,0,0,0~
,0,0,0,0,0,0,0,0,0,0)';
      OUTPUT_LOAD='(1.0,-1.0)';
      PINUSE='OUT';
    'G3_RXN9||SATA31_RXN':
      PIN_NUMBER='(0,0,0,0,0,0,0,0,0,0,0,0,0,AL32,0,0,0,0,0,0,0,0,0,0,0,0,0,0,0,~
0,0,0,0,0,0,0,0,0,0,0)';
      INPUT_LOAD='(-0.01,0.01)';
      PINUSE='IN';
    'G3_TXP5||SATA25_TXP':
      PIN_NUMBER='(0,0,0,0,0,0,0,0,0,0,0,0,0,N26,0,0,0,0,0,0,0,0,0,0,0,0,0,0,0,0~
,0,0,0,0,0,0,0,0,0,0)';
      OUTPUT_LOAD='(1.0,-1.0)';
      PINUSE='OUT';
    'G3_RXN15||SATA37_RXN':
      PIN_NUMBER='(0,0,0,0,0,0,0,0,0,0,0,0,0,AP35,0,0,0,0,0,0,0,0,0,0,0,0,0,0,0,~
0,0,0,0,0,0,0,0,0,0,0)';
      INPUT_LOAD='(-0.01,0.01)';
      PINUSE='IN';
    'G3_RXN12||SATA34_RXN':
      PIN_NUMBER='(0,0,0,0,0,0,0,0,0,0,0,0,0,AK35,0,0,0,0,0,0,0,0,0,0,0,0,0,0,0,~
0,0,0,0,0,0,0,0,0,0,0)';
      INPUT_LOAD='(-0.01,0.01)';
      PINUSE='IN';
    'G3_TXN9||SATA31_TXN':
      PIN_NUMBER='(0,0,0,0,0,0,0,0,0,0,0,0,0,U30,0,0,0,0,0,0,0,0,0,0,0,0,0,0,0,0~
,0,0,0,0,0,0,0,0,0,0)';
      OUTPUT_LOAD='(1.0,-1.0)';
      PINUSE='OUT';
    'G3_RXN2||SATA22_RXN':
      PIN_NUMBER='(0,0,0,0,0,0,0,0,0,0,0,0,0,AN23,0,0,0,0,0,0,0,0,0,0,0,0,0,0,0,~
0,0,0,0,0,0,0,0,0,0,0)';
      INPUT_LOAD='(-0.01,0.01)';
      PINUSE='IN';
    'P0_RXN0||SATA00_RXN':
      PIN_NUMBER='(0,0,0,0,0,0,0,0,0,0,0,0,0,0,BW53,0,0,0,0,0,0,0,0,0,0,0,0,0,0,~
0,0,0,0,0,0,0,0,0,0,0)';
      INPUT_LOAD='(-0.01,0.01)';
      PINUSE='IN';
    'P0_RXN6||SATA06_RXN':
      PIN_NUMBER='(0,0,0,0,0,0,0,0,0,0,0,0,0,0,BW47,0,0,0,0,0,0,0,0,0,0,0,0,0,0,~
0,0,0,0,0,0,0,0,0,0,0)';
      INPUT_LOAD='(-0.01,0.01)';
      PINUSE='IN';
    'P0_RXN3||SATA03_RXN':
      PIN_NUMBER='(0,0,0,0,0,0,0,0,0,0,0,0,0,0,BW50,0,0,0,0,0,0,0,0,0,0,0,0,0,0,~
0,0,0,0,0,0,0,0,0,0,0)';
      INPUT_LOAD='(-0.01,0.01)';
      PINUSE='IN';
    'P0_TXN3||SATA03_TXN':
      PIN_NUMBER='(0,0,0,0,0,0,0,0,0,0,0,0,0,0,CN49,0,0,0,0,0,0,0,0,0,0,0,0,0,0,~
0,0,0,0,0,0,0,0,0,0,0)';
      OUTPUT_LOAD='(1.0,-1.0)';
      PINUSE='OUT';
    'P0_TXN0||SATA00_TXN':
      PIN_NUMBER='(0,0,0,0,0,0,0,0,0,0,0,0,0,0,CN52,0,0,0,0,0,0,0,0,0,0,0,0,0,0,~
0,0,0,0,0,0,0,0,0,0,0)';
      OUTPUT_LOAD='(1.0,-1.0)';
      PINUSE='OUT';
    'P0_RXP1||SATA01_RXP':
      PIN_NUMBER='(0,0,0,0,0,0,0,0,0,0,0,0,0,0,CA52,0,0,0,0,0,0,0,0,0,0,0,0,0,0,~
0,0,0,0,0,0,0,0,0,0,0)';
      INPUT_LOAD='(-0.01,0.01)';
      PINUSE='IN';
    'P0_TXN6||SATA06_TXN':
      PIN_NUMBER='(0,0,0,0,0,0,0,0,0,0,0,0,0,0,CL49,0,0,0,0,0,0,0,0,0,0,0,0,0,0,~
0,0,0,0,0,0,0,0,0,0,0)';
      OUTPUT_LOAD='(1.0,-1.0)';
      PINUSE='OUT';
    'P0_RXP7||SATA07_RXP':
      PIN_NUMBER='(0,0,0,0,0,0,0,0,0,0,0,0,0,0,CA46,0,0,0,0,0,0,0,0,0,0,0,0,0,0,~
0,0,0,0,0,0,0,0,0,0,0)';
      INPUT_LOAD='(-0.01,0.01)';
      PINUSE='IN';
    'P0_RXP4||SATA04_RXP':
      PIN_NUMBER='(0,0,0,0,0,0,0,0,0,0,0,0,0,0,CA49,0,0,0,0,0,0,0,0,0,0,0,0,0,0,~
0,0,0,0,0,0,0,0,0,0,0)';
      INPUT_LOAD='(-0.01,0.01)';
      PINUSE='IN';
    'P0_TXP4||SATA04_TXP':
      PIN_NUMBER='(0,0,0,0,0,0,0,0,0,0,0,0,0,0,CR50,0,0,0,0,0,0,0,0,0,0,0,0,0,0,~
0,0,0,0,0,0,0,0,0,0,0)';
      OUTPUT_LOAD='(1.0,-1.0)';
      PINUSE='OUT';
    'P0_TXP1||SATA01_TXP':
      PIN_NUMBER='(0,0,0,0,0,0,0,0,0,0,0,0,0,0,CR53,0,0,0,0,0,0,0,0,0,0,0,0,0,0,~
0,0,0,0,0,0,0,0,0,0,0)';
      OUTPUT_LOAD='(1.0,-1.0)';
      PINUSE='OUT';
    'P0_TXP7||SATA07_TXP':
      PIN_NUMBER='(0,0,0,0,0,0,0,0,0,0,0,0,0,0,CR47,0,0,0,0,0,0,0,0,0,0,0,0,0,0,~
0,0,0,0,0,0,0,0,0,0,0)';
      OUTPUT_LOAD='(1.0,-1.0)';
      PINUSE='OUT';
    'P0_RXN4||SATA04_RXN':
      PIN_NUMBER='(0,0,0,0,0,0,0,0,0,0,0,0,0,0,CA50,0,0,0,0,0,0,0,0,0,0,0,0,0,0,~
0,0,0,0,0,0,0,0,0,0,0)';
      INPUT_LOAD='(-0.01,0.01)';
      PINUSE='IN';
    'P0_RXN1||SATA01_RXN':
      PIN_NUMBER='(0,0,0,0,0,0,0,0,0,0,0,0,0,0,CA53,0,0,0,0,0,0,0,0,0,0,0,0,0,0,~
0,0,0,0,0,0,0,0,0,0,0)';
      INPUT_LOAD='(-0.01,0.01)';
      PINUSE='IN';
    'P0_RXN7||SATA07_RXN':
      PIN_NUMBER='(0,0,0,0,0,0,0,0,0,0,0,0,0,0,CA47,0,0,0,0,0,0,0,0,0,0,0,0,0,0,~
0,0,0,0,0,0,0,0,0,0,0)';
      INPUT_LOAD='(-0.01,0.01)';
      PINUSE='IN';
    'P0_TXN4||SATA04_TXN':
      PIN_NUMBER='(0,0,0,0,0,0,0,0,0,0,0,0,0,0,CR49,0,0,0,0,0,0,0,0,0,0,0,0,0,0,~
0,0,0,0,0,0,0,0,0,0,0)';
      OUTPUT_LOAD='(1.0,-1.0)';
      PINUSE='OUT';
    'P0_TXN7||SATA07_TXN':
      PIN_NUMBER='(0,0,0,0,0,0,0,0,0,0,0,0,0,0,CR46,0,0,0,0,0,0,0,0,0,0,0,0,0,0,~
0,0,0,0,0,0,0,0,0,0,0)';
      OUTPUT_LOAD='(1.0,-1.0)';
      PINUSE='OUT';
    'P0_TXN1||SATA01_TXN':
      PIN_NUMBER='(0,0,0,0,0,0,0,0,0,0,0,0,0,0,CR52,0,0,0,0,0,0,0,0,0,0,0,0,0,0,~
0,0,0,0,0,0,0,0,0,0,0)';
      OUTPUT_LOAD='(1.0,-1.0)';
      PINUSE='OUT';
    'P0_RXP2||SATA02_RXP':
      PIN_NUMBER='(0,0,0,0,0,0,0,0,0,0,0,0,0,0,BU52,0,0,0,0,0,0,0,0,0,0,0,0,0,0,~
0,0,0,0,0,0,0,0,0,0,0)';
      INPUT_LOAD='(-0.01,0.01)';
      PINUSE='IN';
    'P0_RXP5||SATA05_RXP':
      PIN_NUMBER='(0,0,0,0,0,0,0,0,0,0,0,0,0,0,BU49,0,0,0,0,0,0,0,0,0,0,0,0,0,0,~
0,0,0,0,0,0,0,0,0,0,0)';
      INPUT_LOAD='(-0.01,0.01)';
      PINUSE='IN';
    'P0_TXP5||SATA05_TXP':
      PIN_NUMBER='(0,0,0,0,0,0,0,0,0,0,0,0,0,0,CU50,0,0,0,0,0,0,0,0,0,0,0,0,0,0,~
0,0,0,0,0,0,0,0,0,0,0)';
      OUTPUT_LOAD='(1.0,-1.0)';
      PINUSE='OUT';
    'P0_TXP2||SATA02_TXP':
      PIN_NUMBER='(0,0,0,0,0,0,0,0,0,0,0,0,0,0,CL53,0,0,0,0,0,0,0,0,0,0,0,0,0,0,~
0,0,0,0,0,0,0,0,0,0,0)';
      OUTPUT_LOAD='(1.0,-1.0)';
      PINUSE='OUT';
    'P0_RXN5||SATA05_RXN':
      PIN_NUMBER='(0,0,0,0,0,0,0,0,0,0,0,0,0,0,BU50,0,0,0,0,0,0,0,0,0,0,0,0,0,0,~
0,0,0,0,0,0,0,0,0,0,0)';
      INPUT_LOAD='(-0.01,0.01)';
      PINUSE='IN';
    'P0_RXN2||SATA02_RXN':
      PIN_NUMBER='(0,0,0,0,0,0,0,0,0,0,0,0,0,0,BU53,0,0,0,0,0,0,0,0,0,0,0,0,0,0,~
0,0,0,0,0,0,0,0,0,0,0)';
      INPUT_LOAD='(-0.01,0.01)';
      PINUSE='IN';
    'P0_TXN2||SATA02_TXN':
      PIN_NUMBER='(0,0,0,0,0,0,0,0,0,0,0,0,0,0,CL52,0,0,0,0,0,0,0,0,0,0,0,0,0,0,~
0,0,0,0,0,0,0,0,0,0,0)';
      OUTPUT_LOAD='(1.0,-1.0)';
      PINUSE='OUT';
    'P0_RXP0||SATA00_RXP':
      PIN_NUMBER='(0,0,0,0,0,0,0,0,0,0,0,0,0,0,BW52,0,0,0,0,0,0,0,0,0,0,0,0,0,0,~
0,0,0,0,0,0,0,0,0,0,0)';
      INPUT_LOAD='(-0.01,0.01)';
      PINUSE='IN';
    'P0_TXN5||SATA05_TXN':
      PIN_NUMBER='(0,0,0,0,0,0,0,0,0,0,0,0,0,0,CU49,0,0,0,0,0,0,0,0,0,0,0,0,0,0,~
0,0,0,0,0,0,0,0,0,0,0)';
      OUTPUT_LOAD='(1.0,-1.0)';
      PINUSE='OUT';
    'P0_RXP6||SATA06_RXP':
      PIN_NUMBER='(0,0,0,0,0,0,0,0,0,0,0,0,0,0,BW46,0,0,0,0,0,0,0,0,0,0,0,0,0,0,~
0,0,0,0,0,0,0,0,0,0,0)';
      INPUT_LOAD='(-0.01,0.01)';
      PINUSE='IN';
    'P0_RXP3||SATA03_RXP':
      PIN_NUMBER='(0,0,0,0,0,0,0,0,0,0,0,0,0,0,BW49,0,0,0,0,0,0,0,0,0,0,0,0,0,0,~
0,0,0,0,0,0,0,0,0,0,0)';
      INPUT_LOAD='(-0.01,0.01)';
      PINUSE='IN';
    'P0_TXP0||SATA00_TXP':
      PIN_NUMBER='(0,0,0,0,0,0,0,0,0,0,0,0,0,0,CN53,0,0,0,0,0,0,0,0,0,0,0,0,0,0,~
0,0,0,0,0,0,0,0,0,0,0)';
      OUTPUT_LOAD='(1.0,-1.0)';
      PINUSE='OUT';
    'P0_TXP6||SATA06_TXP':
      PIN_NUMBER='(0,0,0,0,0,0,0,0,0,0,0,0,0,0,CL50,0,0,0,0,0,0,0,0,0,0,0,0,0,0,~
0,0,0,0,0,0,0,0,0,0,0)';
      OUTPUT_LOAD='(1.0,-1.0)';
      PINUSE='OUT';
    'P0_TXP3||SATA03_TXP':
      PIN_NUMBER='(0,0,0,0,0,0,0,0,0,0,0,0,0,0,CN50,0,0,0,0,0,0,0,0,0,0,0,0,0,0,~
0,0,0,0,0,0,0,0,0,0,0)';
      OUTPUT_LOAD='(1.0,-1.0)';
      PINUSE='OUT';
    'P0_TXN13||SATA15_TXN':
      PIN_NUMBER='(0,0,0,0,0,0,0,0,0,0,0,0,0,0,CT40,0,0,0,0,0,0,0,0,0,0,0,0,0,0,~
0,0,0,0,0,0,0,0,0,0,0)';
      OUTPUT_LOAD='(1.0,-1.0)';
      PINUSE='OUT';
    'P0_TXN10||SATA12_TXN':
      PIN_NUMBER='(0,0,0,0,0,0,0,0,0,0,0,0,0,0,CR43,0,0,0,0,0,0,0,0,0,0,0,0,0,0,~
0,0,0,0,0,0,0,0,0,0,0)';
      OUTPUT_LOAD='(1.0,-1.0)';
      PINUSE='OUT';
    'P0_RXP14||SATA16_RXP':
      PIN_NUMBER='(0,0,0,0,0,0,0,0,0,0,0,0,0,0,BV40,0,0,0,0,0,0,0,0,0,0,0,0,0,0,~
0,0,0,0,0,0,0,0,0,0,0)';
      INPUT_LOAD='(-0.01,0.01)';
      PINUSE='IN';
    'P0_RXP8||SATA10_RXP':
      PIN_NUMBER='(0,0,0,0,0,0,0,0,0,0,0,0,0,0,BU46,0,0,0,0,0,0,0,0,0,0,0,0,0,0,~
0,0,0,0,0,0,0,0,0,0,0)';
      INPUT_LOAD='(-0.01,0.01)';
      PINUSE='IN';
    'P0_RXN12||SATA14_RXN':
      PIN_NUMBER='(0,0,0,0,0,0,0,0,0,0,0,0,0,0,BY41,0,0,0,0,0,0,0,0,0,0,0,0,0,0,~
0,0,0,0,0,0,0,0,0,0,0)';
      INPUT_LOAD='(-0.01,0.01)';
      PINUSE='IN';
    'P0_TXP8||SATA10_TXP':
      PIN_NUMBER='(0,0,0,0,0,0,0,0,0,0,0,0,0,0,CU47,0,0,0,0,0,0,0,0,0,0,0,0,0,0,~
0,0,0,0,0,0,0,0,0,0,0)';
      OUTPUT_LOAD='(1.0,-1.0)';
      PINUSE='OUT';
    'P0_RXN15||SATA17_RXN':
      PIN_NUMBER='(0,0,0,0,0,0,0,0,0,0,0,0,0,0,BT41,0,0,0,0,0,0,0,0,0,0,0,0,0,0,~
0,0,0,0,0,0,0,0,0,0,0)';
      INPUT_LOAD='(-0.01,0.01)';
      PINUSE='IN';
    'P0_TXP10||SATA12_TXP':
      PIN_NUMBER='(0,0,0,0,0,0,0,0,0,0,0,0,0,0,CR44,0,0,0,0,0,0,0,0,0,0,0,0,0,0,~
0,0,0,0,0,0,0,0,0,0,0)';
      OUTPUT_LOAD='(1.0,-1.0)';
      PINUSE='OUT';
    'P0_TXP13||SATA15_TXP':
      PIN_NUMBER='(0,0,0,0,0,0,0,0,0,0,0,0,0,0,CT41,0,0,0,0,0,0,0,0,0,0,0,0,0,0,~
0,0,0,0,0,0,0,0,0,0,0)';
      OUTPUT_LOAD='(1.0,-1.0)';
      PINUSE='OUT';
    'P0_RXN8||SATA10_RXN':
      PIN_NUMBER='(0,0,0,0,0,0,0,0,0,0,0,0,0,0,BU47,0,0,0,0,0,0,0,0,0,0,0,0,0,0,~
0,0,0,0,0,0,0,0,0,0,0)';
      INPUT_LOAD='(-0.01,0.01)';
      PINUSE='IN';
    'P0_TXN11||SATA13_TXN':
      PIN_NUMBER='(0,0,0,0,0,0,0,0,0,0,0,0,0,0,CU43,0,0,0,0,0,0,0,0,0,0,0,0,0,0,~
0,0,0,0,0,0,0,0,0,0,0)';
      OUTPUT_LOAD='(1.0,-1.0)';
      PINUSE='OUT';
    'P0_TXN8||SATA10_TXN':
      PIN_NUMBER='(0,0,0,0,0,0,0,0,0,0,0,0,0,0,CU46,0,0,0,0,0,0,0,0,0,0,0,0,0,0,~
0,0,0,0,0,0,0,0,0,0,0)';
      OUTPUT_LOAD='(1.0,-1.0)';
      PINUSE='OUT';
    'P0_RXP15||SATA17_RXP':
      PIN_NUMBER='(0,0,0,0,0,0,0,0,0,0,0,0,0,0,BT40,0,0,0,0,0,0,0,0,0,0,0,0,0,0,~
0,0,0,0,0,0,0,0,0,0,0)';
      INPUT_LOAD='(-0.01,0.01)';
      PINUSE='IN';
    'P0_RXP12||SATA14_RXP':
      PIN_NUMBER='(0,0,0,0,0,0,0,0,0,0,0,0,0,0,BY40,0,0,0,0,0,0,0,0,0,0,0,0,0,0,~
0,0,0,0,0,0,0,0,0,0,0)';
      INPUT_LOAD='(-0.01,0.01)';
      PINUSE='IN';
    'P0_TXN14||SATA16_TXN':
      PIN_NUMBER='(0,0,0,0,0,0,0,0,0,0,0,0,0,0,CP40,0,0,0,0,0,0,0,0,0,0,0,0,0,0,~
0,0,0,0,0,0,0,0,0,0,0)';
      OUTPUT_LOAD='(1.0,-1.0)';
      PINUSE='OUT';
    'P0_RXP9||SATA11_RXP':
      PIN_NUMBER='(0,0,0,0,0,0,0,0,0,0,0,0,0,0,BW43,0,0,0,0,0,0,0,0,0,0,0,0,0,0,~
0,0,0,0,0,0,0,0,0,0,0)';
      INPUT_LOAD='(-0.01,0.01)';
      PINUSE='IN';
    'P0_TXP9||SATA11_TXP':
      PIN_NUMBER='(0,0,0,0,0,0,0,0,0,0,0,0,0,0,CN47,0,0,0,0,0,0,0,0,0,0,0,0,0,0,~
0,0,0,0,0,0,0,0,0,0,0)';
      OUTPUT_LOAD='(1.0,-1.0)';
      PINUSE='OUT';
    'P0_RXN13||SATA15_RXN':
      PIN_NUMBER='(0,0,0,0,0,0,0,0,0,0,0,0,0,0,CB41,0,0,0,0,0,0,0,0,0,0,0,0,0,0,~
0,0,0,0,0,0,0,0,0,0,0)';
      INPUT_LOAD='(-0.01,0.01)';
      PINUSE='IN';
    'P0_RXN10||SATA12_RXN':
      PIN_NUMBER='(0,0,0,0,0,0,0,0,0,0,0,0,0,0,CA44,0,0,0,0,0,0,0,0,0,0,0,0,0,0,~
0,0,0,0,0,0,0,0,0,0,0)';
      INPUT_LOAD='(-0.01,0.01)';
      PINUSE='IN';
    'P0_TXP14||SATA16_TXP':
      PIN_NUMBER='(0,0,0,0,0,0,0,0,0,0,0,0,0,0,CP41,0,0,0,0,0,0,0,0,0,0,0,0,0,0,~
0,0,0,0,0,0,0,0,0,0,0)';
      OUTPUT_LOAD='(1.0,-1.0)';
      PINUSE='OUT';
    'P0_TXP11||SATA13_TXP':
      PIN_NUMBER='(0,0,0,0,0,0,0,0,0,0,0,0,0,0,CU44,0,0,0,0,0,0,0,0,0,0,0,0,0,0,~
0,0,0,0,0,0,0,0,0,0,0)';
      OUTPUT_LOAD='(1.0,-1.0)';
      PINUSE='OUT';
    'P0_RXN9||SATA11_RXN':
      PIN_NUMBER='(0,0,0,0,0,0,0,0,0,0,0,0,0,0,BW44,0,0,0,0,0,0,0,0,0,0,0,0,0,0,~
0,0,0,0,0,0,0,0,0,0,0)';
      INPUT_LOAD='(-0.01,0.01)';
      PINUSE='IN';
    'P0_RXP10||SATA12_RXP':
      PIN_NUMBER='(0,0,0,0,0,0,0,0,0,0,0,0,0,0,CA43,0,0,0,0,0,0,0,0,0,0,0,0,0,0,~
0,0,0,0,0,0,0,0,0,0,0)';
      INPUT_LOAD='(-0.01,0.01)';
      PINUSE='IN';
    'P0_TXN12||SATA14_TXN':
      PIN_NUMBER='(0,0,0,0,0,0,0,0,0,0,0,0,0,0,CN43,0,0,0,0,0,0,0,0,0,0,0,0,0,0,~
0,0,0,0,0,0,0,0,0,0,0)';
      OUTPUT_LOAD='(1.0,-1.0)';
      PINUSE='OUT';
    'P0_TXN9||SATA11_TXN':
      PIN_NUMBER='(0,0,0,0,0,0,0,0,0,0,0,0,0,0,CN46,0,0,0,0,0,0,0,0,0,0,0,0,0,0,~
0,0,0,0,0,0,0,0,0,0,0)';
      OUTPUT_LOAD='(1.0,-1.0)';
      PINUSE='OUT';
    'P0_RXP13||SATA15_RXP':
      PIN_NUMBER='(0,0,0,0,0,0,0,0,0,0,0,0,0,0,CB40,0,0,0,0,0,0,0,0,0,0,0,0,0,0,~
0,0,0,0,0,0,0,0,0,0,0)';
      INPUT_LOAD='(-0.01,0.01)';
      PINUSE='IN';
    'P0_TXN15||SATA17_TXN':
      PIN_NUMBER='(0,0,0,0,0,0,0,0,0,0,0,0,0,0,CM40,0,0,0,0,0,0,0,0,0,0,0,0,0,0,~
0,0,0,0,0,0,0,0,0,0,0)';
      OUTPUT_LOAD='(1.0,-1.0)';
      PINUSE='OUT';
    'P0_RXN14||SATA16_RXN':
      PIN_NUMBER='(0,0,0,0,0,0,0,0,0,0,0,0,0,0,BV41,0,0,0,0,0,0,0,0,0,0,0,0,0,0,~
0,0,0,0,0,0,0,0,0,0,0)';
      INPUT_LOAD='(-0.01,0.01)';
      PINUSE='IN';
    'P0_RXN11||SATA13_RXN':
      PIN_NUMBER='(0,0,0,0,0,0,0,0,0,0,0,0,0,0,BU44,0,0,0,0,0,0,0,0,0,0,0,0,0,0,~
0,0,0,0,0,0,0,0,0,0,0)';
      INPUT_LOAD='(-0.01,0.01)';
      PINUSE='IN';
    'P0_TXP15||SATA17_TXP':
      PIN_NUMBER='(0,0,0,0,0,0,0,0,0,0,0,0,0,0,CM41,0,0,0,0,0,0,0,0,0,0,0,0,0,0,~
0,0,0,0,0,0,0,0,0,0,0)';
      OUTPUT_LOAD='(1.0,-1.0)';
      PINUSE='OUT';
    'P0_TXP12||SATA14_TXP':
      PIN_NUMBER='(0,0,0,0,0,0,0,0,0,0,0,0,0,0,CN44,0,0,0,0,0,0,0,0,0,0,0,0,0,0,~
0,0,0,0,0,0,0,0,0,0,0)';
      OUTPUT_LOAD='(1.0,-1.0)';
      PINUSE='OUT';
    'P0_RXP11||SATA13_RXP':
      PIN_NUMBER='(0,0,0,0,0,0,0,0,0,0,0,0,0,0,BU43,0,0,0,0,0,0,0,0,0,0,0,0,0,0,~
0,0,0,0,0,0,0,0,0,0,0)';
      INPUT_LOAD='(-0.01,0.01)';
      PINUSE='IN';
    'P1_RXP8':
      PIN_NUMBER='(0,0,0,0,0,0,0,0,0,0,0,0,0,0,0,CC46,0,0,0,0,0,0,0,0,0,0,0,0,0,~
0,0,0,0,0,0,0,0,0,0,0)';
      INPUT_LOAD='(-0.01,0.01)';
      PINUSE='IN';
    'P1_RXN8':
      PIN_NUMBER='(0,0,0,0,0,0,0,0,0,0,0,0,0,0,0,CC47,0,0,0,0,0,0,0,0,0,0,0,0,0,~
0,0,0,0,0,0,0,0,0,0,0)';
      INPUT_LOAD='(-0.01,0.01)';
      PINUSE='IN';
    'P1_RXP9':
      PIN_NUMBER='(0,0,0,0,0,0,0,0,0,0,0,0,0,0,0,CE43,0,0,0,0,0,0,0,0,0,0,0,0,0,~
0,0,0,0,0,0,0,0,0,0,0)';
      INPUT_LOAD='(-0.01,0.01)';
      PINUSE='IN';
    'P1_RXN9':
      PIN_NUMBER='(0,0,0,0,0,0,0,0,0,0,0,0,0,0,0,CE44,0,0,0,0,0,0,0,0,0,0,0,0,0,~
0,0,0,0,0,0,0,0,0,0,0)';
      INPUT_LOAD='(-0.01,0.01)';
      PINUSE='IN';
    'P1_RXP10':
      PIN_NUMBER='(0,0,0,0,0,0,0,0,0,0,0,0,0,0,0,CG43,0,0,0,0,0,0,0,0,0,0,0,0,0,~
0,0,0,0,0,0,0,0,0,0,0)';
      INPUT_LOAD='(-0.01,0.01)';
      PINUSE='IN';
    'P1_RXN10':
      PIN_NUMBER='(0,0,0,0,0,0,0,0,0,0,0,0,0,0,0,CG44,0,0,0,0,0,0,0,0,0,0,0,0,0,~
0,0,0,0,0,0,0,0,0,0,0)';
      INPUT_LOAD='(-0.01,0.01)';
      PINUSE='IN';
    'P1_RXP11':
      PIN_NUMBER='(0,0,0,0,0,0,0,0,0,0,0,0,0,0,0,CJ43,0,0,0,0,0,0,0,0,0,0,0,0,0,~
0,0,0,0,0,0,0,0,0,0,0)';
      INPUT_LOAD='(-0.01,0.01)';
      PINUSE='IN';
    'P1_RXN11':
      PIN_NUMBER='(0,0,0,0,0,0,0,0,0,0,0,0,0,0,0,CJ44,0,0,0,0,0,0,0,0,0,0,0,0,0,~
0,0,0,0,0,0,0,0,0,0,0)';
      INPUT_LOAD='(-0.01,0.01)';
      PINUSE='IN';
    'P1_RXP12':
      PIN_NUMBER='(0,0,0,0,0,0,0,0,0,0,0,0,0,0,0,CC43,0,0,0,0,0,0,0,0,0,0,0,0,0,~
0,0,0,0,0,0,0,0,0,0,0)';
      INPUT_LOAD='(-0.01,0.01)';
      PINUSE='IN';
    'P1_RXN12':
      PIN_NUMBER='(0,0,0,0,0,0,0,0,0,0,0,0,0,0,0,CC44,0,0,0,0,0,0,0,0,0,0,0,0,0,~
0,0,0,0,0,0,0,0,0,0,0)';
      INPUT_LOAD='(-0.01,0.01)';
      PINUSE='IN';
    'P1_RXP13':
      PIN_NUMBER='(0,0,0,0,0,0,0,0,0,0,0,0,0,0,0,CH40,0,0,0,0,0,0,0,0,0,0,0,0,0,~
0,0,0,0,0,0,0,0,0,0,0)';
      INPUT_LOAD='(-0.01,0.01)';
      PINUSE='IN';
    'P1_RXN13':
      PIN_NUMBER='(0,0,0,0,0,0,0,0,0,0,0,0,0,0,0,CH41,0,0,0,0,0,0,0,0,0,0,0,0,0,~
0,0,0,0,0,0,0,0,0,0,0)';
      INPUT_LOAD='(-0.01,0.01)';
      PINUSE='IN';
    'P1_RXP14':
      PIN_NUMBER='(0,0,0,0,0,0,0,0,0,0,0,0,0,0,0,CF40,0,0,0,0,0,0,0,0,0,0,0,0,0,~
0,0,0,0,0,0,0,0,0,0,0)';
      INPUT_LOAD='(-0.01,0.01)';
      PINUSE='IN';
    'P1_RXN14':
      PIN_NUMBER='(0,0,0,0,0,0,0,0,0,0,0,0,0,0,0,CF41,0,0,0,0,0,0,0,0,0,0,0,0,0,~
0,0,0,0,0,0,0,0,0,0,0)';
      INPUT_LOAD='(-0.01,0.01)';
      PINUSE='IN';
    'P1_RXP15':
      PIN_NUMBER='(0,0,0,0,0,0,0,0,0,0,0,0,0,0,0,CD40,0,0,0,0,0,0,0,0,0,0,0,0,0,~
0,0,0,0,0,0,0,0,0,0,0)';
      INPUT_LOAD='(-0.01,0.01)';
      PINUSE='IN';
    'P1_RXN15':
      PIN_NUMBER='(0,0,0,0,0,0,0,0,0,0,0,0,0,0,0,CD41,0,0,0,0,0,0,0,0,0,0,0,0,0,~
0,0,0,0,0,0,0,0,0,0,0)';
      INPUT_LOAD='(-0.01,0.01)';
      PINUSE='IN';
    'P1_TXP8':
      PIN_NUMBER='(0,0,0,0,0,0,0,0,0,0,0,0,0,0,0,DC47,0,0,0,0,0,0,0,0,0,0,0,0,0,~
0,0,0,0,0,0,0,0,0,0,0)';
      OUTPUT_LOAD='(1.0,-1.0)';
      PINUSE='OUT';
    'P1_TXN8':
      PIN_NUMBER='(0,0,0,0,0,0,0,0,0,0,0,0,0,0,0,DC46,0,0,0,0,0,0,0,0,0,0,0,0,0,~
0,0,0,0,0,0,0,0,0,0,0)';
      OUTPUT_LOAD='(1.0,-1.0)';
      PINUSE='OUT';
    'P1_TXP9':
      PIN_NUMBER='(0,0,0,0,0,0,0,0,0,0,0,0,0,0,0,CW47,0,0,0,0,0,0,0,0,0,0,0,0,0,~
0,0,0,0,0,0,0,0,0,0,0)';
      OUTPUT_LOAD='(1.0,-1.0)';
      PINUSE='OUT';
    'P1_TXN9':
      PIN_NUMBER='(0,0,0,0,0,0,0,0,0,0,0,0,0,0,0,CW46,0,0,0,0,0,0,0,0,0,0,0,0,0,~
0,0,0,0,0,0,0,0,0,0,0)';
      OUTPUT_LOAD='(1.0,-1.0)';
      PINUSE='OUT';
    'P1_TXP10':
      PIN_NUMBER='(0,0,0,0,0,0,0,0,0,0,0,0,0,0,0,DA44,0,0,0,0,0,0,0,0,0,0,0,0,0,~
0,0,0,0,0,0,0,0,0,0,0)';
      OUTPUT_LOAD='(1.0,-1.0)';
      PINUSE='OUT';
    'P1_TXN10':
      PIN_NUMBER='(0,0,0,0,0,0,0,0,0,0,0,0,0,0,0,DA43,0,0,0,0,0,0,0,0,0,0,0,0,0,~
0,0,0,0,0,0,0,0,0,0,0)';
      OUTPUT_LOAD='(1.0,-1.0)';
      PINUSE='OUT';
    'P1_TXP11':
      PIN_NUMBER='(0,0,0,0,0,0,0,0,0,0,0,0,0,0,0,DC44,0,0,0,0,0,0,0,0,0,0,0,0,0,~
0,0,0,0,0,0,0,0,0,0,0)';
      OUTPUT_LOAD='(1.0,-1.0)';
      PINUSE='OUT';
    'P1_TXN11':
      PIN_NUMBER='(0,0,0,0,0,0,0,0,0,0,0,0,0,0,0,DC43,0,0,0,0,0,0,0,0,0,0,0,0,0,~
0,0,0,0,0,0,0,0,0,0,0)';
      OUTPUT_LOAD='(1.0,-1.0)';
      PINUSE='OUT';
    'P1_TXP12':
      PIN_NUMBER='(0,0,0,0,0,0,0,0,0,0,0,0,0,0,0,CW44,0,0,0,0,0,0,0,0,0,0,0,0,0,~
0,0,0,0,0,0,0,0,0,0,0)';
      OUTPUT_LOAD='(1.0,-1.0)';
      PINUSE='OUT';
    'P1_TXN12':
      PIN_NUMBER='(0,0,0,0,0,0,0,0,0,0,0,0,0,0,0,CW43,0,0,0,0,0,0,0,0,0,0,0,0,0,~
0,0,0,0,0,0,0,0,0,0,0)';
      OUTPUT_LOAD='(1.0,-1.0)';
      PINUSE='OUT';
    'P1_TXP13':
      PIN_NUMBER='(0,0,0,0,0,0,0,0,0,0,0,0,0,0,0,DB41,0,0,0,0,0,0,0,0,0,0,0,0,0,~
0,0,0,0,0,0,0,0,0,0,0)';
      OUTPUT_LOAD='(1.0,-1.0)';
      PINUSE='OUT';
    'P1_TXN13':
      PIN_NUMBER='(0,0,0,0,0,0,0,0,0,0,0,0,0,0,0,DB40,0,0,0,0,0,0,0,0,0,0,0,0,0,~
0,0,0,0,0,0,0,0,0,0,0)';
      OUTPUT_LOAD='(1.0,-1.0)';
      PINUSE='OUT';
    'P1_TXP14':
      PIN_NUMBER='(0,0,0,0,0,0,0,0,0,0,0,0,0,0,0,CY41,0,0,0,0,0,0,0,0,0,0,0,0,0,~
0,0,0,0,0,0,0,0,0,0,0)';
      OUTPUT_LOAD='(1.0,-1.0)';
      PINUSE='OUT';
    'P1_TXN14':
      PIN_NUMBER='(0,0,0,0,0,0,0,0,0,0,0,0,0,0,0,CY40,0,0,0,0,0,0,0,0,0,0,0,0,0,~
0,0,0,0,0,0,0,0,0,0,0)';
      OUTPUT_LOAD='(1.0,-1.0)';
      PINUSE='OUT';
    'P1_TXP15':
      PIN_NUMBER='(0,0,0,0,0,0,0,0,0,0,0,0,0,0,0,CV41,0,0,0,0,0,0,0,0,0,0,0,0,0,~
0,0,0,0,0,0,0,0,0,0,0)';
      OUTPUT_LOAD='(1.0,-1.0)';
      PINUSE='OUT';
    'P1_TXN15':
      PIN_NUMBER='(0,0,0,0,0,0,0,0,0,0,0,0,0,0,0,CV40,0,0,0,0,0,0,0,0,0,0,0,0,0,~
0,0,0,0,0,0,0,0,0,0,0)';
      OUTPUT_LOAD='(1.0,-1.0)';
      PINUSE='OUT';
    'P1_RXN7':
      PIN_NUMBER='(0,0,0,0,0,0,0,0,0,0,0,0,0,0,0,CG47,0,0,0,0,0,0,0,0,0,0,0,0,0,~
0,0,0,0,0,0,0,0,0,0,0)';
      INPUT_LOAD='(-0.01,0.01)';
      PINUSE='IN';
    'P1_TXP0':
      PIN_NUMBER='(0,0,0,0,0,0,0,0,0,0,0,0,0,0,0,CU53,0,0,0,0,0,0,0,0,0,0,0,0,0,~
0,0,0,0,0,0,0,0,0,0,0)';
      OUTPUT_LOAD='(1.0,-1.0)';
      PINUSE='OUT';
    'P1_TXP1':
      PIN_NUMBER='(0,0,0,0,0,0,0,0,0,0,0,0,0,0,0,DA53,0,0,0,0,0,0,0,0,0,0,0,0,0,~
0,0,0,0,0,0,0,0,0,0,0)';
      OUTPUT_LOAD='(1.0,-1.0)';
      PINUSE='OUT';
    'P1_TXP2':
      PIN_NUMBER='(0,0,0,0,0,0,0,0,0,0,0,0,0,0,0,DC53,0,0,0,0,0,0,0,0,0,0,0,0,0,~
0,0,0,0,0,0,0,0,0,0,0)';
      OUTPUT_LOAD='(1.0,-1.0)';
      PINUSE='OUT';
    'P1_TXN0':
      PIN_NUMBER='(0,0,0,0,0,0,0,0,0,0,0,0,0,0,0,CU52,0,0,0,0,0,0,0,0,0,0,0,0,0,~
0,0,0,0,0,0,0,0,0,0,0)';
      OUTPUT_LOAD='(1.0,-1.0)';
      PINUSE='OUT';
    'P1_RXP0':
      PIN_NUMBER='(0,0,0,0,0,0,0,0,0,0,0,0,0,0,0,CE52,0,0,0,0,0,0,0,0,0,0,0,0,0,~
0,0,0,0,0,0,0,0,0,0,0)';
      INPUT_LOAD='(-0.01,0.01)';
      PINUSE='IN';
    'P1_TXP3':
      PIN_NUMBER='(0,0,0,0,0,0,0,0,0,0,0,0,0,0,0,CW53,0,0,0,0,0,0,0,0,0,0,0,0,0,~
0,0,0,0,0,0,0,0,0,0,0)';
      OUTPUT_LOAD='(1.0,-1.0)';
      PINUSE='OUT';
    'P1_TXN1':
      PIN_NUMBER='(0,0,0,0,0,0,0,0,0,0,0,0,0,0,0,DA52,0,0,0,0,0,0,0,0,0,0,0,0,0,~
0,0,0,0,0,0,0,0,0,0,0)';
      OUTPUT_LOAD='(1.0,-1.0)';
      PINUSE='OUT';
    'P1_RXP1':
      PIN_NUMBER='(0,0,0,0,0,0,0,0,0,0,0,0,0,0,0,CG52,0,0,0,0,0,0,0,0,0,0,0,0,0,~
0,0,0,0,0,0,0,0,0,0,0)';
      INPUT_LOAD='(-0.01,0.01)';
      PINUSE='IN';
    'P1_TXP4':
      PIN_NUMBER='(0,0,0,0,0,0,0,0,0,0,0,0,0,0,0,DA50,0,0,0,0,0,0,0,0,0,0,0,0,0,~
0,0,0,0,0,0,0,0,0,0,0)';
      OUTPUT_LOAD='(1.0,-1.0)';
      PINUSE='OUT';
    'P1_TXN2':
      PIN_NUMBER='(0,0,0,0,0,0,0,0,0,0,0,0,0,0,0,DC52,0,0,0,0,0,0,0,0,0,0,0,0,0,~
0,0,0,0,0,0,0,0,0,0,0)';
      OUTPUT_LOAD='(1.0,-1.0)';
      PINUSE='OUT';
    'P1_RXP2':
      PIN_NUMBER='(0,0,0,0,0,0,0,0,0,0,0,0,0,0,0,CC52,0,0,0,0,0,0,0,0,0,0,0,0,0,~
0,0,0,0,0,0,0,0,0,0,0)';
      INPUT_LOAD='(-0.01,0.01)';
      PINUSE='IN';
    'P1_RXN0':
      PIN_NUMBER='(0,0,0,0,0,0,0,0,0,0,0,0,0,0,0,CE53,0,0,0,0,0,0,0,0,0,0,0,0,0,~
0,0,0,0,0,0,0,0,0,0,0)';
      INPUT_LOAD='(-0.01,0.01)';
      PINUSE='IN';
    'P1_TXP5':
      PIN_NUMBER='(0,0,0,0,0,0,0,0,0,0,0,0,0,0,0,DC50,0,0,0,0,0,0,0,0,0,0,0,0,0,~
0,0,0,0,0,0,0,0,0,0,0)';
      OUTPUT_LOAD='(1.0,-1.0)';
      PINUSE='OUT';
    'P1_TXN3':
      PIN_NUMBER='(0,0,0,0,0,0,0,0,0,0,0,0,0,0,0,CW52,0,0,0,0,0,0,0,0,0,0,0,0,0,~
0,0,0,0,0,0,0,0,0,0,0)';
      OUTPUT_LOAD='(1.0,-1.0)';
      PINUSE='OUT';
    'P1_RXP3':
      PIN_NUMBER='(0,0,0,0,0,0,0,0,0,0,0,0,0,0,0,CE49,0,0,0,0,0,0,0,0,0,0,0,0,0,~
0,0,0,0,0,0,0,0,0,0,0)';
      INPUT_LOAD='(-0.01,0.01)';
      PINUSE='IN';
    'P1_RXN1':
      PIN_NUMBER='(0,0,0,0,0,0,0,0,0,0,0,0,0,0,0,CG53,0,0,0,0,0,0,0,0,0,0,0,0,0,~
0,0,0,0,0,0,0,0,0,0,0)';
      INPUT_LOAD='(-0.01,0.01)';
      PINUSE='IN';
    'P1_TXP6':
      PIN_NUMBER='(0,0,0,0,0,0,0,0,0,0,0,0,0,0,0,CW50,0,0,0,0,0,0,0,0,0,0,0,0,0,~
0,0,0,0,0,0,0,0,0,0,0)';
      OUTPUT_LOAD='(1.0,-1.0)';
      PINUSE='OUT';
    'P1_TXN4':
      PIN_NUMBER='(0,0,0,0,0,0,0,0,0,0,0,0,0,0,0,DA49,0,0,0,0,0,0,0,0,0,0,0,0,0,~
0,0,0,0,0,0,0,0,0,0,0)';
      OUTPUT_LOAD='(1.0,-1.0)';
      PINUSE='OUT';
    'P1_RXP4':
      PIN_NUMBER='(0,0,0,0,0,0,0,0,0,0,0,0,0,0,0,CG49,0,0,0,0,0,0,0,0,0,0,0,0,0,~
0,0,0,0,0,0,0,0,0,0,0)';
      INPUT_LOAD='(-0.01,0.01)';
      PINUSE='IN';
    'P1_RXN2':
      PIN_NUMBER='(0,0,0,0,0,0,0,0,0,0,0,0,0,0,0,CC53,0,0,0,0,0,0,0,0,0,0,0,0,0,~
0,0,0,0,0,0,0,0,0,0,0)';
      INPUT_LOAD='(-0.01,0.01)';
      PINUSE='IN';
    'P1_TXP7':
      PIN_NUMBER='(0,0,0,0,0,0,0,0,0,0,0,0,0,0,0,DA47,0,0,0,0,0,0,0,0,0,0,0,0,0,~
0,0,0,0,0,0,0,0,0,0,0)';
      OUTPUT_LOAD='(1.0,-1.0)';
      PINUSE='OUT';
    'P1_TXN5':
      PIN_NUMBER='(0,0,0,0,0,0,0,0,0,0,0,0,0,0,0,DC49,0,0,0,0,0,0,0,0,0,0,0,0,0,~
0,0,0,0,0,0,0,0,0,0,0)';
      OUTPUT_LOAD='(1.0,-1.0)';
      PINUSE='OUT';
    'P1_RXP5':
      PIN_NUMBER='(0,0,0,0,0,0,0,0,0,0,0,0,0,0,0,CC49,0,0,0,0,0,0,0,0,0,0,0,0,0,~
0,0,0,0,0,0,0,0,0,0,0)';
      INPUT_LOAD='(-0.01,0.01)';
      PINUSE='IN';
    'P1_RXN3':
      PIN_NUMBER='(0,0,0,0,0,0,0,0,0,0,0,0,0,0,0,CE50,0,0,0,0,0,0,0,0,0,0,0,0,0,~
0,0,0,0,0,0,0,0,0,0,0)';
      INPUT_LOAD='(-0.01,0.01)';
      PINUSE='IN';
    'P1_TXN6':
      PIN_NUMBER='(0,0,0,0,0,0,0,0,0,0,0,0,0,0,0,CW49,0,0,0,0,0,0,0,0,0,0,0,0,0,~
0,0,0,0,0,0,0,0,0,0,0)';
      OUTPUT_LOAD='(1.0,-1.0)';
      PINUSE='OUT';
    'P1_RXP6':
      PIN_NUMBER='(0,0,0,0,0,0,0,0,0,0,0,0,0,0,0,CE46,0,0,0,0,0,0,0,0,0,0,0,0,0,~
0,0,0,0,0,0,0,0,0,0,0)';
      INPUT_LOAD='(-0.01,0.01)';
      PINUSE='IN';
    'P1_RXN4':
      PIN_NUMBER='(0,0,0,0,0,0,0,0,0,0,0,0,0,0,0,CG50,0,0,0,0,0,0,0,0,0,0,0,0,0,~
0,0,0,0,0,0,0,0,0,0,0)';
      INPUT_LOAD='(-0.01,0.01)';
      PINUSE='IN';
    'P1_TXN7':
      PIN_NUMBER='(0,0,0,0,0,0,0,0,0,0,0,0,0,0,0,DA46,0,0,0,0,0,0,0,0,0,0,0,0,0,~
0,0,0,0,0,0,0,0,0,0,0)';
      OUTPUT_LOAD='(1.0,-1.0)';
      PINUSE='OUT';
    'P1_RXP7':
      PIN_NUMBER='(0,0,0,0,0,0,0,0,0,0,0,0,0,0,0,CG46,0,0,0,0,0,0,0,0,0,0,0,0,0,~
0,0,0,0,0,0,0,0,0,0,0)';
      INPUT_LOAD='(-0.01,0.01)';
      PINUSE='IN';
    'P1_RXN5':
      PIN_NUMBER='(0,0,0,0,0,0,0,0,0,0,0,0,0,0,0,CC50,0,0,0,0,0,0,0,0,0,0,0,0,0,~
0,0,0,0,0,0,0,0,0,0,0)';
      INPUT_LOAD='(-0.01,0.01)';
      PINUSE='IN';
    'P1_RXN6':
      PIN_NUMBER='(0,0,0,0,0,0,0,0,0,0,0,0,0,0,0,CE47,0,0,0,0,0,0,0,0,0,0,0,0,0,~
0,0,0,0,0,0,0,0,0,0,0)';
      INPUT_LOAD='(-0.01,0.01)';
      PINUSE='IN';
    'P2_RXP8':
      PIN_NUMBER='(0,0,0,0,0,0,0,0,0,0,0,0,0,0,0,0,CR29,0,0,0,0,0,0,0,0,0,0,0,0,~
0,0,0,0,0,0,0,0,0,0,0)';
      INPUT_LOAD='(-0.01,0.01)';
      PINUSE='IN';
    'P2_RXN8':
      PIN_NUMBER='(0,0,0,0,0,0,0,0,0,0,0,0,0,0,0,0,CR30,0,0,0,0,0,0,0,0,0,0,0,0,~
0,0,0,0,0,0,0,0,0,0,0)';
      INPUT_LOAD='(-0.01,0.01)';
      PINUSE='IN';
    'P2_RXP9':
      PIN_NUMBER='(0,0,0,0,0,0,0,0,0,0,0,0,0,0,0,0,CL26,0,0,0,0,0,0,0,0,0,0,0,0,~
0,0,0,0,0,0,0,0,0,0,0)';
      INPUT_LOAD='(-0.01,0.01)';
      PINUSE='IN';
    'P2_RXN9':
      PIN_NUMBER='(0,0,0,0,0,0,0,0,0,0,0,0,0,0,0,0,CL27,0,0,0,0,0,0,0,0,0,0,0,0,~
0,0,0,0,0,0,0,0,0,0,0)';
      INPUT_LOAD='(-0.01,0.01)';
      PINUSE='IN';
    'P2_RXP10':
      PIN_NUMBER='(0,0,0,0,0,0,0,0,0,0,0,0,0,0,0,0,CU26,0,0,0,0,0,0,0,0,0,0,0,0,~
0,0,0,0,0,0,0,0,0,0,0)';
      INPUT_LOAD='(-0.01,0.01)';
      PINUSE='IN';
    'P2_RXN10':
      PIN_NUMBER='(0,0,0,0,0,0,0,0,0,0,0,0,0,0,0,0,CU27,0,0,0,0,0,0,0,0,0,0,0,0,~
0,0,0,0,0,0,0,0,0,0,0)';
      INPUT_LOAD='(-0.01,0.01)';
      PINUSE='IN';
    'P2_RXP11':
      PIN_NUMBER='(0,0,0,0,0,0,0,0,0,0,0,0,0,0,0,0,CR26,0,0,0,0,0,0,0,0,0,0,0,0,~
0,0,0,0,0,0,0,0,0,0,0)';
      INPUT_LOAD='(-0.01,0.01)';
      PINUSE='IN';
    'P2_RXN11':
      PIN_NUMBER='(0,0,0,0,0,0,0,0,0,0,0,0,0,0,0,0,CR27,0,0,0,0,0,0,0,0,0,0,0,0,~
0,0,0,0,0,0,0,0,0,0,0)';
      INPUT_LOAD='(-0.01,0.01)';
      PINUSE='IN';
    'P2_RXP12':
      PIN_NUMBER='(0,0,0,0,0,0,0,0,0,0,0,0,0,0,0,0,CN26,0,0,0,0,0,0,0,0,0,0,0,0,~
0,0,0,0,0,0,0,0,0,0,0)';
      INPUT_LOAD='(-0.01,0.01)';
      PINUSE='IN';
    'P2_RXN12':
      PIN_NUMBER='(0,0,0,0,0,0,0,0,0,0,0,0,0,0,0,0,CN27,0,0,0,0,0,0,0,0,0,0,0,0,~
0,0,0,0,0,0,0,0,0,0,0)';
      INPUT_LOAD='(-0.01,0.01)';
      PINUSE='IN';
    'P2_RXP13':
      PIN_NUMBER='(0,0,0,0,0,0,0,0,0,0,0,0,0,0,0,0,CL23,0,0,0,0,0,0,0,0,0,0,0,0,~
0,0,0,0,0,0,0,0,0,0,0)';
      INPUT_LOAD='(-0.01,0.01)';
      PINUSE='IN';
    'P2_RXN13':
      PIN_NUMBER='(0,0,0,0,0,0,0,0,0,0,0,0,0,0,0,0,CL24,0,0,0,0,0,0,0,0,0,0,0,0,~
0,0,0,0,0,0,0,0,0,0,0)';
      INPUT_LOAD='(-0.01,0.01)';
      PINUSE='IN';
    'P2_RXP14':
      PIN_NUMBER='(0,0,0,0,0,0,0,0,0,0,0,0,0,0,0,0,CR23,0,0,0,0,0,0,0,0,0,0,0,0,~
0,0,0,0,0,0,0,0,0,0,0)';
      INPUT_LOAD='(-0.01,0.01)';
      PINUSE='IN';
    'P2_RXN14':
      PIN_NUMBER='(0,0,0,0,0,0,0,0,0,0,0,0,0,0,0,0,CR24,0,0,0,0,0,0,0,0,0,0,0,0,~
0,0,0,0,0,0,0,0,0,0,0)';
      INPUT_LOAD='(-0.01,0.01)';
      PINUSE='IN';
    'P2_RXP15':
      PIN_NUMBER='(0,0,0,0,0,0,0,0,0,0,0,0,0,0,0,0,CN23,0,0,0,0,0,0,0,0,0,0,0,0,~
0,0,0,0,0,0,0,0,0,0,0)';
      INPUT_LOAD='(-0.01,0.01)';
      PINUSE='IN';
    'P2_RXN15':
      PIN_NUMBER='(0,0,0,0,0,0,0,0,0,0,0,0,0,0,0,0,CN24,0,0,0,0,0,0,0,0,0,0,0,0,~
0,0,0,0,0,0,0,0,0,0,0)';
      INPUT_LOAD='(-0.01,0.01)';
      PINUSE='IN';
    'P2_TXP8':
      PIN_NUMBER='(0,0,0,0,0,0,0,0,0,0,0,0,0,0,0,0,CA30,0,0,0,0,0,0,0,0,0,0,0,0,~
0,0,0,0,0,0,0,0,0,0,0)';
      OUTPUT_LOAD='(1.0,-1.0)';
      PINUSE='OUT';
    'P2_TXN8':
      PIN_NUMBER='(0,0,0,0,0,0,0,0,0,0,0,0,0,0,0,0,CA29,0,0,0,0,0,0,0,0,0,0,0,0,~
0,0,0,0,0,0,0,0,0,0,0)';
      OUTPUT_LOAD='(1.0,-1.0)';
      PINUSE='OUT';
    'P2_TXP9':
      PIN_NUMBER='(0,0,0,0,0,0,0,0,0,0,0,0,0,0,0,0,BW30,0,0,0,0,0,0,0,0,0,0,0,0,~
0,0,0,0,0,0,0,0,0,0,0)';
      OUTPUT_LOAD='(1.0,-1.0)';
      PINUSE='OUT';
    'P2_TXN9':
      PIN_NUMBER='(0,0,0,0,0,0,0,0,0,0,0,0,0,0,0,0,BW29,0,0,0,0,0,0,0,0,0,0,0,0,~
0,0,0,0,0,0,0,0,0,0,0)';
      OUTPUT_LOAD='(1.0,-1.0)';
      PINUSE='OUT';
    'P2_TXP10':
      PIN_NUMBER='(0,0,0,0,0,0,0,0,0,0,0,0,0,0,0,0,BU27,0,0,0,0,0,0,0,0,0,0,0,0,~
0,0,0,0,0,0,0,0,0,0,0)';
      OUTPUT_LOAD='(1.0,-1.0)';
      PINUSE='OUT';
    'P2_TXN10':
      PIN_NUMBER='(0,0,0,0,0,0,0,0,0,0,0,0,0,0,0,0,BU26,0,0,0,0,0,0,0,0,0,0,0,0,~
0,0,0,0,0,0,0,0,0,0,0)';
      OUTPUT_LOAD='(1.0,-1.0)';
      PINUSE='OUT';
    'P2_TXP11':
      PIN_NUMBER='(0,0,0,0,0,0,0,0,0,0,0,0,0,0,0,0,CA27,0,0,0,0,0,0,0,0,0,0,0,0,~
0,0,0,0,0,0,0,0,0,0,0)';
      OUTPUT_LOAD='(1.0,-1.0)';
      PINUSE='OUT';
    'P2_TXN11':
      PIN_NUMBER='(0,0,0,0,0,0,0,0,0,0,0,0,0,0,0,0,CA26,0,0,0,0,0,0,0,0,0,0,0,0,~
0,0,0,0,0,0,0,0,0,0,0)';
      OUTPUT_LOAD='(1.0,-1.0)';
      PINUSE='OUT';
    'P2_TXP12':
      PIN_NUMBER='(0,0,0,0,0,0,0,0,0,0,0,0,0,0,0,0,BW27,0,0,0,0,0,0,0,0,0,0,0,0,~
0,0,0,0,0,0,0,0,0,0,0)';
      OUTPUT_LOAD='(1.0,-1.0)';
      PINUSE='OUT';
    'P2_TXN12':
      PIN_NUMBER='(0,0,0,0,0,0,0,0,0,0,0,0,0,0,0,0,BW26,0,0,0,0,0,0,0,0,0,0,0,0,~
0,0,0,0,0,0,0,0,0,0,0)';
      OUTPUT_LOAD='(1.0,-1.0)';
      PINUSE='OUT';
    'P2_TXP13':
      PIN_NUMBER='(0,0,0,0,0,0,0,0,0,0,0,0,0,0,0,0,BU24,0,0,0,0,0,0,0,0,0,0,0,0,~
0,0,0,0,0,0,0,0,0,0,0)';
      OUTPUT_LOAD='(1.0,-1.0)';
      PINUSE='OUT';
    'P2_TXN13':
      PIN_NUMBER='(0,0,0,0,0,0,0,0,0,0,0,0,0,0,0,0,BU23,0,0,0,0,0,0,0,0,0,0,0,0,~
0,0,0,0,0,0,0,0,0,0,0)';
      OUTPUT_LOAD='(1.0,-1.0)';
      PINUSE='OUT';
    'P2_TXP14':
      PIN_NUMBER='(0,0,0,0,0,0,0,0,0,0,0,0,0,0,0,0,CA24,0,0,0,0,0,0,0,0,0,0,0,0,~
0,0,0,0,0,0,0,0,0,0,0)';
      OUTPUT_LOAD='(1.0,-1.0)';
      PINUSE='OUT';
    'P2_TXN14':
      PIN_NUMBER='(0,0,0,0,0,0,0,0,0,0,0,0,0,0,0,0,CA23,0,0,0,0,0,0,0,0,0,0,0,0,~
0,0,0,0,0,0,0,0,0,0,0)';
      OUTPUT_LOAD='(1.0,-1.0)';
      PINUSE='OUT';
    'P2_TXP15':
      PIN_NUMBER='(0,0,0,0,0,0,0,0,0,0,0,0,0,0,0,0,BW24,0,0,0,0,0,0,0,0,0,0,0,0,~
0,0,0,0,0,0,0,0,0,0,0)';
      OUTPUT_LOAD='(1.0,-1.0)';
      PINUSE='OUT';
    'P2_TXN15':
      PIN_NUMBER='(0,0,0,0,0,0,0,0,0,0,0,0,0,0,0,0,BW23,0,0,0,0,0,0,0,0,0,0,0,0,~
0,0,0,0,0,0,0,0,0,0,0)';
      OUTPUT_LOAD='(1.0,-1.0)';
      PINUSE='OUT';
    'P2_TXP0':
      PIN_NUMBER='(0,0,0,0,0,0,0,0,0,0,0,0,0,0,0,0,BT36,0,0,0,0,0,0,0,0,0,0,0,0,~
0,0,0,0,0,0,0,0,0,0,0)';
      OUTPUT_LOAD='(1.0,-1.0)';
      PINUSE='OUT';
    'P2_TXP1':
      PIN_NUMBER='(0,0,0,0,0,0,0,0,0,0,0,0,0,0,0,0,BV36,0,0,0,0,0,0,0,0,0,0,0,0,~
0,0,0,0,0,0,0,0,0,0,0)';
      OUTPUT_LOAD='(1.0,-1.0)';
      PINUSE='OUT';
    'P2_TXP2':
      PIN_NUMBER='(0,0,0,0,0,0,0,0,0,0,0,0,0,0,0,0,CB36,0,0,0,0,0,0,0,0,0,0,0,0,~
0,0,0,0,0,0,0,0,0,0,0)';
      OUTPUT_LOAD='(1.0,-1.0)';
      PINUSE='OUT';
    'P2_TXN0':
      PIN_NUMBER='(0,0,0,0,0,0,0,0,0,0,0,0,0,0,0,0,BT35,0,0,0,0,0,0,0,0,0,0,0,0,~
0,0,0,0,0,0,0,0,0,0,0)';
      OUTPUT_LOAD='(1.0,-1.0)';
      PINUSE='OUT';
    'P2_RXP0':
      PIN_NUMBER='(0,0,0,0,0,0,0,0,0,0,0,0,0,0,0,0,CM35,0,0,0,0,0,0,0,0,0,0,0,0,~
0,0,0,0,0,0,0,0,0,0,0)';
      INPUT_LOAD='(-0.01,0.01)';
      PINUSE='IN';
    'P2_TXP3':
      PIN_NUMBER='(0,0,0,0,0,0,0,0,0,0,0,0,0,0,0,0,BY36,0,0,0,0,0,0,0,0,0,0,0,0,~
0,0,0,0,0,0,0,0,0,0,0)';
      OUTPUT_LOAD='(1.0,-1.0)';
      PINUSE='OUT';
    'P2_TXN1':
      PIN_NUMBER='(0,0,0,0,0,0,0,0,0,0,0,0,0,0,0,0,BV35,0,0,0,0,0,0,0,0,0,0,0,0,~
0,0,0,0,0,0,0,0,0,0,0)';
      OUTPUT_LOAD='(1.0,-1.0)';
      PINUSE='OUT';
    'P2_RXP1':
      PIN_NUMBER='(0,0,0,0,0,0,0,0,0,0,0,0,0,0,0,0,CP35,0,0,0,0,0,0,0,0,0,0,0,0,~
0,0,0,0,0,0,0,0,0,0,0)';
      INPUT_LOAD='(-0.01,0.01)';
      PINUSE='IN';
    'P2_TXP4':
      PIN_NUMBER='(0,0,0,0,0,0,0,0,0,0,0,0,0,0,0,0,BU33,0,0,0,0,0,0,0,0,0,0,0,0,~
0,0,0,0,0,0,0,0,0,0,0)';
      OUTPUT_LOAD='(1.0,-1.0)';
      PINUSE='OUT';
    'P2_TXN2':
      PIN_NUMBER='(0,0,0,0,0,0,0,0,0,0,0,0,0,0,0,0,CB35,0,0,0,0,0,0,0,0,0,0,0,0,~
0,0,0,0,0,0,0,0,0,0,0)';
      OUTPUT_LOAD='(1.0,-1.0)';
      PINUSE='OUT';
    'P2_RXP2':
      PIN_NUMBER='(0,0,0,0,0,0,0,0,0,0,0,0,0,0,0,0,CT35,0,0,0,0,0,0,0,0,0,0,0,0,~
0,0,0,0,0,0,0,0,0,0,0)';
      INPUT_LOAD='(-0.01,0.01)';
      PINUSE='IN';
    'P2_RXN0':
      PIN_NUMBER='(0,0,0,0,0,0,0,0,0,0,0,0,0,0,0,0,CM36,0,0,0,0,0,0,0,0,0,0,0,0,~
0,0,0,0,0,0,0,0,0,0,0)';
      INPUT_LOAD='(-0.01,0.01)';
      PINUSE='IN';
    'P2_TXP5':
      PIN_NUMBER='(0,0,0,0,0,0,0,0,0,0,0,0,0,0,0,0,CA33,0,0,0,0,0,0,0,0,0,0,0,0,~
0,0,0,0,0,0,0,0,0,0,0)';
      OUTPUT_LOAD='(1.0,-1.0)';
      PINUSE='OUT';
    'P2_TXN3':
      PIN_NUMBER='(0,0,0,0,0,0,0,0,0,0,0,0,0,0,0,0,BY35,0,0,0,0,0,0,0,0,0,0,0,0,~
0,0,0,0,0,0,0,0,0,0,0)';
      OUTPUT_LOAD='(1.0,-1.0)';
      PINUSE='OUT';
    'P2_RXP3':
      PIN_NUMBER='(0,0,0,0,0,0,0,0,0,0,0,0,0,0,0,0,CN32,0,0,0,0,0,0,0,0,0,0,0,0,~
0,0,0,0,0,0,0,0,0,0,0)';
      INPUT_LOAD='(-0.01,0.01)';
      PINUSE='IN';
    'P2_RXN1':
      PIN_NUMBER='(0,0,0,0,0,0,0,0,0,0,0,0,0,0,0,0,CP36,0,0,0,0,0,0,0,0,0,0,0,0,~
0,0,0,0,0,0,0,0,0,0,0)';
      INPUT_LOAD='(-0.01,0.01)';
      PINUSE='IN';
    'P2_TXP6':
      PIN_NUMBER='(0,0,0,0,0,0,0,0,0,0,0,0,0,0,0,0,BW33,0,0,0,0,0,0,0,0,0,0,0,0,~
0,0,0,0,0,0,0,0,0,0,0)';
      OUTPUT_LOAD='(1.0,-1.0)';
      PINUSE='OUT';
    'P2_TXN4':
      PIN_NUMBER='(0,0,0,0,0,0,0,0,0,0,0,0,0,0,0,0,BU32,0,0,0,0,0,0,0,0,0,0,0,0,~
0,0,0,0,0,0,0,0,0,0,0)';
      OUTPUT_LOAD='(1.0,-1.0)';
      PINUSE='OUT';
    'P2_RXP4':
      PIN_NUMBER='(0,0,0,0,0,0,0,0,0,0,0,0,0,0,0,0,CU32,0,0,0,0,0,0,0,0,0,0,0,0,~
0,0,0,0,0,0,0,0,0,0,0)';
      INPUT_LOAD='(-0.01,0.01)';
      PINUSE='IN';
    'P2_RXN2':
      PIN_NUMBER='(0,0,0,0,0,0,0,0,0,0,0,0,0,0,0,0,CT36,0,0,0,0,0,0,0,0,0,0,0,0,~
0,0,0,0,0,0,0,0,0,0,0)';
      INPUT_LOAD='(-0.01,0.01)';
      PINUSE='IN';
    'P2_TXP7':
      PIN_NUMBER='(0,0,0,0,0,0,0,0,0,0,0,0,0,0,0,0,BU30,0,0,0,0,0,0,0,0,0,0,0,0,~
0,0,0,0,0,0,0,0,0,0,0)';
      OUTPUT_LOAD='(1.0,-1.0)';
      PINUSE='OUT';
    'P2_TXN5':
      PIN_NUMBER='(0,0,0,0,0,0,0,0,0,0,0,0,0,0,0,0,CA32,0,0,0,0,0,0,0,0,0,0,0,0,~
0,0,0,0,0,0,0,0,0,0,0)';
      OUTPUT_LOAD='(1.0,-1.0)';
      PINUSE='OUT';
    'P2_RXP5':
      PIN_NUMBER='(0,0,0,0,0,0,0,0,0,0,0,0,0,0,0,0,CR32,0,0,0,0,0,0,0,0,0,0,0,0,~
0,0,0,0,0,0,0,0,0,0,0)';
      INPUT_LOAD='(-0.01,0.01)';
      PINUSE='IN';
    'P2_RXN3':
      PIN_NUMBER='(0,0,0,0,0,0,0,0,0,0,0,0,0,0,0,0,CN33,0,0,0,0,0,0,0,0,0,0,0,0,~
0,0,0,0,0,0,0,0,0,0,0)';
      INPUT_LOAD='(-0.01,0.01)';
      PINUSE='IN';
    'P2_TXN6':
      PIN_NUMBER='(0,0,0,0,0,0,0,0,0,0,0,0,0,0,0,0,BW32,0,0,0,0,0,0,0,0,0,0,0,0,~
0,0,0,0,0,0,0,0,0,0,0)';
      OUTPUT_LOAD='(1.0,-1.0)';
      PINUSE='OUT';
    'P2_RXP6':
      PIN_NUMBER='(0,0,0,0,0,0,0,0,0,0,0,0,0,0,0,0,CN29,0,0,0,0,0,0,0,0,0,0,0,0,~
0,0,0,0,0,0,0,0,0,0,0)';
      INPUT_LOAD='(-0.01,0.01)';
      PINUSE='IN';
    'P2_RXN4':
      PIN_NUMBER='(0,0,0,0,0,0,0,0,0,0,0,0,0,0,0,0,CU33,0,0,0,0,0,0,0,0,0,0,0,0,~
0,0,0,0,0,0,0,0,0,0,0)';
      INPUT_LOAD='(-0.01,0.01)';
      PINUSE='IN';
    'P2_TXN7':
      PIN_NUMBER='(0,0,0,0,0,0,0,0,0,0,0,0,0,0,0,0,BU29,0,0,0,0,0,0,0,0,0,0,0,0,~
0,0,0,0,0,0,0,0,0,0,0)';
      OUTPUT_LOAD='(1.0,-1.0)';
      PINUSE='OUT';
    'P2_RXP7':
      PIN_NUMBER='(0,0,0,0,0,0,0,0,0,0,0,0,0,0,0,0,CU29,0,0,0,0,0,0,0,0,0,0,0,0,~
0,0,0,0,0,0,0,0,0,0,0)';
      INPUT_LOAD='(-0.01,0.01)';
      PINUSE='IN';
    'P2_RXN5':
      PIN_NUMBER='(0,0,0,0,0,0,0,0,0,0,0,0,0,0,0,0,CR33,0,0,0,0,0,0,0,0,0,0,0,0,~
0,0,0,0,0,0,0,0,0,0,0)';
      INPUT_LOAD='(-0.01,0.01)';
      PINUSE='IN';
    'P2_RXN6':
      PIN_NUMBER='(0,0,0,0,0,0,0,0,0,0,0,0,0,0,0,0,CN30,0,0,0,0,0,0,0,0,0,0,0,0,~
0,0,0,0,0,0,0,0,0,0,0)';
      INPUT_LOAD='(-0.01,0.01)';
      PINUSE='IN';
    'P2_RXN7':
      PIN_NUMBER='(0,0,0,0,0,0,0,0,0,0,0,0,0,0,0,0,CU30,0,0,0,0,0,0,0,0,0,0,0,0,~
0,0,0,0,0,0,0,0,0,0,0)';
      INPUT_LOAD='(-0.01,0.01)';
      PINUSE='IN';
    'P3_RXP0':
      PIN_NUMBER='(0,0,0,0,0,0,0,0,0,0,0,0,0,0,0,0,0,CV35,0,0,0,0,0,0,0,0,0,0,0,~
0,0,0,0,0,0,0,0,0,0,0)';
      INPUT_LOAD='(-0.01,0.01)';
      PINUSE='IN';
    'P3_RXN0':
      PIN_NUMBER='(0,0,0,0,0,0,0,0,0,0,0,0,0,0,0,0,0,CV36,0,0,0,0,0,0,0,0,0,0,0,~
0,0,0,0,0,0,0,0,0,0,0)';
      INPUT_LOAD='(-0.01,0.01)';
      PINUSE='IN';
    'P3_RXP1':
      PIN_NUMBER='(0,0,0,0,0,0,0,0,0,0,0,0,0,0,0,0,0,CY35,0,0,0,0,0,0,0,0,0,0,0,~
0,0,0,0,0,0,0,0,0,0,0)';
      INPUT_LOAD='(-0.01,0.01)';
      PINUSE='IN';
    'P3_RXN1':
      PIN_NUMBER='(0,0,0,0,0,0,0,0,0,0,0,0,0,0,0,0,0,CY36,0,0,0,0,0,0,0,0,0,0,0,~
0,0,0,0,0,0,0,0,0,0,0)';
      INPUT_LOAD='(-0.01,0.01)';
      PINUSE='IN';
    'P3_RXP2':
      PIN_NUMBER='(0,0,0,0,0,0,0,0,0,0,0,0,0,0,0,0,0,DB35,0,0,0,0,0,0,0,0,0,0,0,~
0,0,0,0,0,0,0,0,0,0,0)';
      INPUT_LOAD='(-0.01,0.01)';
      PINUSE='IN';
    'P3_RXN2':
      PIN_NUMBER='(0,0,0,0,0,0,0,0,0,0,0,0,0,0,0,0,0,DB36,0,0,0,0,0,0,0,0,0,0,0,~
0,0,0,0,0,0,0,0,0,0,0)';
      INPUT_LOAD='(-0.01,0.01)';
      PINUSE='IN';
    'P3_RXP3':
      PIN_NUMBER='(0,0,0,0,0,0,0,0,0,0,0,0,0,0,0,0,0,CW32,0,0,0,0,0,0,0,0,0,0,0,~
0,0,0,0,0,0,0,0,0,0,0)';
      INPUT_LOAD='(-0.01,0.01)';
      PINUSE='IN';
    'P3_RXN3':
      PIN_NUMBER='(0,0,0,0,0,0,0,0,0,0,0,0,0,0,0,0,0,CW33,0,0,0,0,0,0,0,0,0,0,0,~
0,0,0,0,0,0,0,0,0,0,0)';
      INPUT_LOAD='(-0.01,0.01)';
      PINUSE='IN';
    'P3_RXP4':
      PIN_NUMBER='(0,0,0,0,0,0,0,0,0,0,0,0,0,0,0,0,0,DC32,0,0,0,0,0,0,0,0,0,0,0,~
0,0,0,0,0,0,0,0,0,0,0)';
      INPUT_LOAD='(-0.01,0.01)';
      PINUSE='IN';
    'P3_RXN4':
      PIN_NUMBER='(0,0,0,0,0,0,0,0,0,0,0,0,0,0,0,0,0,DC33,0,0,0,0,0,0,0,0,0,0,0,~
0,0,0,0,0,0,0,0,0,0,0)';
      INPUT_LOAD='(-0.01,0.01)';
      PINUSE='IN';
    'P3_RXP5':
      PIN_NUMBER='(0,0,0,0,0,0,0,0,0,0,0,0,0,0,0,0,0,DA32,0,0,0,0,0,0,0,0,0,0,0,~
0,0,0,0,0,0,0,0,0,0,0)';
      INPUT_LOAD='(-0.01,0.01)';
      PINUSE='IN';
    'P3_RXN5':
      PIN_NUMBER='(0,0,0,0,0,0,0,0,0,0,0,0,0,0,0,0,0,DA33,0,0,0,0,0,0,0,0,0,0,0,~
0,0,0,0,0,0,0,0,0,0,0)';
      INPUT_LOAD='(-0.01,0.01)';
      PINUSE='IN';
    'P3_RXP6':
      PIN_NUMBER='(0,0,0,0,0,0,0,0,0,0,0,0,0,0,0,0,0,CW29,0,0,0,0,0,0,0,0,0,0,0,~
0,0,0,0,0,0,0,0,0,0,0)';
      INPUT_LOAD='(-0.01,0.01)';
      PINUSE='IN';
    'P3_RXN6':
      PIN_NUMBER='(0,0,0,0,0,0,0,0,0,0,0,0,0,0,0,0,0,CW30,0,0,0,0,0,0,0,0,0,0,0,~
0,0,0,0,0,0,0,0,0,0,0)';
      INPUT_LOAD='(-0.01,0.01)';
      PINUSE='IN';
    'P3_RXP7':
      PIN_NUMBER='(0,0,0,0,0,0,0,0,0,0,0,0,0,0,0,0,0,DC29,0,0,0,0,0,0,0,0,0,0,0,~
0,0,0,0,0,0,0,0,0,0,0)';
      INPUT_LOAD='(-0.01,0.01)';
      PINUSE='IN';
    'P3_RXN7':
      PIN_NUMBER='(0,0,0,0,0,0,0,0,0,0,0,0,0,0,0,0,0,DC30,0,0,0,0,0,0,0,0,0,0,0,~
0,0,0,0,0,0,0,0,0,0,0)';
      INPUT_LOAD='(-0.01,0.01)';
      PINUSE='IN';
    'P3_RXP8':
      PIN_NUMBER='(0,0,0,0,0,0,0,0,0,0,0,0,0,0,0,0,0,DA29,0,0,0,0,0,0,0,0,0,0,0,~
0,0,0,0,0,0,0,0,0,0,0)';
      INPUT_LOAD='(-0.01,0.01)';
      PINUSE='IN';
    'P3_RXN8':
      PIN_NUMBER='(0,0,0,0,0,0,0,0,0,0,0,0,0,0,0,0,0,DA30,0,0,0,0,0,0,0,0,0,0,0,~
0,0,0,0,0,0,0,0,0,0,0)';
      INPUT_LOAD='(-0.01,0.01)';
      PINUSE='IN';
    'P3_RXP9':
      PIN_NUMBER='(0,0,0,0,0,0,0,0,0,0,0,0,0,0,0,0,0,CW26,0,0,0,0,0,0,0,0,0,0,0,~
0,0,0,0,0,0,0,0,0,0,0)';
      INPUT_LOAD='(-0.01,0.01)';
      PINUSE='IN';
    'P3_RXN9':
      PIN_NUMBER='(0,0,0,0,0,0,0,0,0,0,0,0,0,0,0,0,0,CW27,0,0,0,0,0,0,0,0,0,0,0,~
0,0,0,0,0,0,0,0,0,0,0)';
      INPUT_LOAD='(-0.01,0.01)';
      PINUSE='IN';
    'P3_RXP10':
      PIN_NUMBER='(0,0,0,0,0,0,0,0,0,0,0,0,0,0,0,0,0,DC26,0,0,0,0,0,0,0,0,0,0,0,~
0,0,0,0,0,0,0,0,0,0,0)';
      INPUT_LOAD='(-0.01,0.01)';
      PINUSE='IN';
    'P3_RXN10':
      PIN_NUMBER='(0,0,0,0,0,0,0,0,0,0,0,0,0,0,0,0,0,DC27,0,0,0,0,0,0,0,0,0,0,0,~
0,0,0,0,0,0,0,0,0,0,0)';
      INPUT_LOAD='(-0.01,0.01)';
      PINUSE='IN';
    'P3_RXP11':
      PIN_NUMBER='(0,0,0,0,0,0,0,0,0,0,0,0,0,0,0,0,0,DA26,0,0,0,0,0,0,0,0,0,0,0,~
0,0,0,0,0,0,0,0,0,0,0)';
      INPUT_LOAD='(-0.01,0.01)';
      PINUSE='IN';
    'P3_RXN11':
      PIN_NUMBER='(0,0,0,0,0,0,0,0,0,0,0,0,0,0,0,0,0,DA27,0,0,0,0,0,0,0,0,0,0,0,~
0,0,0,0,0,0,0,0,0,0,0)';
      INPUT_LOAD='(-0.01,0.01)';
      PINUSE='IN';
    'P3_RXP12':
      PIN_NUMBER='(0,0,0,0,0,0,0,0,0,0,0,0,0,0,0,0,0,CW23,0,0,0,0,0,0,0,0,0,0,0,~
0,0,0,0,0,0,0,0,0,0,0)';
      INPUT_LOAD='(-0.01,0.01)';
      PINUSE='IN';
    'P3_RXN12':
      PIN_NUMBER='(0,0,0,0,0,0,0,0,0,0,0,0,0,0,0,0,0,CW24,0,0,0,0,0,0,0,0,0,0,0,~
0,0,0,0,0,0,0,0,0,0,0)';
      INPUT_LOAD='(-0.01,0.01)';
      PINUSE='IN';
    'P3_RXP13':
      PIN_NUMBER='(0,0,0,0,0,0,0,0,0,0,0,0,0,0,0,0,0,DC23,0,0,0,0,0,0,0,0,0,0,0,~
0,0,0,0,0,0,0,0,0,0,0)';
      INPUT_LOAD='(-0.01,0.01)';
      PINUSE='IN';
    'P3_RXN13':
      PIN_NUMBER='(0,0,0,0,0,0,0,0,0,0,0,0,0,0,0,0,0,DC24,0,0,0,0,0,0,0,0,0,0,0,~
0,0,0,0,0,0,0,0,0,0,0)';
      INPUT_LOAD='(-0.01,0.01)';
      PINUSE='IN';
    'P3_RXP14':
      PIN_NUMBER='(0,0,0,0,0,0,0,0,0,0,0,0,0,0,0,0,0,DA23,0,0,0,0,0,0,0,0,0,0,0,~
0,0,0,0,0,0,0,0,0,0,0)';
      INPUT_LOAD='(-0.01,0.01)';
      PINUSE='IN';
    'P3_RXN14':
      PIN_NUMBER='(0,0,0,0,0,0,0,0,0,0,0,0,0,0,0,0,0,DA24,0,0,0,0,0,0,0,0,0,0,0,~
0,0,0,0,0,0,0,0,0,0,0)';
      INPUT_LOAD='(-0.01,0.01)';
      PINUSE='IN';
    'P3_RXP15':
      PIN_NUMBER='(0,0,0,0,0,0,0,0,0,0,0,0,0,0,0,0,0,CU23,0,0,0,0,0,0,0,0,0,0,0,~
0,0,0,0,0,0,0,0,0,0,0)';
      INPUT_LOAD='(-0.01,0.01)';
      PINUSE='IN';
    'P3_RXN15':
      PIN_NUMBER='(0,0,0,0,0,0,0,0,0,0,0,0,0,0,0,0,0,CU24,0,0,0,0,0,0,0,0,0,0,0,~
0,0,0,0,0,0,0,0,0,0,0)';
      INPUT_LOAD='(-0.01,0.01)';
      PINUSE='IN';
    'P3_TXP0':
      PIN_NUMBER='(0,0,0,0,0,0,0,0,0,0,0,0,0,0,0,0,0,CD36,0,0,0,0,0,0,0,0,0,0,0,~
0,0,0,0,0,0,0,0,0,0,0)';
      OUTPUT_LOAD='(1.0,-1.0)';
      PINUSE='OUT';
    'P3_TXN0':
      PIN_NUMBER='(0,0,0,0,0,0,0,0,0,0,0,0,0,0,0,0,0,CD35,0,0,0,0,0,0,0,0,0,0,0,~
0,0,0,0,0,0,0,0,0,0,0)';
      OUTPUT_LOAD='(1.0,-1.0)';
      PINUSE='OUT';
    'P3_TXP1':
      PIN_NUMBER='(0,0,0,0,0,0,0,0,0,0,0,0,0,0,0,0,0,CF36,0,0,0,0,0,0,0,0,0,0,0,~
0,0,0,0,0,0,0,0,0,0,0)';
      OUTPUT_LOAD='(1.0,-1.0)';
      PINUSE='OUT';
    'P3_TXN1':
      PIN_NUMBER='(0,0,0,0,0,0,0,0,0,0,0,0,0,0,0,0,0,CF35,0,0,0,0,0,0,0,0,0,0,0,~
0,0,0,0,0,0,0,0,0,0,0)';
      OUTPUT_LOAD='(1.0,-1.0)';
      PINUSE='OUT';
    'P3_TXP2':
      PIN_NUMBER='(0,0,0,0,0,0,0,0,0,0,0,0,0,0,0,0,0,CH36,0,0,0,0,0,0,0,0,0,0,0,~
0,0,0,0,0,0,0,0,0,0,0)';
      OUTPUT_LOAD='(1.0,-1.0)';
      PINUSE='OUT';
    'P3_TXN2':
      PIN_NUMBER='(0,0,0,0,0,0,0,0,0,0,0,0,0,0,0,0,0,CH35,0,0,0,0,0,0,0,0,0,0,0,~
0,0,0,0,0,0,0,0,0,0,0)';
      OUTPUT_LOAD='(1.0,-1.0)';
      PINUSE='OUT';
    'P3_TXP3':
      PIN_NUMBER='(0,0,0,0,0,0,0,0,0,0,0,0,0,0,0,0,0,CC33,0,0,0,0,0,0,0,0,0,0,0,~
0,0,0,0,0,0,0,0,0,0,0)';
      OUTPUT_LOAD='(1.0,-1.0)';
      PINUSE='OUT';
    'P3_TXN3':
      PIN_NUMBER='(0,0,0,0,0,0,0,0,0,0,0,0,0,0,0,0,0,CC32,0,0,0,0,0,0,0,0,0,0,0,~
0,0,0,0,0,0,0,0,0,0,0)';
      OUTPUT_LOAD='(1.0,-1.0)';
      PINUSE='OUT';
    'P3_TXP4':
      PIN_NUMBER='(0,0,0,0,0,0,0,0,0,0,0,0,0,0,0,0,0,CJ33,0,0,0,0,0,0,0,0,0,0,0,~
0,0,0,0,0,0,0,0,0,0,0)';
      OUTPUT_LOAD='(1.0,-1.0)';
      PINUSE='OUT';
    'P3_TXN4':
      PIN_NUMBER='(0,0,0,0,0,0,0,0,0,0,0,0,0,0,0,0,0,CJ32,0,0,0,0,0,0,0,0,0,0,0,~
0,0,0,0,0,0,0,0,0,0,0)';
      OUTPUT_LOAD='(1.0,-1.0)';
      PINUSE='OUT';
    'P3_TXP5':
      PIN_NUMBER='(0,0,0,0,0,0,0,0,0,0,0,0,0,0,0,0,0,CG33,0,0,0,0,0,0,0,0,0,0,0,~
0,0,0,0,0,0,0,0,0,0,0)';
      OUTPUT_LOAD='(1.0,-1.0)';
      PINUSE='OUT';
    'P3_TXN5':
      PIN_NUMBER='(0,0,0,0,0,0,0,0,0,0,0,0,0,0,0,0,0,CG32,0,0,0,0,0,0,0,0,0,0,0,~
0,0,0,0,0,0,0,0,0,0,0)';
      OUTPUT_LOAD='(1.0,-1.0)';
      PINUSE='OUT';
    'P3_TXP6':
      PIN_NUMBER='(0,0,0,0,0,0,0,0,0,0,0,0,0,0,0,0,0,CE33,0,0,0,0,0,0,0,0,0,0,0,~
0,0,0,0,0,0,0,0,0,0,0)';
      OUTPUT_LOAD='(1.0,-1.0)';
      PINUSE='OUT';
    'P3_TXN6':
      PIN_NUMBER='(0,0,0,0,0,0,0,0,0,0,0,0,0,0,0,0,0,CE32,0,0,0,0,0,0,0,0,0,0,0,~
0,0,0,0,0,0,0,0,0,0,0)';
      OUTPUT_LOAD='(1.0,-1.0)';
      PINUSE='OUT';
    'P3_TXP7':
      PIN_NUMBER='(0,0,0,0,0,0,0,0,0,0,0,0,0,0,0,0,0,CC30,0,0,0,0,0,0,0,0,0,0,0,~
0,0,0,0,0,0,0,0,0,0,0)';
      OUTPUT_LOAD='(1.0,-1.0)';
      PINUSE='OUT';
    'P3_TXN7':
      PIN_NUMBER='(0,0,0,0,0,0,0,0,0,0,0,0,0,0,0,0,0,CC29,0,0,0,0,0,0,0,0,0,0,0,~
0,0,0,0,0,0,0,0,0,0,0)';
      OUTPUT_LOAD='(1.0,-1.0)';
      PINUSE='OUT';
    'P3_TXP8':
      PIN_NUMBER='(0,0,0,0,0,0,0,0,0,0,0,0,0,0,0,0,0,CG30,0,0,0,0,0,0,0,0,0,0,0,~
0,0,0,0,0,0,0,0,0,0,0)';
      OUTPUT_LOAD='(1.0,-1.0)';
      PINUSE='OUT';
    'P3_TXN8':
      PIN_NUMBER='(0,0,0,0,0,0,0,0,0,0,0,0,0,0,0,0,0,CG29,0,0,0,0,0,0,0,0,0,0,0,~
0,0,0,0,0,0,0,0,0,0,0)';
      OUTPUT_LOAD='(1.0,-1.0)';
      PINUSE='OUT';
    'P3_TXP9':
      PIN_NUMBER='(0,0,0,0,0,0,0,0,0,0,0,0,0,0,0,0,0,CE30,0,0,0,0,0,0,0,0,0,0,0,~
0,0,0,0,0,0,0,0,0,0,0)';
      OUTPUT_LOAD='(1.0,-1.0)';
      PINUSE='OUT';
    'P3_TXN9':
      PIN_NUMBER='(0,0,0,0,0,0,0,0,0,0,0,0,0,0,0,0,0,CE29,0,0,0,0,0,0,0,0,0,0,0,~
0,0,0,0,0,0,0,0,0,0,0)';
      OUTPUT_LOAD='(1.0,-1.0)';
      PINUSE='OUT';
    'P3_TXP10':
      PIN_NUMBER='(0,0,0,0,0,0,0,0,0,0,0,0,0,0,0,0,0,CC27,0,0,0,0,0,0,0,0,0,0,0,~
0,0,0,0,0,0,0,0,0,0,0)';
      OUTPUT_LOAD='(1.0,-1.0)';
      PINUSE='OUT';
    'P3_TXN10':
      PIN_NUMBER='(0,0,0,0,0,0,0,0,0,0,0,0,0,0,0,0,0,CC26,0,0,0,0,0,0,0,0,0,0,0,~
0,0,0,0,0,0,0,0,0,0,0)';
      OUTPUT_LOAD='(1.0,-1.0)';
      PINUSE='OUT';
    'P3_TXP11':
      PIN_NUMBER='(0,0,0,0,0,0,0,0,0,0,0,0,0,0,0,0,0,CG27,0,0,0,0,0,0,0,0,0,0,0,~
0,0,0,0,0,0,0,0,0,0,0)';
      OUTPUT_LOAD='(1.0,-1.0)';
      PINUSE='OUT';
    'P3_TXN11':
      PIN_NUMBER='(0,0,0,0,0,0,0,0,0,0,0,0,0,0,0,0,0,CG26,0,0,0,0,0,0,0,0,0,0,0,~
0,0,0,0,0,0,0,0,0,0,0)';
      OUTPUT_LOAD='(1.0,-1.0)';
      PINUSE='OUT';
    'P3_TXP12':
      PIN_NUMBER='(0,0,0,0,0,0,0,0,0,0,0,0,0,0,0,0,0,CE27,0,0,0,0,0,0,0,0,0,0,0,~
0,0,0,0,0,0,0,0,0,0,0)';
      OUTPUT_LOAD='(1.0,-1.0)';
      PINUSE='OUT';
    'P3_TXN12':
      PIN_NUMBER='(0,0,0,0,0,0,0,0,0,0,0,0,0,0,0,0,0,CE26,0,0,0,0,0,0,0,0,0,0,0,~
0,0,0,0,0,0,0,0,0,0,0)';
      OUTPUT_LOAD='(1.0,-1.0)';
      PINUSE='OUT';
    'P3_TXP13':
      PIN_NUMBER='(0,0,0,0,0,0,0,0,0,0,0,0,0,0,0,0,0,CC24,0,0,0,0,0,0,0,0,0,0,0,~
0,0,0,0,0,0,0,0,0,0,0)';
      OUTPUT_LOAD='(1.0,-1.0)';
      PINUSE='OUT';
    'P3_TXN13':
      PIN_NUMBER='(0,0,0,0,0,0,0,0,0,0,0,0,0,0,0,0,0,CC23,0,0,0,0,0,0,0,0,0,0,0,~
0,0,0,0,0,0,0,0,0,0,0)';
      OUTPUT_LOAD='(1.0,-1.0)';
      PINUSE='OUT';
    'P3_TXP14':
      PIN_NUMBER='(0,0,0,0,0,0,0,0,0,0,0,0,0,0,0,0,0,CG24,0,0,0,0,0,0,0,0,0,0,0,~
0,0,0,0,0,0,0,0,0,0,0)';
      OUTPUT_LOAD='(1.0,-1.0)';
      PINUSE='OUT';
    'P3_TXN14':
      PIN_NUMBER='(0,0,0,0,0,0,0,0,0,0,0,0,0,0,0,0,0,CG23,0,0,0,0,0,0,0,0,0,0,0,~
0,0,0,0,0,0,0,0,0,0,0)';
      OUTPUT_LOAD='(1.0,-1.0)';
      PINUSE='OUT';
    'P3_TXP15':
      PIN_NUMBER='(0,0,0,0,0,0,0,0,0,0,0,0,0,0,0,0,0,CE24,0,0,0,0,0,0,0,0,0,0,0,~
0,0,0,0,0,0,0,0,0,0,0)';
      OUTPUT_LOAD='(1.0,-1.0)';
      PINUSE='OUT';
    'P3_TXN15':
      PIN_NUMBER='(0,0,0,0,0,0,0,0,0,0,0,0,0,0,0,0,0,CE23,0,0,0,0,0,0,0,0,0,0,0,~
0,0,0,0,0,0,0,0,0,0,0)';
      OUTPUT_LOAD='(1.0,-1.0)';
      PINUSE='OUT';
    'P4_RXN2':
      PIN_NUMBER='(0,0,0,0,0,0,0,0,0,0,0,0,0,0,0,0,0,0,DG47,0,0,0,0,0,0,0,0,0,0,~
0,0,0,0,0,0,0,0,0,0,0)';
      INPUT_LOAD='(-0.01,0.01)';
      PINUSE='IN';
    'P4_RXN3':
      PIN_NUMBER='(0,0,0,0,0,0,0,0,0,0,0,0,0,0,0,0,0,0,DG44,0,0,0,0,0,0,0,0,0,0,~
0,0,0,0,0,0,0,0,0,0,0)';
      INPUT_LOAD='(-0.01,0.01)';
      PINUSE='IN';
    'P4_RXP2':
      PIN_NUMBER='(0,0,0,0,0,0,0,0,0,0,0,0,0,0,0,0,0,0,DG48,0,0,0,0,0,0,0,0,0,0,~
0,0,0,0,0,0,0,0,0,0,0)';
      INPUT_LOAD='(-0.01,0.01)';
      PINUSE='IN';
    'P4_RXP3':
      PIN_NUMBER='(0,0,0,0,0,0,0,0,0,0,0,0,0,0,0,0,0,0,DG45,0,0,0,0,0,0,0,0,0,0,~
0,0,0,0,0,0,0,0,0,0,0)';
      INPUT_LOAD='(-0.01,0.01)';
      PINUSE='IN';
    'P4_TXN2':
      PIN_NUMBER='(0,0,0,0,0,0,0,0,0,0,0,0,0,0,0,0,0,0,DE46,0,0,0,0,0,0,0,0,0,0,~
0,0,0,0,0,0,0,0,0,0,0)';
      OUTPUT_LOAD='(1.0,-1.0)';
      PINUSE='OUT';
    'P4_TXN3':
      PIN_NUMBER='(0,0,0,0,0,0,0,0,0,0,0,0,0,0,0,0,0,0,DE43,0,0,0,0,0,0,0,0,0,0,~
0,0,0,0,0,0,0,0,0,0,0)';
      OUTPUT_LOAD='(1.0,-1.0)';
      PINUSE='OUT';
    'P4_TXP2':
      PIN_NUMBER='(0,0,0,0,0,0,0,0,0,0,0,0,0,0,0,0,0,0,DE47,0,0,0,0,0,0,0,0,0,0,~
0,0,0,0,0,0,0,0,0,0,0)';
      OUTPUT_LOAD='(1.0,-1.0)';
      PINUSE='OUT';
    'P4_TXP3':
      PIN_NUMBER='(0,0,0,0,0,0,0,0,0,0,0,0,0,0,0,0,0,0,DE44,0,0,0,0,0,0,0,0,0,0,~
0,0,0,0,0,0,0,0,0,0,0)';
      OUTPUT_LOAD='(1.0,-1.0)';
      PINUSE='OUT';
    'P5_RXN2':
      PIN_NUMBER='(0,0,0,0,0,0,0,0,0,0,0,0,0,0,0,0,0,0,E44,0,0,0,0,0,0,0,0,0,0,0~
,0,0,0,0,0,0,0,0,0,0)';
      INPUT_LOAD='(-0.01,0.01)';
      PINUSE='IN';
    'P5_RXN3':
      PIN_NUMBER='(0,0,0,0,0,0,0,0,0,0,0,0,0,0,0,0,0,0,E41,0,0,0,0,0,0,0,0,0,0,0~
,0,0,0,0,0,0,0,0,0,0)';
      INPUT_LOAD='(-0.01,0.01)';
      PINUSE='IN';
    'P5_RXP2':
      PIN_NUMBER='(0,0,0,0,0,0,0,0,0,0,0,0,0,0,0,0,0,0,E43,0,0,0,0,0,0,0,0,0,0,0~
,0,0,0,0,0,0,0,0,0,0)';
      INPUT_LOAD='(-0.01,0.01)';
      PINUSE='IN';
    'P5_RXP3':
      PIN_NUMBER='(0,0,0,0,0,0,0,0,0,0,0,0,0,0,0,0,0,0,E40,0,0,0,0,0,0,0,0,0,0,0~
,0,0,0,0,0,0,0,0,0,0)';
      INPUT_LOAD='(-0.01,0.01)';
      PINUSE='IN';
    'P5_TXN2':
      PIN_NUMBER='(0,0,0,0,0,0,0,0,0,0,0,0,0,0,0,0,0,0,C45,0,0,0,0,0,0,0,0,0,0,0~
,0,0,0,0,0,0,0,0,0,0)';
      OUTPUT_LOAD='(1.0,-1.0)';
      PINUSE='OUT';
    'P5_TXN3':
      PIN_NUMBER='(0,0,0,0,0,0,0,0,0,0,0,0,0,0,0,0,0,0,C42,0,0,0,0,0,0,0,0,0,0,0~
,0,0,0,0,0,0,0,0,0,0)';
      OUTPUT_LOAD='(1.0,-1.0)';
      PINUSE='OUT';
    'P5_TXP2':
      PIN_NUMBER='(0,0,0,0,0,0,0,0,0,0,0,0,0,0,0,0,0,0,C44,0,0,0,0,0,0,0,0,0,0,0~
,0,0,0,0,0,0,0,0,0,0)';
      OUTPUT_LOAD='(1.0,-1.0)';
      PINUSE='OUT';
    'P5_TXP3':
      PIN_NUMBER='(0,0,0,0,0,0,0,0,0,0,0,0,0,0,0,0,0,0,C41,0,0,0,0,0,0,0,0,0,0,0~
,0,0,0,0,0,0,0,0,0,0)';
      OUTPUT_LOAD='(1.0,-1.0)';
      PINUSE='OUT';
    'P4_TXP0':
      PIN_NUMBER='(0,0,0,0,0,0,0,0,0,0,0,0,0,0,0,0,0,0,DE53,0,0,0,0,0,0,0,0,0,0,~
0,0,0,0,0,0,0,0,0,0,0)';
      OUTPUT_LOAD='(1.0,-1.0)';
      PINUSE='OUT';
    'P4_TXP1':
      PIN_NUMBER='(0,0,0,0,0,0,0,0,0,0,0,0,0,0,0,0,0,0,DE50,0,0,0,0,0,0,0,0,0,0,~
0,0,0,0,0,0,0,0,0,0,0)';
      OUTPUT_LOAD='(1.0,-1.0)';
      PINUSE='OUT';
    'P4_TXN0':
      PIN_NUMBER='(0,0,0,0,0,0,0,0,0,0,0,0,0,0,0,0,0,0,DE52,0,0,0,0,0,0,0,0,0,0,~
0,0,0,0,0,0,0,0,0,0,0)';
      OUTPUT_LOAD='(1.0,-1.0)';
      PINUSE='OUT';
    'P4_RXP0':
      PIN_NUMBER='(0,0,0,0,0,0,0,0,0,0,0,0,0,0,0,0,0,0,DG54,0,0,0,0,0,0,0,0,0,0,~
0,0,0,0,0,0,0,0,0,0,0)';
      INPUT_LOAD='(-0.01,0.01)';
      PINUSE='IN';
    'P4_TXN1':
      PIN_NUMBER='(0,0,0,0,0,0,0,0,0,0,0,0,0,0,0,0,0,0,DE49,0,0,0,0,0,0,0,0,0,0,~
0,0,0,0,0,0,0,0,0,0,0)';
      OUTPUT_LOAD='(1.0,-1.0)';
      PINUSE='OUT';
    'P4_RXP1':
      PIN_NUMBER='(0,0,0,0,0,0,0,0,0,0,0,0,0,0,0,0,0,0,DG51,0,0,0,0,0,0,0,0,0,0,~
0,0,0,0,0,0,0,0,0,0,0)';
      INPUT_LOAD='(-0.01,0.01)';
      PINUSE='IN';
    'P4_RXN0':
      PIN_NUMBER='(0,0,0,0,0,0,0,0,0,0,0,0,0,0,0,0,0,0,DG53,0,0,0,0,0,0,0,0,0,0,~
0,0,0,0,0,0,0,0,0,0,0)';
      INPUT_LOAD='(-0.01,0.01)';
      PINUSE='IN';
    'P4_RXN1':
      PIN_NUMBER='(0,0,0,0,0,0,0,0,0,0,0,0,0,0,0,0,0,0,DG50,0,0,0,0,0,0,0,0,0,0,~
0,0,0,0,0,0,0,0,0,0,0)';
      INPUT_LOAD='(-0.01,0.01)';
      PINUSE='IN';
    'WAFL_RXN0||P5_RXN0':
      PIN_NUMBER='(0,0,0,0,0,0,0,0,0,0,0,0,0,0,0,0,0,0,E50,0,0,0,0,0,0,0,0,0,0,0~
,0,0,0,0,0,0,0,0,0,0)';
      INPUT_LOAD='(-0.01,0.01)';
      PINUSE='IN';
    'WAFL_RXP0||P5_RXP0':
      PIN_NUMBER='(0,0,0,0,0,0,0,0,0,0,0,0,0,0,0,0,0,0,E49,0,0,0,0,0,0,0,0,0,0,0~
,0,0,0,0,0,0,0,0,0,0)';
      INPUT_LOAD='(-0.01,0.01)';
      PINUSE='IN';
    'WAFL_RXN1||P5_RXN1':
      PIN_NUMBER='(0,0,0,0,0,0,0,0,0,0,0,0,0,0,0,0,0,0,E47,0,0,0,0,0,0,0,0,0,0,0~
,0,0,0,0,0,0,0,0,0,0)';
      INPUT_LOAD='(-0.01,0.01)';
      PINUSE='IN';
    'WAFL_RXP1||P5_RXP1':
      PIN_NUMBER='(0,0,0,0,0,0,0,0,0,0,0,0,0,0,0,0,0,0,E46,0,0,0,0,0,0,0,0,0,0,0~
,0,0,0,0,0,0,0,0,0,0)';
      INPUT_LOAD='(-0.01,0.01)';
      PINUSE='IN';
    'WAFL_TXN0||P5_TXN0':
      PIN_NUMBER='(0,0,0,0,0,0,0,0,0,0,0,0,0,0,0,0,0,0,C51,0,0,0,0,0,0,0,0,0,0,0~
,0,0,0,0,0,0,0,0,0,0)';
      OUTPUT_LOAD='(1.0,-1.0)';
      PINUSE='OUT';
    'WAFL_TXP0||P5_TXP0':
      PIN_NUMBER='(0,0,0,0,0,0,0,0,0,0,0,0,0,0,0,0,0,0,C50,0,0,0,0,0,0,0,0,0,0,0~
,0,0,0,0,0,0,0,0,0,0)';
      OUTPUT_LOAD='(1.0,-1.0)';
      PINUSE='OUT';
    'WAFL_TXN1||P5_TXN1':
      PIN_NUMBER='(0,0,0,0,0,0,0,0,0,0,0,0,0,0,0,0,0,0,C48,0,0,0,0,0,0,0,0,0,0,0~
,0,0,0,0,0,0,0,0,0,0)';
      OUTPUT_LOAD='(1.0,-1.0)';
      PINUSE='OUT';
    'WAFL_TXP1||P5_TXP1':
      PIN_NUMBER='(0,0,0,0,0,0,0,0,0,0,0,0,0,0,0,0,0,0,C47,0,0,0,0,0,0,0,0,0,0,0~
,0,0,0,0,0,0,0,0,0,0)';
      OUTPUT_LOAD='(1.0,-1.0)';
      PINUSE='OUT';
    'ALERT_L':
      PIN_NUMBER='(0,0,0,0,0,0,0,0,0,0,0,0,0,0,0,0,0,0,0,A68,0,0,0,0,0,0,0,0,0,0~
,0,0,0,0,0,0,0,0,0,0)';
      OUTPUT_LOAD='(1.0,-1.0)';
      PINUSE='OUT';
    'CPU_PRESENT_L':
      PIN_NUMBER='(0,0,0,0,0,0,0,0,0,0,0,0,0,0,0,0,0,0,0,B66,0,0,0,0,0,0,0,0,0,0~
,0,0,0,0,0,0,0,0,0,0)';
      OUTPUT_LOAD='(1.0,-1.0)';
      PINUSE='OUT';
    'DBREQ_L':
      PIN_NUMBER='(0,0,0,0,0,0,0,0,0,0,0,0,0,0,0,0,0,0,0,C16,0,0,0,0,0,0,0,0,0,0~
,0,0,0,0,0,0,0,0,0,0)';
      INPUT_LOAD='(-0.01,0.01)';
      PINUSE='IN';
    'PROCHOT_L':
      PIN_NUMBER='(0,0,0,0,0,0,0,0,0,0,0,0,0,0,0,0,0,0,0,A69,0,0,0,0,0,0,0,0,0,0~
,0,0,0,0,0,0,0,0,0,0)';
      INPUT_LOAD='(-0.01,0.01)';
      PINUSE='IN';
    'SA0':
      PIN_NUMBER='(0,0,0,0,0,0,0,0,0,0,0,0,0,0,0,0,0,0,0,DJ55,0,0,0,0,0,0,0,0,0,~
0,0,0,0,0,0,0,0,0,0,0)';
      INPUT_LOAD='(-0.01,0.01)';
      PINUSE='IN';
    'SIC':
      PIN_NUMBER='(0,0,0,0,0,0,0,0,0,0,0,0,0,0,0,0,0,0,0,DJ71,0,0,0,0,0,0,0,0,0,~
0,0,0,0,0,0,0,0,0,0,0)';
      OUTPUT_LOAD='(1.0,-1.0)';
      PINUSE='OUT';
    'SID':
      PIN_NUMBER='(0,0,0,0,0,0,0,0,0,0,0,0,0,0,0,0,0,0,0,DH71,0,0,0,0,0,0,0,0,0,~
0,0,0,0,0,0,0,0,0,0,0)';
      BIDIRECTIONAL='TRUE';
      INPUT_LOAD='(-0.01,0.01)';
      OUTPUT_LOAD='(1.0,-1.0)';
      PINUSE='BI';
    'TDI':
      PIN_NUMBER='(0,0,0,0,0,0,0,0,0,0,0,0,0,0,0,0,0,0,0,C17,0,0,0,0,0,0,0,0,0,0~
,0,0,0,0,0,0,0,0,0,0)';
      INPUT_LOAD='(-0.01,0.01)';
      PINUSE='IN';
    'TDO':
      PIN_NUMBER='(0,0,0,0,0,0,0,0,0,0,0,0,0,0,0,0,0,0,0,C18,0,0,0,0,0,0,0,0,0,0~
,0,0,0,0,0,0,0,0,0,0)';
      OUTPUT_LOAD='(1.0,-1.0)';
      PINUSE='OUT';
    'THERMTRIP_L':
      PIN_NUMBER='(0,0,0,0,0,0,0,0,0,0,0,0,0,0,0,0,0,0,0,DJ9,0,0,0,0,0,0,0,0,0,0~
,0,0,0,0,0,0,0,0,0,0)';
      OUTPUT_LOAD='(1.0,-1.0)';
      PINUSE='OUT';
    'TMS':
      PIN_NUMBER='(0,0,0,0,0,0,0,0,0,0,0,0,0,0,0,0,0,0,0,A16,0,0,0,0,0,0,0,0,0,0~
,0,0,0,0,0,0,0,0,0,0)';
      INPUT_LOAD='(-0.01,0.01)';
      PINUSE='IN';
    'TRST_L':
      PIN_NUMBER='(0,0,0,0,0,0,0,0,0,0,0,0,0,0,0,0,0,0,0,A17,0,0,0,0,0,0,0,0,0,0~
,0,0,0,0,0,0,0,0,0,0)';
      INPUT_LOAD='(-0.01,0.01)';
      PINUSE='IN';
    'XTRIG_L4':
      PIN_NUMBER='(0,0,0,0,0,0,0,0,0,0,0,0,0,0,0,0,0,0,0,C66,0,0,0,0,0,0,0,0,0,0~
,0,0,0,0,0,0,0,0,0,0)';
      OUTPUT_LOAD='(1.0,-1.0)';
      PINUSE='OUT';
    'XTRIG_L5':
      PIN_NUMBER='(0,0,0,0,0,0,0,0,0,0,0,0,0,0,0,0,0,0,0,C65,0,0,0,0,0,0,0,0,0,0~
,0,0,0,0,0,0,0,0,0,0)';
      OUTPUT_LOAD='(1.0,-1.0)';
      PINUSE='OUT';
    'XTRIG_L6':
      PIN_NUMBER='(0,0,0,0,0,0,0,0,0,0,0,0,0,0,0,0,0,0,0,A66,0,0,0,0,0,0,0,0,0,0~
,0,0,0,0,0,0,0,0,0,0)';
      OUTPUT_LOAD='(1.0,-1.0)';
      PINUSE='OUT';
    'XTRIG_L7':
      PIN_NUMBER='(0,0,0,0,0,0,0,0,0,0,0,0,0,0,0,0,0,0,0,A65,0,0,0,0,0,0,0,0,0,0~
,0,0,0,0,0,0,0,0,0,0)';
      OUTPUT_LOAD='(1.0,-1.0)';
      PINUSE='OUT';
    'SA1':
      PIN_NUMBER='(0,0,0,0,0,0,0,0,0,0,0,0,0,0,0,0,0,0,0,DJ56,0,0,0,0,0,0,0,0,0,~
0,0,0,0,0,0,0,0,0,0,0)';
      INPUT_LOAD='(-0.01,0.01)';
      PINUSE='IN';
    'CORETYPE0':
      PIN_NUMBER='(0,0,0,0,0,0,0,0,0,0,0,0,0,0,0,0,0,0,0,C70,0,0,0,0,0,0,0,0,0,0~
,0,0,0,0,0,0,0,0,0,0)';
      OUTPUT_LOAD='(1.0,-1.0)';
      PINUSE='OUT';
    'CORETYPE1':
      PIN_NUMBER='(0,0,0,0,0,0,0,0,0,0,0,0,0,0,0,0,0,0,0,B69,0,0,0,0,0,0,0,0,0,0~
,0,0,0,0,0,0,0,0,0,0)';
      OUTPUT_LOAD='(1.0,-1.0)';
      PINUSE='OUT';
    'SP5R2':
      PIN_NUMBER='(0,0,0,0,0,0,0,0,0,0,0,0,0,0,0,0,0,0,0,C68,0,0,0,0,0,0,0,0,0,0~
,0,0,0,0,0,0,0,0,0,0)';
      OUTPUT_LOAD='(1.0,-1.0)';
      PINUSE='OUT';
    'SP5R3':
      PIN_NUMBER='(0,0,0,0,0,0,0,0,0,0,0,0,0,0,0,0,0,0,0,DH73,0,0,0,0,0,0,0,0,0,~
0,0,0,0,0,0,0,0,0,0,0)';
      OUTPUT_LOAD='(1.0,-1.0)';
      PINUSE='OUT';
    'SP5R4':
      PIN_NUMBER='(0,0,0,0,0,0,0,0,0,0,0,0,0,0,0,0,0,0,0,DH10,0,0,0,0,0,0,0,0,0,~
0,0,0,0,0,0,0,0,0,0,0)';
      OUTPUT_LOAD='(1.0,-1.0)';
      PINUSE='OUT';
    'PCC0_L':
      PIN_NUMBER='(0,0,0,0,0,0,0,0,0,0,0,0,0,0,0,0,0,0,0,C22,0,0,0,0,0,0,0,0,0,0~
,0,0,0,0,0,0,0,0,0,0)';
      INPUT_LOAD='(-0.01,0.01)';
      PINUSE='IN';
    'PCC1_L':
      PIN_NUMBER='(0,0,0,0,0,0,0,0,0,0,0,0,0,0,0,0,0,0,0,DG72,0,0,0,0,0,0,0,0,0,~
0,0,0,0,0,0,0,0,0,0,0)';
      INPUT_LOAD='(-0.01,0.01)';
      PINUSE='IN';
    'AZ_BITCLK':
      PIN_NUMBER='(0,0,0,0,0,0,0,0,0,0,0,0,0,0,0,0,0,0,0,C32,0,0,0,0,0,0,0,0,0,0~
,0,0,0,0,0,0,0,0,0,0)';
      OUTPUT_LOAD='(1.0,-1.0)';
      PINUSE='OUT';
    'AZ_SYNC':
      PIN_NUMBER='(0,0,0,0,0,0,0,0,0,0,0,0,0,0,0,0,0,0,0,D32,0,0,0,0,0,0,0,0,0,0~
,0,0,0,0,0,0,0,0,0,0)';
      OUTPUT_LOAD='(1.0,-1.0)';
      PINUSE='OUT';
    'SVD0':
      PIN_NUMBER='(0,0,0,0,0,0,0,0,0,0,0,0,0,0,0,0,0,0,0,A22,0,0,0,0,0,0,0,0,0,0~
,0,0,0,0,0,0,0,0,0,0)';
      BIDIRECTIONAL='TRUE';
      INPUT_LOAD='(-0.01,0.01)';
      OUTPUT_LOAD='(1.0,-1.0)';
      PINUSE='BI';
    'SVT0':
      PIN_NUMBER='(0,0,0,0,0,0,0,0,0,0,0,0,0,0,0,0,0,0,0,B21,0,0,0,0,0,0,0,0,0,0~
,0,0,0,0,0,0,0,0,0,0)';
      INPUT_LOAD='(-0.01,0.01)';
      PINUSE='IN';
    'SVD1':
      PIN_NUMBER='(0,0,0,0,0,0,0,0,0,0,0,0,0,0,0,0,0,0,0,DH72,0,0,0,0,0,0,0,0,0,~
0,0,0,0,0,0,0,0,0,0,0)';
      BIDIRECTIONAL='TRUE';
      INPUT_LOAD='(-0.01,0.01)';
      OUTPUT_LOAD='(1.0,-1.0)';
      PINUSE='BI';
    'SVC0':
      PIN_NUMBER='(0,0,0,0,0,0,0,0,0,0,0,0,0,0,0,0,0,0,0,A23,0,0,0,0,0,0,0,0,0,0~
,0,0,0,0,0,0,0,0,0,0)';
      OUTPUT_LOAD='(1.0,-1.0)';
      PINUSE='OUT';
    'SVT1':
      PIN_NUMBER='(0,0,0,0,0,0,0,0,0,0,0,0,0,0,0,0,0,0,0,DG73,0,0,0,0,0,0,0,0,0,~
0,0,0,0,0,0,0,0,0,0,0)';
      INPUT_LOAD='(-0.01,0.01)';
      PINUSE='IN';
    'SVC1':
      PIN_NUMBER='(0,0,0,0,0,0,0,0,0,0,0,0,0,0,0,0,0,0,0,DJ72,0,0,0,0,0,0,0,0,0,~
0,0,0,0,0,0,0,0,0,0,0)';
      OUTPUT_LOAD='(1.0,-1.0)';
      PINUSE='OUT';
    'UART0_RXD||AGPIO136':
      PIN_NUMBER='(0,0,0,0,0,0,0,0,0,0,0,0,0,0,0,0,0,0,0,DG35,0,0,0,0,0,0,0,0,0,~
0,0,0,0,0,0,0,0,0,0,0)';
      BIDIRECTIONAL='TRUE';
      INPUT_LOAD='(-0.01,0.01)';
      OUTPUT_LOAD='(1.0,-1.0)';
      PINUSE='BI';
    'UART0_RTS_L||UART2_RXD||AGPIO137':
      PIN_NUMBER='(0,0,0,0,0,0,0,0,0,0,0,0,0,0,0,0,0,0,0,DF34,0,0,0,0,0,0,0,0,0,~
0,0,0,0,0,0,0,0,0,0,0)';
      BIDIRECTIONAL='TRUE';
      INPUT_LOAD='(-0.01,0.01)';
      OUTPUT_LOAD='(1.0,-1.0)';
      PINUSE='BI';
    'UART0_INTR||AGPIO139':
      PIN_NUMBER='(0,0,0,0,0,0,0,0,0,0,0,0,0,0,0,0,0,0,0,DG34,0,0,0,0,0,0,0,0,0,~
0,0,0,0,0,0,0,0,0,0,0)';
      BIDIRECTIONAL='TRUE';
      INPUT_LOAD='(-0.01,0.01)';
      OUTPUT_LOAD='(1.0,-1.0)';
      PINUSE='BI';
    'UART0_TXD||AGPIO138':
      PIN_NUMBER='(0,0,0,0,0,0,0,0,0,0,0,0,0,0,0,0,0,0,0,DJ34,0,0,0,0,0,0,0,0,0,~
0,0,0,0,0,0,0,0,0,0,0)';
      BIDIRECTIONAL='TRUE';
      INPUT_LOAD='(-0.01,0.01)';
      OUTPUT_LOAD='(1.0,-1.0)';
      PINUSE='BI';
    'UART0_CTS_L||UART2_TXD||AGPIO135':
      PIN_NUMBER='(0,0,0,0,0,0,0,0,0,0,0,0,0,0,0,0,0,0,0,DJ33,0,0,0,0,0,0,0,0,0,~
0,0,0,0,0,0,0,0,0,0,0)';
      BIDIRECTIONAL='TRUE';
      INPUT_LOAD='(-0.01,0.01)';
      OUTPUT_LOAD='(1.0,-1.0)';
      PINUSE='BI';
    'AZ_SDIN2||SW_MDATA0':
      PIN_NUMBER='(0,0,0,0,0,0,0,0,0,0,0,0,0,0,0,0,0,0,0,A33,0,0,0,0,0,0,0,0,0,0~
,0,0,0,0,0,0,0,0,0,0)';
      OUTPUT_LOAD='(1.0,-1.0)';
      PINUSE='OUT';
    'AZ_SDOUT||SW_MDATA2':
      PIN_NUMBER='(0,0,0,0,0,0,0,0,0,0,0,0,0,0,0,0,0,0,0,A32,0,0,0,0,0,0,0,0,0,0~
,0,0,0,0,0,0,0,0,0,0)';
      OUTPUT_LOAD='(1.0,-1.0)';
      PINUSE='OUT';
    'AZ_RST_L||SW_MDATA1':
      PIN_NUMBER='(0,0,0,0,0,0,0,0,0,0,0,0,0,0,0,0,0,0,0,A34,0,0,0,0,0,0,0,0,0,0~
,0,0,0,0,0,0,0,0,0,0)';
      OUTPUT_LOAD='(1.0,-1.0)';
      PINUSE='OUT';
    'AZ_SDIN0||SW_MDATA3':
      PIN_NUMBER='(0,0,0,0,0,0,0,0,0,0,0,0,0,0,0,0,0,0,0,C33,0,0,0,0,0,0,0,0,0,0~
,0,0,0,0,0,0,0,0,0,0)';
      OUTPUT_LOAD='(1.0,-1.0)';
      PINUSE='OUT';
    'AZ_SDIN1||SW_MCLK':
      PIN_NUMBER='(0,0,0,0,0,0,0,0,0,0,0,0,0,0,0,0,0,0,0,D33,0,0,0,0,0,0,0,0,0,0~
,0,0,0,0,0,0,0,0,0,0)';
      OUTPUT_LOAD='(1.0,-1.0)';
      PINUSE='OUT';
    'SP5R1':
      PIN_NUMBER='(0,0,0,0,0,0,0,0,0,0,0,0,0,0,0,0,0,0,0,C19,0,0,0,0,0,0,0,0,0,0~
,0,0,0,0,0,0,0,0,0,0)';
      OUTPUT_LOAD='(1.0,-1.0)';
      PINUSE='OUT';
    'TCK':
      PIN_NUMBER='(0,0,0,0,0,0,0,0,0,0,0,0,0,0,0,0,0,0,0,B17,0,0,0,0,0,0,0,0,0,0~
,0,0,0,0,0,0,0,0,0,0)';
      INPUT_LOAD='(-0.01,0.01)';
      PINUSE='IN';
    'RTC_LDO_SELECT':
      PIN_NUMBER='(0,0,0,0,0,0,0,0,0,0,0,0,0,0,0,0,0,0,0,DH8,0,0,0,0,0,0,0,0,0,0~
,0,0,0,0,0,0,0,0,0,0)';
      INPUT_LOAD='(-0.01,0.01)';
      PINUSE='IN';
    'UART1_RXD||AGPIO141':
      PIN_NUMBER='(0,0,0,0,0,0,0,0,0,0,0,0,0,0,0,0,0,0,0,DH33,0,0,0,0,0,0,0,0,0,~
0,0,0,0,0,0,0,0,0,0,0)';
      BIDIRECTIONAL='TRUE';
      INPUT_LOAD='(-0.01,0.01)';
      OUTPUT_LOAD='(1.0,-1.0)';
      PINUSE='BI';
    'UART1_TXD||AGPIO142':
      PIN_NUMBER='(0,0,0,0,0,0,0,0,0,0,0,0,0,0,0,0,0,0,0,DJ32,0,0,0,0,0,0,0,0,0,~
0,0,0,0,0,0,0,0,0,0,0)';
      BIDIRECTIONAL='TRUE';
      INPUT_LOAD='(-0.01,0.01)';
      OUTPUT_LOAD='(1.0,-1.0)';
      PINUSE='BI';
    'VSS_SENSE_A':
      PIN_NUMBER='(0,0,0,0,0,0,0,0,0,0,0,0,0,0,0,0,0,0,0,C3,0,0,0,0,0,0,0,0,0,0,~
0,0,0,0,0,0,0,0,0,0)';
      PINUSE='POWER';
      NO_LOAD_CHECK='Both';
      NO_IO_CHECK='Both';
      NO_ASSERT_CHECK='TRUE';
      NO_DIR_CHECK='TRUE';
      ALLOW_CONNECT='TRUE';
    'VSS_SENSE_B':
      PIN_NUMBER='(0,0,0,0,0,0,0,0,0,0,0,0,0,0,0,0,0,0,0,BR54,0,0,0,0,0,0,0,0,0,~
0,0,0,0,0,0,0,0,0,0,0)';
      PINUSE='POWER';
      NO_LOAD_CHECK='Both';
      NO_IO_CHECK='Both';
      NO_ASSERT_CHECK='TRUE';
      NO_DIR_CHECK='TRUE';
      ALLOW_CONNECT='TRUE';
    'VSS_SENSE_C':
      PIN_NUMBER='(0,0,0,0,0,0,0,0,0,0,0,0,0,0,0,0,0,0,0,DJ3,0,0,0,0,0,0,0,0,0,0~
,0,0,0,0,0,0,0,0,0,0)';
      PINUSE='POWER';
      NO_LOAD_CHECK='Both';
      NO_IO_CHECK='Both';
      NO_ASSERT_CHECK='TRUE';
      NO_DIR_CHECK='TRUE';
      ALLOW_CONNECT='TRUE';
    'VSS_SENSE_D':
      PIN_NUMBER='(0,0,0,0,0,0,0,0,0,0,0,0,0,0,0,0,0,0,0,B73,0,0,0,0,0,0,0,0,0,0~
,0,0,0,0,0,0,0,0,0,0)';
      PINUSE='POWER';
      NO_LOAD_CHECK='Both';
      NO_IO_CHECK='Both';
      NO_ASSERT_CHECK='TRUE';
      NO_DIR_CHECK='TRUE';
      ALLOW_CONNECT='TRUE';
    'VDDIO_SENSE':
      PIN_NUMBER='(0,0,0,0,0,0,0,0,0,0,0,0,0,0,0,0,0,0,0,BR53,0,0,0,0,0,0,0,0,0,~
0,0,0,0,0,0,0,0,0,0,0)';
      PINUSE='POWER';
      NO_LOAD_CHECK='Both';
      NO_IO_CHECK='Both';
      NO_ASSERT_CHECK='TRUE';
      NO_DIR_CHECK='TRUE';
      ALLOW_CONNECT='TRUE';
    'VDD_11_S3_SENSE':
      PIN_NUMBER='(0,0,0,0,0,0,0,0,0,0,0,0,0,0,0,0,0,0,0,DH3,0,0,0,0,0,0,0,0,0,0~
,0,0,0,0,0,0,0,0,0,0)';
      PINUSE='POWER';
      NO_LOAD_CHECK='Both';
      NO_IO_CHECK='Both';
      NO_ASSERT_CHECK='TRUE';
      NO_DIR_CHECK='TRUE';
      ALLOW_CONNECT='TRUE';
    'VDD_18_S5_SENSE':
      PIN_NUMBER='(0,0,0,0,0,0,0,0,0,0,0,0,0,0,0,0,0,0,0,C74,0,0,0,0,0,0,0,0,0,0~
,0,0,0,0,0,0,0,0,0,0)';
      PINUSE='POWER';
      NO_LOAD_CHECK='Both';
      NO_IO_CHECK='Both';
      NO_ASSERT_CHECK='TRUE';
      NO_DIR_CHECK='TRUE';
      ALLOW_CONNECT='TRUE';
    'VDD_33_S5_SENSE':
      PIN_NUMBER='(0,0,0,0,0,0,0,0,0,0,0,0,0,0,0,0,0,0,0,BP53,0,0,0,0,0,0,0,0,0,~
0,0,0,0,0,0,0,0,0,0,0)';
      PINUSE='POWER';
      NO_LOAD_CHECK='Both';
      NO_IO_CHECK='Both';
      NO_ASSERT_CHECK='TRUE';
      NO_DIR_CHECK='TRUE';
      ALLOW_CONNECT='TRUE';
    'VDDCR_SOC_SENSE':
      PIN_NUMBER='(0,0,0,0,0,0,0,0,0,0,0,0,0,0,0,0,0,0,0,B3,0,0,0,0,0,0,0,0,0,0,~
0,0,0,0,0,0,0,0,0,0)';
      PINUSE='POWER';
      NO_LOAD_CHECK='Both';
      NO_IO_CHECK='Both';
      NO_ASSERT_CHECK='TRUE';
      NO_DIR_CHECK='TRUE';
      ALLOW_CONNECT='TRUE';
    'VDDCR_CPU1_SENSE':
      PIN_NUMBER='(0,0,0,0,0,0,0,0,0,0,0,0,0,0,0,0,0,0,0,DG3,0,0,0,0,0,0,0,0,0,0~
,0,0,0,0,0,0,0,0,0,0)';
      PINUSE='POWER';
      NO_LOAD_CHECK='Both';
      NO_IO_CHECK='Both';
      NO_ASSERT_CHECK='TRUE';
      NO_DIR_CHECK='TRUE';
      ALLOW_CONNECT='TRUE';
    'VDDCR_CPU0_SENSE':
      PIN_NUMBER='(0,0,0,0,0,0,0,0,0,0,0,0,0,0,0,0,0,0,0,C2,0,0,0,0,0,0,0,0,0,0,~
0,0,0,0,0,0,0,0,0,0)';
      PINUSE='POWER';
      NO_LOAD_CHECK='Both';
      NO_IO_CHECK='Both';
      NO_ASSERT_CHECK='TRUE';
      NO_DIR_CHECK='TRUE';
      ALLOW_CONNECT='TRUE';
    'TEST6_X3D4':
      PIN_NUMBER='(0,0,0,0,0,0,0,0,0,0,0,0,0,0,0,0,0,0,0,AA23,0,0,0,0,0,0,0,0,0,~
0,0,0,0,0,0,0,0,0,0,0)';
      OUTPUT_LOAD='(1.0,-1.0)';
      PINUSE='OUT';
    'TEST6_CCD1':
      PIN_NUMBER='(0,0,0,0,0,0,0,0,0,0,0,0,0,0,0,0,0,0,0,CJ30,0,0,0,0,0,0,0,0,0,~
0,0,0,0,0,0,0,0,0,0,0)';
      OUTPUT_LOAD='(1.0,-1.0)';
      PINUSE='OUT';
    'TEST5_CCD0':
      PIN_NUMBER='(0,0,0,0,0,0,0,0,0,0,0,0,0,0,0,0,0,0,0,AA51,0,0,0,0,0,0,0,0,0,~
0,0,0,0,0,0,0,0,0,0,0)';
      OUTPUT_TYPE='(TS,TS)';
      INPUT_LOAD='(-0.01,0.01)';
      OUTPUT_LOAD='(1.0,-1.0)';
      PINUSE='TRI';
    'TEST6_X3D5':
      PIN_NUMBER='(0,0,0,0,0,0,0,0,0,0,0,0,0,0,0,0,0,0,0,CJ53,0,0,0,0,0,0,0,0,0,~
0,0,0,0,0,0,0,0,0,0,0)';
      OUTPUT_LOAD='(1.0,-1.0)';
      PINUSE='OUT';
    'TEST6_CCD2':
      PIN_NUMBER='(0,0,0,0,0,0,0,0,0,0,0,0,0,0,0,0,0,0,0,CJ46,0,0,0,0,0,0,0,0,0,~
0,0,0,0,0,0,0,0,0,0,0)';
      OUTPUT_LOAD='(1.0,-1.0)';
      PINUSE='OUT';
    'TEST5_CCD1':
      PIN_NUMBER='(0,0,0,0,0,0,0,0,0,0,0,0,0,0,0,0,0,0,0,CJ27,0,0,0,0,0,0,0,0,0,~
0,0,0,0,0,0,0,0,0,0,0)';
      OUTPUT_TYPE='(TS,TS)';
      INPUT_LOAD='(-0.01,0.01)';
      OUTPUT_LOAD='(1.0,-1.0)';
      PINUSE='TRI';
    'TEST4_CCD0':
      PIN_NUMBER='(0,0,0,0,0,0,0,0,0,0,0,0,0,0,0,0,0,0,0,AA50,0,0,0,0,0,0,0,0,0,~
0,0,0,0,0,0,0,0,0,0,0)';
      OUTPUT_TYPE='(TS,TS)';
      INPUT_LOAD='(-0.01,0.01)';
      OUTPUT_LOAD='(1.0,-1.0)';
      PINUSE='TRI';
    'TEST6_CCD3':
      PIN_NUMBER='(0,0,0,0,0,0,0,0,0,0,0,0,0,0,0,0,0,0,0,Y46,0,0,0,0,0,0,0,0,0,0~
,0,0,0,0,0,0,0,0,0,0)';
      OUTPUT_LOAD='(1.0,-1.0)';
      PINUSE='OUT';
    'TEST5_CCD2':
      PIN_NUMBER='(0,0,0,0,0,0,0,0,0,0,0,0,0,0,0,0,0,0,0,CJ49,0,0,0,0,0,0,0,0,0,~
0,0,0,0,0,0,0,0,0,0,0)';
      OUTPUT_TYPE='(TS,TS)';
      INPUT_LOAD='(-0.01,0.01)';
      OUTPUT_LOAD='(1.0,-1.0)';
      PINUSE='TRI';
    'TEST4_CCD1':
      PIN_NUMBER='(0,0,0,0,0,0,0,0,0,0,0,0,0,0,0,0,0,0,0,CJ28,0,0,0,0,0,0,0,0,0,~
0,0,0,0,0,0,0,0,0,0,0)';
      OUTPUT_TYPE='(TS,TS)';
      INPUT_LOAD='(-0.01,0.01)';
      OUTPUT_LOAD='(1.0,-1.0)';
      PINUSE='TRI';
    'TEST5_CCD3':
      PIN_NUMBER='(0,0,0,0,0,0,0,0,0,0,0,0,0,0,0,0,0,0,0,Y30,0,0,0,0,0,0,0,0,0,0~
,0,0,0,0,0,0,0,0,0,0)';
      OUTPUT_TYPE='(TS,TS)';
      INPUT_LOAD='(-0.01,0.01)';
      OUTPUT_LOAD='(1.0,-1.0)';
      PINUSE='TRI';
    'TEST4_IOD':
      PIN_NUMBER='(0,0,0,0,0,0,0,0,0,0,0,0,0,0,0,0,0,0,0,AA25,0,0,0,0,0,0,0,0,0,~
0,0,0,0,0,0,0,0,0,0,0)';
      OUTPUT_TYPE='(TS,TS)';
      INPUT_LOAD='(-0.01,0.01)';
      OUTPUT_LOAD='(1.0,-1.0)';
      PINUSE='TRI';
    'TEST4_CCD2':
      PIN_NUMBER='(0,0,0,0,0,0,0,0,0,0,0,0,0,0,0,0,0,0,0,CJ48,0,0,0,0,0,0,0,0,0,~
0,0,0,0,0,0,0,0,0,0,0)';
      OUTPUT_TYPE='(TS,TS)';
      INPUT_LOAD='(-0.01,0.01)';
      OUTPUT_LOAD='(1.0,-1.0)';
      PINUSE='TRI';
    'TEST5_IOD':
      PIN_NUMBER='(0,0,0,0,0,0,0,0,0,0,0,0,0,0,0,0,0,0,0,AA24,0,0,0,0,0,0,0,0,0,~
0,0,0,0,0,0,0,0,0,0,0)';
      OUTPUT_TYPE='(TS,TS)';
      INPUT_LOAD='(-0.01,0.01)';
      OUTPUT_LOAD='(1.0,-1.0)';
      PINUSE='TRI';
    'TEST5_CCD4':
      PIN_NUMBER='(0,0,0,0,0,0,0,0,0,0,0,0,0,0,0,0,0,0,0,AA53,0,0,0,0,0,0,0,0,0,~
0,0,0,0,0,0,0,0,0,0,0)';
      OUTPUT_TYPE='(TS,TS)';
      INPUT_LOAD='(-0.01,0.01)';
      OUTPUT_LOAD='(1.0,-1.0)';
      PINUSE='TRI';
    'TEST4_CCD3':
      PIN_NUMBER='(0,0,0,0,0,0,0,0,0,0,0,0,0,0,0,0,0,0,0,AA30,0,0,0,0,0,0,0,0,0,~
0,0,0,0,0,0,0,0,0,0,0)';
      OUTPUT_TYPE='(TS,TS)';
      INPUT_LOAD='(-0.01,0.01)';
      OUTPUT_LOAD='(1.0,-1.0)';
      PINUSE='TRI';
    'TEST6_IOD':
      PIN_NUMBER='(0,0,0,0,0,0,0,0,0,0,0,0,0,0,0,0,0,0,0,AA49,0,0,0,0,0,0,0,0,0,~
0,0,0,0,0,0,0,0,0,0,0)';
      OUTPUT_LOAD='(1.0,-1.0)';
      PINUSE='OUT';
    'TEST5_CCD5':
      PIN_NUMBER='(0,0,0,0,0,0,0,0,0,0,0,0,0,0,0,0,0,0,0,CJ25,0,0,0,0,0,0,0,0,0,~
0,0,0,0,0,0,0,0,0,0,0)';
      OUTPUT_TYPE='(TS,TS)';
      INPUT_LOAD='(-0.01,0.01)';
      OUTPUT_LOAD='(1.0,-1.0)';
      PINUSE='TRI';
    'TEST4_CCD4':
      PIN_NUMBER='(0,0,0,0,0,0,0,0,0,0,0,0,0,0,0,0,0,0,0,AA52,0,0,0,0,0,0,0,0,0,~
0,0,0,0,0,0,0,0,0,0,0)';
      OUTPUT_TYPE='(TS,TS)';
      INPUT_LOAD='(-0.01,0.01)';
      OUTPUT_LOAD='(1.0,-1.0)';
      PINUSE='TRI';
    'TEST5_CCD6':
      PIN_NUMBER='(0,0,0,0,0,0,0,0,0,0,0,0,0,0,0,0,0,0,0,CJ51,0,0,0,0,0,0,0,0,0,~
0,0,0,0,0,0,0,0,0,0,0)';
      OUTPUT_TYPE='(TS,TS)';
      INPUT_LOAD='(-0.01,0.01)';
      OUTPUT_LOAD='(1.0,-1.0)';
      PINUSE='TRI';
    'TEST4_CCD5':
      PIN_NUMBER='(0,0,0,0,0,0,0,0,0,0,0,0,0,0,0,0,0,0,0,CJ26,0,0,0,0,0,0,0,0,0,~
0,0,0,0,0,0,0,0,0,0,0)';
      OUTPUT_TYPE='(TS,TS)';
      INPUT_LOAD='(-0.01,0.01)';
      OUTPUT_LOAD='(1.0,-1.0)';
      PINUSE='TRI';
    'TEST5_CCD7':
      PIN_NUMBER='(0,0,0,0,0,0,0,0,0,0,0,0,0,0,0,0,0,0,0,AA26,0,0,0,0,0,0,0,0,0,~
0,0,0,0,0,0,0,0,0,0,0)';
      OUTPUT_TYPE='(TS,TS)';
      INPUT_LOAD='(-0.01,0.01)';
      OUTPUT_LOAD='(1.0,-1.0)';
      PINUSE='TRI';
    'TEST4_CCD6':
      PIN_NUMBER='(0,0,0,0,0,0,0,0,0,0,0,0,0,0,0,0,0,0,0,CJ50,0,0,0,0,0,0,0,0,0,~
0,0,0,0,0,0,0,0,0,0,0)';
      OUTPUT_TYPE='(TS,TS)';
      INPUT_LOAD='(-0.01,0.01)';
      OUTPUT_LOAD='(1.0,-1.0)';
      PINUSE='TRI';
    'TEST47_CCD0':
      PIN_NUMBER='(0,0,0,0,0,0,0,0,0,0,0,0,0,0,0,0,0,0,0,B60,0,0,0,0,0,0,0,0,0,0~
,0,0,0,0,0,0,0,0,0,0)';
      OUTPUT_TYPE='(TS,TS)';
      INPUT_LOAD='(-0.01,0.01)';
      OUTPUT_LOAD='(1.0,-1.0)';
      PINUSE='TRI';
    'TEST5_CCD8':
      PIN_NUMBER='(0,0,0,0,0,0,0,0,0,0,0,0,0,0,0,0,0,0,0,Y47,0,0,0,0,0,0,0,0,0,0~
,0,0,0,0,0,0,0,0,0,0)';
      OUTPUT_TYPE='(TS,TS)';
      INPUT_LOAD='(-0.01,0.01)';
      OUTPUT_LOAD='(1.0,-1.0)';
      PINUSE='TRI';
    'TEST50_IOD':
      PIN_NUMBER='(0,0,0,0,0,0,0,0,0,0,0,0,0,0,0,0,0,0,0,B61,0,0,0,0,0,0,0,0,0,0~
,0,0,0,0,0,0,0,0,0,0)';
      OUTPUT_TYPE='(TS,TS)';
      INPUT_LOAD='(-0.01,0.01)';
      OUTPUT_LOAD='(1.0,-1.0)';
      PINUSE='TRI';
    'TEST4_CCD7':
      PIN_NUMBER='(0,0,0,0,0,0,0,0,0,0,0,0,0,0,0,0,0,0,0,AA27,0,0,0,0,0,0,0,0,0,~
0,0,0,0,0,0,0,0,0,0,0)';
      OUTPUT_TYPE='(TS,TS)';
      INPUT_LOAD='(-0.01,0.01)';
      OUTPUT_LOAD='(1.0,-1.0)';
      PINUSE='TRI';
    'TEST47_CCD1':
      PIN_NUMBER='(0,0,0,0,0,0,0,0,0,0,0,0,0,0,0,0,0,0,0,CJ24,0,0,0,0,0,0,0,0,0,~
0,0,0,0,0,0,0,0,0,0,0)';
      OUTPUT_TYPE='(TS,TS)';
      INPUT_LOAD='(-0.01,0.01)';
      OUTPUT_LOAD='(1.0,-1.0)';
      PINUSE='TRI';
    'TEST5_CCD9':
      PIN_NUMBER='(0,0,0,0,0,0,0,0,0,0,0,0,0,0,0,0,0,0,0,CK29,0,0,0,0,0,0,0,0,0,~
0,0,0,0,0,0,0,0,0,0,0)';
      OUTPUT_TYPE='(TS,TS)';
      INPUT_LOAD='(-0.01,0.01)';
      OUTPUT_LOAD='(1.0,-1.0)';
      PINUSE='TRI';
    'TEST4_CCD8':
      PIN_NUMBER='(0,0,0,0,0,0,0,0,0,0,0,0,0,0,0,0,0,0,0,AA48,0,0,0,0,0,0,0,0,0,~
0,0,0,0,0,0,0,0,0,0,0)';
      OUTPUT_TYPE='(TS,TS)';
      INPUT_LOAD='(-0.01,0.01)';
      OUTPUT_LOAD='(1.0,-1.0)';
      PINUSE='TRI';
    'TEST47_CCD2':
      PIN_NUMBER='(0,0,0,0,0,0,0,0,0,0,0,0,0,0,0,0,0,0,0,CK46,0,0,0,0,0,0,0,0,0,~
0,0,0,0,0,0,0,0,0,0,0)';
      OUTPUT_TYPE='(TS,TS)';
      INPUT_LOAD='(-0.01,0.01)';
      OUTPUT_LOAD='(1.0,-1.0)';
      PINUSE='TRI';
    'TEST4_CCD10':
      PIN_NUMBER='(0,0,0,0,0,0,0,0,0,0,0,0,0,0,0,0,0,0,0,CJ47,0,0,0,0,0,0,0,0,0,~
0,0,0,0,0,0,0,0,0,0,0)';
      OUTPUT_TYPE='(TS,TS)';
      INPUT_LOAD='(-0.01,0.01)';
      OUTPUT_LOAD='(1.0,-1.0)';
      PINUSE='TRI';
    'TEST4_CCD9':
      PIN_NUMBER='(0,0,0,0,0,0,0,0,0,0,0,0,0,0,0,0,0,0,0,CK30,0,0,0,0,0,0,0,0,0,~
0,0,0,0,0,0,0,0,0,0,0)';
      OUTPUT_TYPE='(TS,TS)';
      INPUT_LOAD='(-0.01,0.01)';
      OUTPUT_LOAD='(1.0,-1.0)';
      PINUSE='TRI';
    'TEST5_CCD10':
      PIN_NUMBER='(0,0,0,0,0,0,0,0,0,0,0,0,0,0,0,0,0,0,0,CK47,0,0,0,0,0,0,0,0,0,~
0,0,0,0,0,0,0,0,0,0,0)';
      OUTPUT_TYPE='(TS,TS)';
      INPUT_LOAD='(-0.01,0.01)';
      OUTPUT_LOAD='(1.0,-1.0)';
      PINUSE='TRI';
    'TEST4_CCD11':
      PIN_NUMBER='(0,0,0,0,0,0,0,0,0,0,0,0,0,0,0,0,0,0,0,AA28,0,0,0,0,0,0,0,0,0,~
0,0,0,0,0,0,0,0,0,0,0)';
      OUTPUT_TYPE='(TS,TS)';
      INPUT_LOAD='(-0.01,0.01)';
      OUTPUT_LOAD='(1.0,-1.0)';
      PINUSE='TRI';
    'TEST5_CCD11':
      PIN_NUMBER='(0,0,0,0,0,0,0,0,0,0,0,0,0,0,0,0,0,0,0,Y29,0,0,0,0,0,0,0,0,0,0~
,0,0,0,0,0,0,0,0,0,0)';
      OUTPUT_TYPE='(TS,TS)';
      INPUT_LOAD='(-0.01,0.01)';
      OUTPUT_LOAD='(1.0,-1.0)';
      PINUSE='TRI';
    'TEST6_X3D0':
      PIN_NUMBER='(0,0,0,0,0,0,0,0,0,0,0,0,0,0,0,0,0,0,0,AA47,0,0,0,0,0,0,0,0,0,~
0,0,0,0,0,0,0,0,0,0,0)';
      OUTPUT_LOAD='(1.0,-1.0)';
      PINUSE='OUT';
    'TEST47_IOD0':
      PIN_NUMBER='(0,0,0,0,0,0,0,0,0,0,0,0,0,0,0,0,0,0,0,B58,0,0,0,0,0,0,0,0,0,0~
,0,0,0,0,0,0,0,0,0,0)';
      OUTPUT_TYPE='(TS,TS)';
      INPUT_LOAD='(-0.01,0.01)';
      OUTPUT_LOAD='(1.0,-1.0)';
      PINUSE='TRI';
    'TEST6_X3D1':
      PIN_NUMBER='(0,0,0,0,0,0,0,0,0,0,0,0,0,0,0,0,0,0,0,CJ29,0,0,0,0,0,0,0,0,0,~
0,0,0,0,0,0,0,0,0,0,0)';
      OUTPUT_LOAD='(1.0,-1.0)';
      PINUSE='OUT';
    'TEST47_IOD1':
      PIN_NUMBER='(0,0,0,0,0,0,0,0,0,0,0,0,0,0,0,0,0,0,0,D7,0,0,0,0,0,0,0,0,0,0,~
0,0,0,0,0,0,0,0,0,0)';
      OUTPUT_TYPE='(TS,TS)';
      INPUT_LOAD='(-0.01,0.01)';
      OUTPUT_LOAD='(1.0,-1.0)';
      PINUSE='TRI';
    'TEST6_X3D2':
      PIN_NUMBER='(0,0,0,0,0,0,0,0,0,0,0,0,0,0,0,0,0,0,0,AA29,0,0,0,0,0,0,0,0,0,~
0,0,0,0,0,0,0,0,0,0,0)';
      OUTPUT_LOAD='(1.0,-1.0)';
      PINUSE='OUT';
    'TEST6_X3D3':
      PIN_NUMBER='(0,0,0,0,0,0,0,0,0,0,0,0,0,0,0,0,0,0,0,CJ52,0,0,0,0,0,0,0,0,0,~
0,0,0,0,0,0,0,0,0,0,0)';
      OUTPUT_LOAD='(1.0,-1.0)';
      PINUSE='OUT';
    'TEST6_CCD0':
      PIN_NUMBER='(0,0,0,0,0,0,0,0,0,0,0,0,0,0,0,0,0,0,0,AA46,0,0,0,0,0,0,0,0,0,~
0,0,0,0,0,0,0,0,0,0,0)';
      OUTPUT_LOAD='(1.0,-1.0)';
      PINUSE='OUT';
    'TEST47_CCD3':
      PIN_NUMBER='(0,0,0,0,0,0,0,0,0,0,0,0,0,0,0,0,0,0,0,E32,0,0,0,0,0,0,0,0,0,0~
,0,0,0,0,0,0,0,0,0,0)';
      OUTPUT_TYPE='(TS,TS)';
      INPUT_LOAD='(-0.01,0.01)';
      OUTPUT_LOAD='(1.0,-1.0)';
      PINUSE='TRI';
    'TEST41_IOD':
      PIN_NUMBER='(0,0,0,0,0,0,0,0,0,0,0,0,0,0,0,0,0,0,0,W31,0,0,0,0,0,0,0,0,0,0~
,0,0,0,0,0,0,0,0,0,0)';
      OUTPUT_TYPE='(TS,TS)';
      INPUT_LOAD='(-0.01,0.01)';
      OUTPUT_LOAD='(1.0,-1.0)';
      PINUSE='TRI';
    'BP0':
      PIN_NUMBER='(0,0,0,0,0,0,0,0,0,0,0,0,0,0,0,0,0,0,0,C63,0,0,0,0,0,0,0,0,0,0~
,0,0,0,0,0,0,0,0,0,0)';
      OUTPUT_LOAD='(1.0,-1.0)';
      PINUSE='OUT';
    'BP1':
      PIN_NUMBER='(0,0,0,0,0,0,0,0,0,0,0,0,0,0,0,0,0,0,0,C62,0,0,0,0,0,0,0,0,0,0~
,0,0,0,0,0,0,0,0,0,0)';
      OUTPUT_LOAD='(1.0,-1.0)';
      PINUSE='OUT';
    'BP2':
      PIN_NUMBER='(0,0,0,0,0,0,0,0,0,0,0,0,0,0,0,0,0,0,0,A63,0,0,0,0,0,0,0,0,0,0~
,0,0,0,0,0,0,0,0,0,0)';
      OUTPUT_LOAD='(1.0,-1.0)';
      PINUSE='OUT';
    'BP3':
      PIN_NUMBER='(0,0,0,0,0,0,0,0,0,0,0,0,0,0,0,0,0,0,0,A62,0,0,0,0,0,0,0,0,0,0~
,0,0,0,0,0,0,0,0,0,0)';
      OUTPUT_LOAD='(1.0,-1.0)';
      PINUSE='OUT';
    'CORETYPE2':
      PIN_NUMBER='(0,0,0,0,0,0,0,0,0,0,0,0,0,0,0,0,0,0,0,D68,0,0,0,0,0,0,0,0,0,0~
,0,0,0,0,0,0,0,0,0,0)';
      OUTPUT_LOAD='(1.0,-1.0)';
      PINUSE='OUT';
    'PWR_GOOD':
      PIN_NUMBER='(0,0,0,0,0,0,0,0,0,0,0,0,0,0,0,0,0,0,0,0,DJ8,0,0,0,0,0,0,0,0,0~
,0,0,0,0,0,0,0,0,0,0)';
      INPUT_LOAD='(-0.01,0.01)';
      PINUSE='IN';
    'RSMRST_L':
      PIN_NUMBER='(0,0,0,0,0,0,0,0,0,0,0,0,0,0,0,0,0,0,0,0,DG10,0,0,0,0,0,0,0,0,~
0,0,0,0,0,0,0,0,0,0,0)';
      INPUT_LOAD='(-0.01,0.01)';
      PINUSE='IN';
    'SLP_S3_L':
      PIN_NUMBER='(0,0,0,0,0,0,0,0,0,0,0,0,0,0,0,0,0,0,0,0,DJ5,0,0,0,0,0,0,0,0,0~
,0,0,0,0,0,0,0,0,0,0)';
      OUTPUT_LOAD='(1.0,-1.0)';
      PINUSE='OUT';
    'SLP_S5_L':
      PIN_NUMBER='(0,0,0,0,0,0,0,0,0,0,0,0,0,0,0,0,0,0,0,0,DG4,0,0,0,0,0,0,0,0,0~
,0,0,0,0,0,0,0,0,0,0)';
      OUTPUT_LOAD='(1.0,-1.0)';
      PINUSE='OUT';
    'SYS_RESET_L||AGPIO1':
      PIN_NUMBER='(0,0,0,0,0,0,0,0,0,0,0,0,0,0,0,0,0,0,0,0,DH6,0,0,0,0,0,0,0,0,0~
,0,0,0,0,0,0,0,0,0,0)';
      BIDIRECTIONAL='TRUE';
      INPUT_LOAD='(-0.01,0.01)';
      OUTPUT_LOAD='(1.0,-1.0)';
      PINUSE='BI';
    'WAKE_L||AGPIO2':
      PIN_NUMBER='(0,0,0,0,0,0,0,0,0,0,0,0,0,0,0,0,0,0,0,0,DJ10,0,0,0,0,0,0,0,0,~
0,0,0,0,0,0,0,0,0,0,0)';
      BIDIRECTIONAL='TRUE';
      INPUT_LOAD='(-0.01,0.01)';
      OUTPUT_LOAD='(1.0,-1.0)';
      PINUSE='BI';
    'X32K_X1':
      PIN_NUMBER='(0,0,0,0,0,0,0,0,0,0,0,0,0,0,0,0,0,0,0,0,DJ14,0,0,0,0,0,0,0,0,~
0,0,0,0,0,0,0,0,0,0,0)';
      INPUT_LOAD='(-0.01,0.01)';
      PINUSE='IN';
    'X32K_X2':
      PIN_NUMBER='(0,0,0,0,0,0,0,0,0,0,0,0,0,0,0,0,0,0,0,0,DJ13,0,0,0,0,0,0,0,0,~
0,0,0,0,0,0,0,0,0,0,0)';
      INPUT_LOAD='(-0.01,0.01)';
      PINUSE='IN';
    'X48M_X1':
      PIN_NUMBER='(0,0,0,0,0,0,0,0,0,0,0,0,0,0,0,0,0,0,0,0,DJ17,0,0,0,0,0,0,0,0,~
0,0,0,0,0,0,0,0,0,0,0)';
      INPUT_LOAD='(-0.01,0.01)';
      PINUSE='IN';
    'X48M_X2':
      PIN_NUMBER='(0,0,0,0,0,0,0,0,0,0,0,0,0,0,0,0,0,0,0,0,DJ16,0,0,0,0,0,0,0,0,~
0,0,0,0,0,0,0,0,0,0,0)';
      INPUT_LOAD='(-0.01,0.01)';
      PINUSE='IN';
    'PWR_BTN_L||AGPIO0':
      PIN_NUMBER='(0,0,0,0,0,0,0,0,0,0,0,0,0,0,0,0,0,0,0,0,DH7,0,0,0,0,0,0,0,0,0~
,0,0,0,0,0,0,0,0,0,0)';
      BIDIRECTIONAL='TRUE';
      INPUT_LOAD='(-0.01,0.01)';
      OUTPUT_LOAD='(1.0,-1.0)';
      PINUSE='BI';
    'NV_SAVE_L':
      PIN_NUMBER='(0,0,0,0,0,0,0,0,0,0,0,0,0,0,0,0,0,0,0,0,B64,0,0,0,0,0,0,0,0,0~
,0,0,0,0,0,0,0,0,0,0)';
      OUTPUT_LOAD='(1.0,-1.0)';
      PINUSE='OUT';
    'FORCE_SELFREFRESH':
      PIN_NUMBER='(0,0,0,0,0,0,0,0,0,0,0,0,0,0,0,0,0,0,0,0,B63,0,0,0,0,0,0,0,0,0~
,0,0,0,0,0,0,0,0,0,0)';
      INPUT_LOAD='(-0.01,0.01)';
      PINUSE='IN';
    'RTCCLK':
      PIN_NUMBER='(0,0,0,0,0,0,0,0,0,0,0,0,0,0,0,0,0,0,0,0,DH9,0,0,0,0,0,0,0,0,0~
,0,0,0,0,0,0,0,0,0,0)';
      BIDIRECTIONAL='TRUE';
      INPUT_LOAD='(-0.01,0.01)';
      OUTPUT_LOAD='(1.0,-1.0)';
      PINUSE='BI';
    'GPP_CLK05N':
      PIN_NUMBER='(0,0,0,0,0,0,0,0,0,0,0,0,0,0,0,0,0,0,0,0,C9,0,0,0,0,0,0,0,0,0,~
0,0,0,0,0,0,0,0,0,0)';
      OUTPUT_LOAD='(1.0,-1.0)';
      PINUSE='OUT';
    'GPP_CLK15N':
      PIN_NUMBER='(0,0,0,0,0,0,0,0,0,0,0,0,0,0,0,0,0,0,0,0,DJ50,0,0,0,0,0,0,0,0,~
0,0,0,0,0,0,0,0,0,0,0)';
      OUTPUT_LOAD='(1.0,-1.0)';
      PINUSE='OUT';
    'GPP_CLK04N':
      PIN_NUMBER='(0,0,0,0,0,0,0,0,0,0,0,0,0,0,0,0,0,0,0,0,C12,0,0,0,0,0,0,0,0,0~
,0,0,0,0,0,0,0,0,0,0)';
      OUTPUT_LOAD='(1.0,-1.0)';
      PINUSE='OUT';
    'GPP_CLK14N':
      PIN_NUMBER='(0,0,0,0,0,0,0,0,0,0,0,0,0,0,0,0,0,0,0,0,DJ47,0,0,0,0,0,0,0,0,~
0,0,0,0,0,0,0,0,0,0,0)';
      OUTPUT_LOAD='(1.0,-1.0)';
      PINUSE='OUT';
    'GPP_CLK05P':
      PIN_NUMBER='(0,0,0,0,0,0,0,0,0,0,0,0,0,0,0,0,0,0,0,0,B9,0,0,0,0,0,0,0,0,0,~
0,0,0,0,0,0,0,0,0,0)';
      OUTPUT_LOAD='(1.0,-1.0)';
      PINUSE='OUT';
    'GPP_CLK03N':
      PIN_NUMBER='(0,0,0,0,0,0,0,0,0,0,0,0,0,0,0,0,0,0,0,0,A11,0,0,0,0,0,0,0,0,0~
,0,0,0,0,0,0,0,0,0,0)';
      OUTPUT_LOAD='(1.0,-1.0)';
      PINUSE='OUT';
    'GPP_CLK15P':
      PIN_NUMBER='(0,0,0,0,0,0,0,0,0,0,0,0,0,0,0,0,0,0,0,0,DJ51,0,0,0,0,0,0,0,0,~
0,0,0,0,0,0,0,0,0,0,0)';
      OUTPUT_LOAD='(1.0,-1.0)';
      PINUSE='OUT';
    'GPP_CLK13N':
      PIN_NUMBER='(0,0,0,0,0,0,0,0,0,0,0,0,0,0,0,0,0,0,0,0,DJ54,0,0,0,0,0,0,0,0,~
0,0,0,0,0,0,0,0,0,0,0)';
      OUTPUT_LOAD='(1.0,-1.0)';
      PINUSE='OUT';
    'GPP_CLK04P':
      PIN_NUMBER='(0,0,0,0,0,0,0,0,0,0,0,0,0,0,0,0,0,0,0,0,B12,0,0,0,0,0,0,0,0,0~
,0,0,0,0,0,0,0,0,0,0)';
      OUTPUT_LOAD='(1.0,-1.0)';
      PINUSE='OUT';
    'GPP_CLK02N':
      PIN_NUMBER='(0,0,0,0,0,0,0,0,0,0,0,0,0,0,0,0,0,0,0,0,C6,0,0,0,0,0,0,0,0,0,~
0,0,0,0,0,0,0,0,0,0)';
      OUTPUT_LOAD='(1.0,-1.0)';
      PINUSE='OUT';
    'GPP_CLK14P':
      PIN_NUMBER='(0,0,0,0,0,0,0,0,0,0,0,0,0,0,0,0,0,0,0,0,DJ48,0,0,0,0,0,0,0,0,~
0,0,0,0,0,0,0,0,0,0,0)';
      OUTPUT_LOAD='(1.0,-1.0)';
      PINUSE='OUT';
    'GPP_CLK12N':
      PIN_NUMBER='(0,0,0,0,0,0,0,0,0,0,0,0,0,0,0,0,0,0,0,0,DJ44,0,0,0,0,0,0,0,0,~
0,0,0,0,0,0,0,0,0,0,0)';
      OUTPUT_LOAD='(1.0,-1.0)';
      PINUSE='OUT';
    'GPP_CLK03P':
      PIN_NUMBER='(0,0,0,0,0,0,0,0,0,0,0,0,0,0,0,0,0,0,0,0,A10,0,0,0,0,0,0,0,0,0~
,0,0,0,0,0,0,0,0,0,0)';
      OUTPUT_LOAD='(1.0,-1.0)';
      PINUSE='OUT';
    'GPP_CLK01N':
      PIN_NUMBER='(0,0,0,0,0,0,0,0,0,0,0,0,0,0,0,0,0,0,0,0,A7,0,0,0,0,0,0,0,0,0,~
0,0,0,0,0,0,0,0,0,0)';
      OUTPUT_LOAD='(1.0,-1.0)';
      PINUSE='OUT';
    'GPP_CLK13P':
      PIN_NUMBER='(0,0,0,0,0,0,0,0,0,0,0,0,0,0,0,0,0,0,0,0,DJ53,0,0,0,0,0,0,0,0,~
0,0,0,0,0,0,0,0,0,0,0)';
      OUTPUT_LOAD='(1.0,-1.0)';
      PINUSE='OUT';
    'GPP_CLK11N':
      PIN_NUMBER='(0,0,0,0,0,0,0,0,0,0,0,0,0,0,0,0,0,0,0,0,DJ42,0,0,0,0,0,0,0,0,~
0,0,0,0,0,0,0,0,0,0,0)';
      OUTPUT_LOAD='(1.0,-1.0)';
      PINUSE='OUT';
    'GPP_CLK02P':
      PIN_NUMBER='(0,0,0,0,0,0,0,0,0,0,0,0,0,0,0,0,0,0,0,0,B6,0,0,0,0,0,0,0,0,0,~
0,0,0,0,0,0,0,0,0,0)';
      OUTPUT_LOAD='(1.0,-1.0)';
      PINUSE='OUT';
    'GPP_CLK12P':
      PIN_NUMBER='(0,0,0,0,0,0,0,0,0,0,0,0,0,0,0,0,0,0,0,0,DJ45,0,0,0,0,0,0,0,0,~
0,0,0,0,0,0,0,0,0,0,0)';
      OUTPUT_LOAD='(1.0,-1.0)';
      PINUSE='OUT';
    'GPP_CLK01P':
      PIN_NUMBER='(0,0,0,0,0,0,0,0,0,0,0,0,0,0,0,0,0,0,0,0,A8,0,0,0,0,0,0,0,0,0,~
0,0,0,0,0,0,0,0,0,0)';
      OUTPUT_LOAD='(1.0,-1.0)';
      PINUSE='OUT';
    'GPP_CLK11P':
      PIN_NUMBER='(0,0,0,0,0,0,0,0,0,0,0,0,0,0,0,0,0,0,0,0,DJ41,0,0,0,0,0,0,0,0,~
0,0,0,0,0,0,0,0,0,0,0)';
      OUTPUT_LOAD='(1.0,-1.0)';
      PINUSE='OUT';
    'AGPIO4||SATA_ACT_L':
      PIN_NUMBER='(0,0,0,0,0,0,0,0,0,0,0,0,0,0,0,0,0,0,0,0,DF36,0,0,0,0,0,0,0,0,~
0,0,0,0,0,0,0,0,0,0,0)';
      BIDIRECTIONAL='TRUE';
      INPUT_LOAD='(-0.01,0.01)';
      OUTPUT_LOAD='(1.0,-1.0)';
      PINUSE='BI';
    'AGPIO3||SPD_HOST_CTRL_L':
      PIN_NUMBER='(0,0,0,0,0,0,0,0,0,0,0,0,0,0,0,0,0,0,0,0,DE36,0,0,0,0,0,0,0,0,~
0,0,0,0,0,0,0,0,0,0,0)';
      BIDIRECTIONAL='TRUE';
      INPUT_LOAD='(-0.01,0.01)';
      OUTPUT_LOAD='(1.0,-1.0)';
      PINUSE='BI';
    'PCIE_RST1_L||AGPIO26':
      PIN_NUMBER='(0,0,0,0,0,0,0,0,0,0,0,0,0,0,0,0,0,0,0,0,DG36,0,0,0,0,0,0,0,0,~
0,0,0,0,0,0,0,0,0,0,0)';
      BIDIRECTIONAL='TRUE';
      INPUT_LOAD='(-0.01,0.01)';
      OUTPUT_LOAD='(1.0,-1.0)';
      PINUSE='BI';
    'SGPIO_LOAD||AGPIO261':
      PIN_NUMBER='(0,0,0,0,0,0,0,0,0,0,0,0,0,0,0,0,0,0,0,0,B15,0,0,0,0,0,0,0,0,0~
,0,0,0,0,0,0,0,0,0,0)';
      BIDIRECTIONAL='TRUE';
      INPUT_LOAD='(-0.01,0.01)';
      OUTPUT_LOAD='(1.0,-1.0)';
      PINUSE='BI';
    'I3C2_SDA||I2C2_SDA||SPD2_SDA||AGPIO150':
      PIN_NUMBER='(0,0,0,0,0,0,0,0,0,0,0,0,0,0,0,0,0,0,0,0,B72,0,0,0,0,0,0,0,0,0~
,0,0,0,0,0,0,0,0,0,0)';
      BIDIRECTIONAL='TRUE';
      INPUT_LOAD='(-0.01,0.01)';
      OUTPUT_LOAD='(1.0,-1.0)';
      PINUSE='BI';
    'SGPIO_DATAOUT||AGPIO260':
      PIN_NUMBER='(0,0,0,0,0,0,0,0,0,0,0,0,0,0,0,0,0,0,0,0,D15,0,0,0,0,0,0,0,0,0~
,0,0,0,0,0,0,0,0,0,0)';
      BIDIRECTIONAL='TRUE';
      INPUT_LOAD='(-0.01,0.01)';
      OUTPUT_LOAD='(1.0,-1.0)';
      PINUSE='BI';
    'I3C3_SDA||I2C3_SDA||SPD3_SDA||AGPIO152':
      PIN_NUMBER='(0,0,0,0,0,0,0,0,0,0,0,0,0,0,0,0,0,0,0,0,B4,0,0,0,0,0,0,0,0,0,~
0,0,0,0,0,0,0,0,0,0)';
      BIDIRECTIONAL='TRUE';
      INPUT_LOAD='(-0.01,0.01)';
      OUTPUT_LOAD='(1.0,-1.0)';
      PINUSE='BI';
    'AGPIO258||SGPIO2_CLK||CLK_REQ02_L':
      PIN_NUMBER='(0,0,0,0,0,0,0,0,0,0,0,0,0,0,0,0,0,0,0,0,A13,0,0,0,0,0,0,0,0,0~
,0,0,0,0,0,0,0,0,0,0)';
      BIDIRECTIONAL='TRUE';
      INPUT_LOAD='(-0.01,0.01)';
      OUTPUT_LOAD='(1.0,-1.0)';
      PINUSE='BI';
    'AGPIO256||SGPIO0_CLK':
      PIN_NUMBER='(0,0,0,0,0,0,0,0,0,0,0,0,0,0,0,0,0,0,0,0,A14,0,0,0,0,0,0,0,0,0~
,0,0,0,0,0,0,0,0,0,0)';
      BIDIRECTIONAL='TRUE';
      INPUT_LOAD='(-0.01,0.01)';
      OUTPUT_LOAD='(1.0,-1.0)';
      PINUSE='BI';
    'PCIE_RST0_L||AGPIO266':
      PIN_NUMBER='(0,0,0,0,0,0,0,0,0,0,0,0,0,0,0,0,0,0,0,0,D18,0,0,0,0,0,0,0,0,0~
,0,0,0,0,0,0,0,0,0,0)';
      BIDIRECTIONAL='TRUE';
      INPUT_LOAD='(-0.01,0.01)';
      OUTPUT_LOAD='(1.0,-1.0)';
      PINUSE='BI';
    'AGPIO115||CLK_REQ11_L':
      PIN_NUMBER='(0,0,0,0,0,0,0,0,0,0,0,0,0,0,0,0,0,0,0,0,DH16,0,0,0,0,0,0,0,0,~
0,0,0,0,0,0,0,0,0,0,0)';
      BIDIRECTIONAL='TRUE';
      INPUT_LOAD='(-0.01,0.01)';
      OUTPUT_LOAD='(1.0,-1.0)';
      PINUSE='BI';
    'I3C0_SDA||I2C0_SDA||SPD0_SDA||SMBUS0_SDA||AGPIO146':
      PIN_NUMBER='(0,0,0,0,0,0,0,0,0,0,0,0,0,0,0,0,0,0,0,0,B71,0,0,0,0,0,0,0,0,0~
,0,0,0,0,0,0,0,0,0,0)';
      BIDIRECTIONAL='TRUE';
      INPUT_LOAD='(-0.01,0.01)';
      OUTPUT_LOAD='(1.0,-1.0)';
      PINUSE='BI';
    'I3C1_SCL||I2C1_SCL||SPD1_SCL||AGPIO147':
      PIN_NUMBER='(0,0,0,0,0,0,0,0,0,0,0,0,0,0,0,0,0,0,0,0,C7,0,0,0,0,0,0,0,0,0,~
0,0,0,0,0,0,0,0,0,0)';
      BIDIRECTIONAL='TRUE';
      INPUT_LOAD='(-0.01,0.01)';
      OUTPUT_LOAD='(1.0,-1.0)';
      PINUSE='BI';
    'I3C2_SCL||I2C2_SCL||SPD2_SCL||AGPIO149':
      PIN_NUMBER='(0,0,0,0,0,0,0,0,0,0,0,0,0,0,0,0,0,0,0,0,C72,0,0,0,0,0,0,0,0,0~
,0,0,0,0,0,0,0,0,0,0)';
      BIDIRECTIONAL='TRUE';
      INPUT_LOAD='(-0.01,0.01)';
      OUTPUT_LOAD='(1.0,-1.0)';
      PINUSE='BI';
    'I3C0_SCL||I2C0_SCL||SPD0_SCL||SMBUS0_SCL||AGPIO145':
      PIN_NUMBER='(0,0,0,0,0,0,0,0,0,0,0,0,0,0,0,0,0,0,0,0,A71,0,0,0,0,0,0,0,0,0~
,0,0,0,0,0,0,0,0,0,0)';
      BIDIRECTIONAL='TRUE';
      INPUT_LOAD='(-0.01,0.01)';
      OUTPUT_LOAD='(1.0,-1.0)';
      PINUSE='BI';
    'AGPIO259||SGPIO3_CLK':
      PIN_NUMBER='(0,0,0,0,0,0,0,0,0,0,0,0,0,0,0,0,0,0,0,0,B16,0,0,0,0,0,0,0,0,0~
,0,0,0,0,0,0,0,0,0,0)';
      BIDIRECTIONAL='TRUE';
      INPUT_LOAD='(-0.01,0.01)';
      OUTPUT_LOAD='(1.0,-1.0)';
      PINUSE='BI';
    'PWRGD_OUT||AGPIO12':
      PIN_NUMBER='(0,0,0,0,0,0,0,0,0,0,0,0,0,0,0,0,0,0,0,0,DH36,0,0,0,0,0,0,0,0,~
0,0,0,0,0,0,0,0,0,0,0)';
      BIDIRECTIONAL='TRUE';
      INPUT_LOAD='(-0.01,0.01)';
      OUTPUT_LOAD='(1.0,-1.0)';
      PINUSE='BI';
    'AGPIO116||CLK_REQ12_L':
      PIN_NUMBER='(0,0,0,0,0,0,0,0,0,0,0,0,0,0,0,0,0,0,0,0,DH15,0,0,0,0,0,0,0,0,~
0,0,0,0,0,0,0,0,0,0,0)';
      BIDIRECTIONAL='TRUE';
      INPUT_LOAD='(-0.01,0.01)';
      OUTPUT_LOAD='(1.0,-1.0)';
      PINUSE='BI';
    'I3C1_SDA||I2C1_SDA||SPD1_SDA||AGPIO148':
      PIN_NUMBER='(0,0,0,0,0,0,0,0,0,0,0,0,0,0,0,0,0,0,0,0,A5,0,0,0,0,0,0,0,0,0,~
0,0,0,0,0,0,0,0,0,0)';
      BIDIRECTIONAL='TRUE';
      INPUT_LOAD='(-0.01,0.01)';
      OUTPUT_LOAD='(1.0,-1.0)';
      PINUSE='BI';
    'I3C3_SCL||I2C3_SCL||SPD3_SCL||AGPIO151':
      PIN_NUMBER='(0,0,0,0,0,0,0,0,0,0,0,0,0,0,0,0,0,0,0,0,A4,0,0,0,0,0,0,0,0,0,~
0,0,0,0,0,0,0,0,0,0)';
      BIDIRECTIONAL='TRUE';
      INPUT_LOAD='(-0.01,0.01)';
      OUTPUT_LOAD='(1.0,-1.0)';
      PINUSE='BI';
    'I2C4_SCL||HP_SCL||UBM_SCL||AGPIO13':
      PIN_NUMBER='(0,0,0,0,0,0,0,0,0,0,0,0,0,0,0,0,0,0,0,0,DG12,0,0,0,0,0,0,0,0,~
0,0,0,0,0,0,0,0,0,0,0)';
      BIDIRECTIONAL='TRUE';
      INPUT_LOAD='(-0.01,0.01)';
      OUTPUT_LOAD='(1.0,-1.0)';
      PINUSE='BI';
    'I2C4_SDA||HP_SDA||UBM_SDA||AGPIO14':
      PIN_NUMBER='(0,0,0,0,0,0,0,0,0,0,0,0,0,0,0,0,0,0,0,0,DH12,0,0,0,0,0,0,0,0,~
0,0,0,0,0,0,0,0,0,0,0)';
      BIDIRECTIONAL='TRUE';
      INPUT_LOAD='(-0.01,0.01)';
      OUTPUT_LOAD='(1.0,-1.0)';
      PINUSE='BI';
    'I2C5_SCL||BMC_SCL||SMBUS1_SCL||AGPIO19':
      PIN_NUMBER='(0,0,0,0,0,0,0,0,0,0,0,0,0,0,0,0,0,0,0,0,DJ21,0,0,0,0,0,0,0,0,~
0,0,0,0,0,0,0,0,0,0,0)';
      BIDIRECTIONAL='TRUE';
      INPUT_LOAD='(-0.01,0.01)';
      OUTPUT_LOAD='(1.0,-1.0)';
      PINUSE='BI';
    'I2C5_SDA||BMC_SDA||SMBUS1_SDA||AGPIO20':
      PIN_NUMBER='(0,0,0,0,0,0,0,0,0,0,0,0,0,0,0,0,0,0,0,0,DJ20,0,0,0,0,0,0,0,0,~
0,0,0,0,0,0,0,0,0,0,0)';
      BIDIRECTIONAL='TRUE';
      INPUT_LOAD='(-0.01,0.01)';
      OUTPUT_LOAD='(1.0,-1.0)';
      PINUSE='BI';
    'SMERR_L||AGPIO24':
      PIN_NUMBER='(0,0,0,0,0,0,0,0,0,0,0,0,0,0,0,0,0,0,0,0,DJ11,0,0,0,0,0,0,0,0,~
0,0,0,0,0,0,0,0,0,0,0)';
      BIDIRECTIONAL='TRUE';
      INPUT_LOAD='(-0.01,0.01)';
      OUTPUT_LOAD='(1.0,-1.0)';
      PINUSE='BI';
    'REFCLK100SSC_P||GPP_CLK10P':
      PIN_NUMBER='(0,0,0,0,0,0,0,0,0,0,0,0,0,0,0,0,0,0,0,0,A19,0,0,0,0,0,0,0,0,0~
,0,0,0,0,0,0,0,0,0,0)';
      BIDIRECTIONAL='TRUE';
      INPUT_LOAD='(-0.01,0.01)';
      OUTPUT_LOAD='(1.0,-1.0)';
      PINUSE='BI';
    'REFCLK100SSC_N||GPP_CLK10N':
      PIN_NUMBER='(0,0,0,0,0,0,0,0,0,0,0,0,0,0,0,0,0,0,0,0,A20,0,0,0,0,0,0,0,0,0~
,0,0,0,0,0,0,0,0,0,0)';
      BIDIRECTIONAL='TRUE';
      INPUT_LOAD='(-0.01,0.01)';
      OUTPUT_LOAD='(1.0,-1.0)';
      PINUSE='BI';
    'RESET_L':
      PIN_NUMBER='(0,0,0,0,0,0,0,0,0,0,0,0,0,0,0,0,0,0,0,0,B67,0,0,0,0,0,0,0,0,0~
,0,0,0,0,0,0,0,0,0,0)';
      BIDIRECTIONAL='TRUE';
      INPUT_LOAD='(-0.01,0.01)';
      OUTPUT_LOAD='(1.0,-1.0)';
      PINUSE='BI';
    'AGPIO104':
      PIN_NUMBER='(0,0,0,0,0,0,0,0,0,0,0,0,0,0,0,0,0,0,0,0,DH30,0,0,0,0,0,0,0,0,~
0,0,0,0,0,0,0,0,0,0,0)';
      BIDIRECTIONAL='TRUE';
      INPUT_LOAD='(-0.01,0.01)';
      OUTPUT_LOAD='(1.0,-1.0)';
      PINUSE='BI';
    'AGPIO105':
      PIN_NUMBER='(0,0,0,0,0,0,0,0,0,0,0,0,0,0,0,0,0,0,0,0,DE30,0,0,0,0,0,0,0,0,~
0,0,0,0,0,0,0,0,0,0,0)';
      BIDIRECTIONAL='TRUE';
      INPUT_LOAD='(-0.01,0.01)';
      OUTPUT_LOAD='(1.0,-1.0)';
      PINUSE='BI';
    'AGPIO106':
      PIN_NUMBER='(0,0,0,0,0,0,0,0,0,0,0,0,0,0,0,0,0,0,0,0,DF31,0,0,0,0,0,0,0,0,~
0,0,0,0,0,0,0,0,0,0,0)';
      BIDIRECTIONAL='TRUE';
      INPUT_LOAD='(-0.01,0.01)';
      OUTPUT_LOAD='(1.0,-1.0)';
      PINUSE='BI';
    'AGPIO107':
      PIN_NUMBER='(0,0,0,0,0,0,0,0,0,0,0,0,0,0,0,0,0,0,0,0,DG31,0,0,0,0,0,0,0,0,~
0,0,0,0,0,0,0,0,0,0,0)';
      BIDIRECTIONAL='TRUE';
      INPUT_LOAD='(-0.01,0.01)';
      OUTPUT_LOAD='(1.0,-1.0)';
      PINUSE='BI';
    'AGPIO109':
      PIN_NUMBER='(0,0,0,0,0,0,0,0,0,0,0,0,0,0,0,0,0,0,0,0,DG32,0,0,0,0,0,0,0,0,~
0,0,0,0,0,0,0,0,0,0,0)';
      BIDIRECTIONAL='TRUE';
      INPUT_LOAD='(-0.01,0.01)';
      OUTPUT_LOAD='(1.0,-1.0)';
      PINUSE='BI';
    'AGPIO87':
      PIN_NUMBER='(0,0,0,0,0,0,0,0,0,0,0,0,0,0,0,0,0,0,0,0,DG11,0,0,0,0,0,0,0,0,~
0,0,0,0,0,0,0,0,0,0,0)';
      BIDIRECTIONAL='TRUE';
      INPUT_LOAD='(-0.01,0.01)';
      OUTPUT_LOAD='(1.0,-1.0)';
      PINUSE='BI';
    'AGPIO21':
      PIN_NUMBER='(0,0,0,0,0,0,0,0,0,0,0,0,0,0,0,0,0,0,0,0,DF33,0,0,0,0,0,0,0,0,~
0,0,0,0,0,0,0,0,0,0,0)';
      BIDIRECTIONAL='TRUE';
      INPUT_LOAD='(-0.01,0.01)';
      OUTPUT_LOAD='(1.0,-1.0)';
      PINUSE='BI';
    'AGPIO88':
      PIN_NUMBER='(0,0,0,0,0,0,0,0,0,0,0,0,0,0,0,0,0,0,0,0,DJ29,0,0,0,0,0,0,0,0,~
0,0,0,0,0,0,0,0,0,0,0)';
      BIDIRECTIONAL='TRUE';
      INPUT_LOAD='(-0.01,0.01)';
      OUTPUT_LOAD='(1.0,-1.0)';
      PINUSE='BI';
    'AGPIO22':
      PIN_NUMBER='(0,0,0,0,0,0,0,0,0,0,0,0,0,0,0,0,0,0,0,0,DE32,0,0,0,0,0,0,0,0,~
0,0,0,0,0,0,0,0,0,0,0)';
      BIDIRECTIONAL='TRUE';
      INPUT_LOAD='(-0.01,0.01)';
      OUTPUT_LOAD='(1.0,-1.0)';
      PINUSE='BI';
    'GENINT_L||PM_INTR_L||UBM_CPRSNT_CHANGE_DET_L||AGPIO89':
      PIN_NUMBER='(0,0,0,0,0,0,0,0,0,0,0,0,0,0,0,0,0,0,0,0,DJ35,0,0,0,0,0,0,0,0,~
0,0,0,0,0,0,0,0,0,0,0)';
      BIDIRECTIONAL='TRUE';
      INPUT_LOAD='(-0.01,0.01)';
      OUTPUT_LOAD='(1.0,-1.0)';
      PINUSE='BI';
    'AGPIO5||DEVSLP0||SATA_ZP0_L':
      PIN_NUMBER='(0,0,0,0,0,0,0,0,0,0,0,0,0,0,0,0,0,0,0,0,DF40,0,0,0,0,0,0,0,0,~
0,0,0,0,0,0,0,0,0,0,0)';
      BIDIRECTIONAL='TRUE';
      INPUT_LOAD='(-0.01,0.01)';
      OUTPUT_LOAD='(1.0,-1.0)';
      PINUSE='BI';
    'AGPIO6||DEVSLP1||SATA_ZP1_L':
      PIN_NUMBER='(0,0,0,0,0,0,0,0,0,0,0,0,0,0,0,0,0,0,0,0,DE40,0,0,0,0,0,0,0,0,~
0,0,0,0,0,0,0,0,0,0,0)';
      BIDIRECTIONAL='TRUE';
      INPUT_LOAD='(-0.01,0.01)';
      OUTPUT_LOAD='(1.0,-1.0)';
      PINUSE='BI';
    'PWROK||SVI_RST_L':
      PIN_NUMBER='(0,0,0,0,0,0,0,0,0,0,0,0,0,0,0,0,0,0,0,0,D69,0,0,0,0,0,0,0,0,0~
,0,0,0,0,0,0,0,0,0,0)';
      OUTPUT_LOAD='(1.0,-1.0)';
      PINUSE='OUT';
    'AGPIO257||SGPIO1_CLK||CLK_REQ01_L':
      PIN_NUMBER='(0,0,0,0,0,0,0,0,0,0,0,0,0,0,0,0,0,0,0,0,C14,0,0,0,0,0,0,0,0,0~
,0,0,0,0,0,0,0,0,0,0)';
      BIDIRECTIONAL='TRUE';
      INPUT_LOAD='(-0.01,0.01)';
      OUTPUT_LOAD='(1.0,-1.0)';
      PINUSE='BI';
    'SEC_SDA||AGPIO263':
      PIN_NUMBER='(0,0,0,0,0,0,0,0,0,0,0,0,0,0,0,0,0,0,0,0,D14,0,0,0,0,0,0,0,0,0~
,0,0,0,0,0,0,0,0,0,0)';
      BIDIRECTIONAL='TRUE';
      INPUT_LOAD='(-0.01,0.01)';
      OUTPUT_LOAD='(1.0,-1.0)';
      PINUSE='BI';
    'SEC_SCL||AGPIO262':
      PIN_NUMBER='(0,0,0,0,0,0,0,0,0,0,0,0,0,0,0,0,0,0,0,0,B14,0,0,0,0,0,0,0,0,0~
,0,0,0,0,0,0,0,0,0,0)';
      BIDIRECTIONAL='TRUE';
      INPUT_LOAD='(-0.01,0.01)';
      OUTPUT_LOAD='(1.0,-1.0)';
      PINUSE='BI';
    'NMI_SYNC_FLOOD_L':
      PIN_NUMBER='(0,0,0,0,0,0,0,0,0,0,0,0,0,0,0,0,0,0,0,0,DJ31,0,0,0,0,0,0,0,0,~
0,0,0,0,0,0,0,0,0,0,0)';
      INPUT_LOAD='(-0.01,0.01)';
      PINUSE='IN';
    'AGPIO7':
      PIN_NUMBER='(0,0,0,0,0,0,0,0,0,0,0,0,0,0,0,0,0,0,0,0,DH4,0,0,0,0,0,0,0,0,0~
,0,0,0,0,0,0,0,0,0,0)';
      BIDIRECTIONAL='TRUE';
      INPUT_LOAD='(-0.01,0.01)';
      OUTPUT_LOAD='(1.0,-1.0)';
      PINUSE='BI';
    'USB00_DN':
      PIN_NUMBER='(0,0,0,0,0,0,0,0,0,0,0,0,0,0,0,0,0,0,0,0,0,A25,0,0,0,0,0,0,0,0~
,0,0,0,0,0,0,0,0,0,0)';
      BIDIRECTIONAL='TRUE';
      INPUT_LOAD='(-0.01,0.01)';
      OUTPUT_LOAD='(1.0,-1.0)';
      PINUSE='BI';
    'USB00_DP':
      PIN_NUMBER='(0,0,0,0,0,0,0,0,0,0,0,0,0,0,0,0,0,0,0,0,0,A26,0,0,0,0,0,0,0,0~
,0,0,0,0,0,0,0,0,0,0)';
      BIDIRECTIONAL='TRUE';
      INPUT_LOAD='(-0.01,0.01)';
      OUTPUT_LOAD='(1.0,-1.0)';
      PINUSE='BI';
    'USB00_RXN':
      PIN_NUMBER='(0,0,0,0,0,0,0,0,0,0,0,0,0,0,0,0,0,0,0,0,0,E26,0,0,0,0,0,0,0,0~
,0,0,0,0,0,0,0,0,0,0)';
      INPUT_LOAD='(-0.01,0.01)';
      PINUSE='IN';
    'USB00_RXP':
      PIN_NUMBER='(0,0,0,0,0,0,0,0,0,0,0,0,0,0,0,0,0,0,0,0,0,E27,0,0,0,0,0,0,0,0~
,0,0,0,0,0,0,0,0,0,0)';
      INPUT_LOAD='(-0.01,0.01)';
      PINUSE='IN';
    'USB00_TXN':
      PIN_NUMBER='(0,0,0,0,0,0,0,0,0,0,0,0,0,0,0,0,0,0,0,0,0,C26,0,0,0,0,0,0,0,0~
,0,0,0,0,0,0,0,0,0,0)';
      OUTPUT_LOAD='(1.0,-1.0)';
      PINUSE='OUT';
    'USB00_TXP':
      PIN_NUMBER='(0,0,0,0,0,0,0,0,0,0,0,0,0,0,0,0,0,0,0,0,0,C25,0,0,0,0,0,0,0,0~
,0,0,0,0,0,0,0,0,0,0)';
      OUTPUT_LOAD='(1.0,-1.0)';
      PINUSE='OUT';
    'USB01_DN':
      PIN_NUMBER='(0,0,0,0,0,0,0,0,0,0,0,0,0,0,0,0,0,0,0,0,0,A29,0,0,0,0,0,0,0,0~
,0,0,0,0,0,0,0,0,0,0)';
      BIDIRECTIONAL='TRUE';
      INPUT_LOAD='(-0.01,0.01)';
      OUTPUT_LOAD='(1.0,-1.0)';
      PINUSE='BI';
    'USB01_DP':
      PIN_NUMBER='(0,0,0,0,0,0,0,0,0,0,0,0,0,0,0,0,0,0,0,0,0,A28,0,0,0,0,0,0,0,0~
,0,0,0,0,0,0,0,0,0,0)';
      BIDIRECTIONAL='TRUE';
      INPUT_LOAD='(-0.01,0.01)';
      OUTPUT_LOAD='(1.0,-1.0)';
      PINUSE='BI';
    'USB01_RXN':
      PIN_NUMBER='(0,0,0,0,0,0,0,0,0,0,0,0,0,0,0,0,0,0,0,0,0,C28,0,0,0,0,0,0,0,0~
,0,0,0,0,0,0,0,0,0,0)';
      INPUT_LOAD='(-0.01,0.01)';
      PINUSE='IN';
    'USB01_RXP':
      PIN_NUMBER='(0,0,0,0,0,0,0,0,0,0,0,0,0,0,0,0,0,0,0,0,0,C29,0,0,0,0,0,0,0,0~
,0,0,0,0,0,0,0,0,0,0)';
      INPUT_LOAD='(-0.01,0.01)';
      PINUSE='IN';
    'USB01_TXN':
      PIN_NUMBER='(0,0,0,0,0,0,0,0,0,0,0,0,0,0,0,0,0,0,0,0,0,E29,0,0,0,0,0,0,0,0~
,0,0,0,0,0,0,0,0,0,0)';
      OUTPUT_LOAD='(1.0,-1.0)';
      PINUSE='OUT';
    'USB01_TXP':
      PIN_NUMBER='(0,0,0,0,0,0,0,0,0,0,0,0,0,0,0,0,0,0,0,0,0,E30,0,0,0,0,0,0,0,0~
,0,0,0,0,0,0,0,0,0,0)';
      OUTPUT_LOAD='(1.0,-1.0)';
      PINUSE='OUT';
    'USB10_DN':
      PIN_NUMBER='(0,0,0,0,0,0,0,0,0,0,0,0,0,0,0,0,0,0,0,0,0,DH67,0,0,0,0,0,0,0,~
0,0,0,0,0,0,0,0,0,0,0)';
      BIDIRECTIONAL='TRUE';
      INPUT_LOAD='(-0.01,0.01)';
      OUTPUT_LOAD='(1.0,-1.0)';
      PINUSE='BI';
    'USB10_DP':
      PIN_NUMBER='(0,0,0,0,0,0,0,0,0,0,0,0,0,0,0,0,0,0,0,0,0,DJ67,0,0,0,0,0,0,0,~
0,0,0,0,0,0,0,0,0,0,0)';
      BIDIRECTIONAL='TRUE';
      INPUT_LOAD='(-0.01,0.01)';
      OUTPUT_LOAD='(1.0,-1.0)';
      PINUSE='BI';
    'USB10_RXN':
      PIN_NUMBER='(0,0,0,0,0,0,0,0,0,0,0,0,0,0,0,0,0,0,0,0,0,DH65,0,0,0,0,0,0,0,~
0,0,0,0,0,0,0,0,0,0,0)';
      INPUT_LOAD='(-0.01,0.01)';
      PINUSE='IN';
    'USB10_RXP':
      PIN_NUMBER='(0,0,0,0,0,0,0,0,0,0,0,0,0,0,0,0,0,0,0,0,0,DJ65,0,0,0,0,0,0,0,~
0,0,0,0,0,0,0,0,0,0,0)';
      INPUT_LOAD='(-0.01,0.01)';
      PINUSE='IN';
    'USB10_TXN':
      PIN_NUMBER='(0,0,0,0,0,0,0,0,0,0,0,0,0,0,0,0,0,0,0,0,0,DJ69,0,0,0,0,0,0,0,~
0,0,0,0,0,0,0,0,0,0,0)';
      OUTPUT_LOAD='(1.0,-1.0)';
      PINUSE='OUT';
    'USB10_TXP':
      PIN_NUMBER='(0,0,0,0,0,0,0,0,0,0,0,0,0,0,0,0,0,0,0,0,0,DH69,0,0,0,0,0,0,0,~
0,0,0,0,0,0,0,0,0,0,0)';
      OUTPUT_LOAD='(1.0,-1.0)';
      PINUSE='OUT';
    'USB11_DN':
      PIN_NUMBER='(0,0,0,0,0,0,0,0,0,0,0,0,0,0,0,0,0,0,0,0,0,DJ60,0,0,0,0,0,0,0,~
0,0,0,0,0,0,0,0,0,0,0)';
      BIDIRECTIONAL='TRUE';
      INPUT_LOAD='(-0.01,0.01)';
      OUTPUT_LOAD='(1.0,-1.0)';
      PINUSE='BI';
    'USB11_DP':
      PIN_NUMBER='(0,0,0,0,0,0,0,0,0,0,0,0,0,0,0,0,0,0,0,0,0,DH60,0,0,0,0,0,0,0,~
0,0,0,0,0,0,0,0,0,0,0)';
      BIDIRECTIONAL='TRUE';
      INPUT_LOAD='(-0.01,0.01)';
      OUTPUT_LOAD='(1.0,-1.0)';
      PINUSE='BI';
    'USB11_RXN':
      PIN_NUMBER='(0,0,0,0,0,0,0,0,0,0,0,0,0,0,0,0,0,0,0,0,0,DH62,0,0,0,0,0,0,0,~
0,0,0,0,0,0,0,0,0,0,0)';
      INPUT_LOAD='(-0.01,0.01)';
      PINUSE='IN';
    'USB11_RXP':
      PIN_NUMBER='(0,0,0,0,0,0,0,0,0,0,0,0,0,0,0,0,0,0,0,0,0,DJ62,0,0,0,0,0,0,0,~
0,0,0,0,0,0,0,0,0,0,0)';
      INPUT_LOAD='(-0.01,0.01)';
      PINUSE='IN';
    'USB11_TXN':
      PIN_NUMBER='(0,0,0,0,0,0,0,0,0,0,0,0,0,0,0,0,0,0,0,0,0,DH58,0,0,0,0,0,0,0,~
0,0,0,0,0,0,0,0,0,0,0)';
      OUTPUT_LOAD='(1.0,-1.0)';
      PINUSE='OUT';
    'USB11_TXP':
      PIN_NUMBER='(0,0,0,0,0,0,0,0,0,0,0,0,0,0,0,0,0,0,0,0,0,DG58,0,0,0,0,0,0,0,~
0,0,0,0,0,0,0,0,0,0,0)';
      OUTPUT_LOAD='(1.0,-1.0)';
      PINUSE='OUT';
    'USB10_OC_L||AGPIO16':
      PIN_NUMBER='(0,0,0,0,0,0,0,0,0,0,0,0,0,0,0,0,0,0,0,0,0,DG40,0,0,0,0,0,0,0,~
0,0,0,0,0,0,0,0,0,0,0)';
      BIDIRECTIONAL='TRUE';
      INPUT_LOAD='(-0.01,0.01)';
      OUTPUT_LOAD='(1.0,-1.0)';
      PINUSE='BI';
    'USB11_OC_L||AGPIO17':
      PIN_NUMBER='(0,0,0,0,0,0,0,0,0,0,0,0,0,0,0,0,0,0,0,0,0,DH40,0,0,0,0,0,0,0,~
0,0,0,0,0,0,0,0,0,0,0)';
      BIDIRECTIONAL='TRUE';
      INPUT_LOAD='(-0.01,0.01)';
      OUTPUT_LOAD='(1.0,-1.0)';
      PINUSE='BI';
    'ESPI_CS0_L||AGPIO124':
      PIN_NUMBER='(0,0,0,0,0,0,0,0,0,0,0,0,0,0,0,0,0,0,0,0,0,DG28,0,0,0,0,0,0,0,~
0,0,0,0,0,0,0,0,0,0,0)';
      BIDIRECTIONAL='TRUE';
      INPUT_LOAD='(-0.01,0.01)';
      OUTPUT_LOAD='(1.0,-1.0)';
      PINUSE='BI';
    'USB00_OC_L||AGPIO264':
      PIN_NUMBER='(0,0,0,0,0,0,0,0,0,0,0,0,0,0,0,0,0,0,0,0,0,E23,0,0,0,0,0,0,0,0~
,0,0,0,0,0,0,0,0,0,0)';
      BIDIRECTIONAL='TRUE';
      INPUT_LOAD='(-0.01,0.01)';
      OUTPUT_LOAD='(1.0,-1.0)';
      PINUSE='BI';
    'SPI_CS0_L||AGPIO118':
      PIN_NUMBER='(0,0,0,0,0,0,0,0,0,0,0,0,0,0,0,0,0,0,0,0,0,DF30,0,0,0,0,0,0,0,~
0,0,0,0,0,0,0,0,0,0,0)';
      BIDIRECTIONAL='TRUE';
      INPUT_LOAD='(-0.01,0.01)';
      OUTPUT_LOAD='(1.0,-1.0)';
      PINUSE='BI';
    'ESPI1_DAT1||SPI1_DAT1||AGPIO132':
      PIN_NUMBER='(0,0,0,0,0,0,0,0,0,0,0,0,0,0,0,0,0,0,0,0,0,DE24,0,0,0,0,0,0,0,~
0,0,0,0,0,0,0,0,0,0,0)';
      BIDIRECTIONAL='TRUE';
      INPUT_LOAD='(-0.01,0.01)';
      OUTPUT_LOAD='(1.0,-1.0)';
      PINUSE='BI';
    'ESPI1_DAT0||SPI1_DAT0||AGPIO131':
      PIN_NUMBER='(0,0,0,0,0,0,0,0,0,0,0,0,0,0,0,0,0,0,0,0,0,DH24,0,0,0,0,0,0,0,~
0,0,0,0,0,0,0,0,0,0,0)';
      BIDIRECTIONAL='TRUE';
      INPUT_LOAD='(-0.01,0.01)';
      OUTPUT_LOAD='(1.0,-1.0)';
      PINUSE='BI';
    'ESPI_CS1_L||AGPIO125':
      PIN_NUMBER='(0,0,0,0,0,0,0,0,0,0,0,0,0,0,0,0,0,0,0,0,0,DJ23,0,0,0,0,0,0,0,~
0,0,0,0,0,0,0,0,0,0,0)';
      BIDIRECTIONAL='TRUE';
      INPUT_LOAD='(-0.01,0.01)';
      OUTPUT_LOAD='(1.0,-1.0)';
      PINUSE='BI';
    'ESPI1_DAT3||SPI1_DAT3||AGPIO134':
      PIN_NUMBER='(0,0,0,0,0,0,0,0,0,0,0,0,0,0,0,0,0,0,0,0,0,DG25,0,0,0,0,0,0,0,~
0,0,0,0,0,0,0,0,0,0,0)';
      BIDIRECTIONAL='TRUE';
      INPUT_LOAD='(-0.01,0.01)';
      OUTPUT_LOAD='(1.0,-1.0)';
      PINUSE='BI';
    'ESPI1_DAT2||SPI1_DAT2||AGPIO133':
      PIN_NUMBER='(0,0,0,0,0,0,0,0,0,0,0,0,0,0,0,0,0,0,0,0,0,DF25,0,0,0,0,0,0,0,~
0,0,0,0,0,0,0,0,0,0,0)';
      BIDIRECTIONAL='TRUE';
      INPUT_LOAD='(-0.01,0.01)';
      OUTPUT_LOAD='(1.0,-1.0)';
      PINUSE='BI';
    'ESPI0_DAT3||SPI0_DAT3||AGPIO123':
      PIN_NUMBER='(0,0,0,0,0,0,0,0,0,0,0,0,0,0,0,0,0,0,0,0,0,DG29,0,0,0,0,0,0,0,~
0,0,0,0,0,0,0,0,0,0,0)';
      BIDIRECTIONAL='TRUE';
      INPUT_LOAD='(-0.01,0.01)';
      OUTPUT_LOAD='(1.0,-1.0)';
      PINUSE='BI';
    'ESPI0_DAT2||SPI0_DAT2||AGPIO122':
      PIN_NUMBER='(0,0,0,0,0,0,0,0,0,0,0,0,0,0,0,0,0,0,0,0,0,DJ28,0,0,0,0,0,0,0,~
0,0,0,0,0,0,0,0,0,0,0)';
      BIDIRECTIONAL='TRUE';
      INPUT_LOAD='(-0.01,0.01)';
      OUTPUT_LOAD='(1.0,-1.0)';
      PINUSE='BI';
    'ESPI0_DAT1||SPI0_DAT1||AGPIO121':
      PIN_NUMBER='(0,0,0,0,0,0,0,0,0,0,0,0,0,0,0,0,0,0,0,0,0,DG22,0,0,0,0,0,0,0,~
0,0,0,0,0,0,0,0,0,0,0)';
      BIDIRECTIONAL='TRUE';
      INPUT_LOAD='(-0.01,0.01)';
      OUTPUT_LOAD='(1.0,-1.0)';
      PINUSE='BI';
    'ESPI0_DAT0||SPI0_DAT0||AGPIO120':
      PIN_NUMBER='(0,0,0,0,0,0,0,0,0,0,0,0,0,0,0,0,0,0,0,0,0,DF28,0,0,0,0,0,0,0,~
0,0,0,0,0,0,0,0,0,0,0)';
      BIDIRECTIONAL='TRUE';
      INPUT_LOAD='(-0.01,0.01)';
      OUTPUT_LOAD='(1.0,-1.0)';
      PINUSE='BI';
    'SPI_CS2_L||AGPIO126':
      PIN_NUMBER='(0,0,0,0,0,0,0,0,0,0,0,0,0,0,0,0,0,0,0,0,0,DH27,0,0,0,0,0,0,0,~
0,0,0,0,0,0,0,0,0,0,0)';
      BIDIRECTIONAL='TRUE';
      INPUT_LOAD='(-0.01,0.01)';
      OUTPUT_LOAD='(1.0,-1.0)';
      PINUSE='BI';
    'SPI_CS1_L||AGPIO119':
      PIN_NUMBER='(0,0,0,0,0,0,0,0,0,0,0,0,0,0,0,0,0,0,0,0,0,DG26,0,0,0,0,0,0,0,~
0,0,0,0,0,0,0,0,0,0,0)';
      BIDIRECTIONAL='TRUE';
      INPUT_LOAD='(-0.01,0.01)';
      OUTPUT_LOAD='(1.0,-1.0)';
      PINUSE='BI';
    'USB01_OC_L||AGPIO265':
      PIN_NUMBER='(0,0,0,0,0,0,0,0,0,0,0,0,0,0,0,0,0,0,0,0,0,E24,0,0,0,0,0,0,0,0~
,0,0,0,0,0,0,0,0,0,0)';
      BIDIRECTIONAL='TRUE';
      INPUT_LOAD='(-0.01,0.01)';
      OUTPUT_LOAD='(1.0,-1.0)';
      PINUSE='BI';
    'ESPI_RSTIN_L||KBRST_L||AGPIO129':
      PIN_NUMBER='(0,0,0,0,0,0,0,0,0,0,0,0,0,0,0,0,0,0,0,0,0,DJ26,0,0,0,0,0,0,0,~
0,0,0,0,0,0,0,0,0,0,0)';
      BIDIRECTIONAL='TRUE';
      INPUT_LOAD='(-0.01,0.01)';
      OUTPUT_LOAD='(1.0,-1.0)';
      PINUSE='BI';
    'ESPI1_ALERT_L||AGPIO110':
      PIN_NUMBER='(0,0,0,0,0,0,0,0,0,0,0,0,0,0,0,0,0,0,0,0,0,DF24,0,0,0,0,0,0,0,~
0,0,0,0,0,0,0,0,0,0,0)';
      BIDIRECTIONAL='TRUE';
      INPUT_LOAD='(-0.01,0.01)';
      OUTPUT_LOAD='(1.0,-1.0)';
      PINUSE='BI';
    'ESPI_CLK0||SPI_CLK0||AGPIO117':
      PIN_NUMBER='(0,0,0,0,0,0,0,0,0,0,0,0,0,0,0,0,0,0,0,0,0,DJ27,0,0,0,0,0,0,0,~
0,0,0,0,0,0,0,0,0,0,0)';
      BIDIRECTIONAL='TRUE';
      INPUT_LOAD='(-0.01,0.01)';
      OUTPUT_LOAD='(1.0,-1.0)';
      PINUSE='BI';
    'AGPIO76||SPI_TPM_CS_L':
      PIN_NUMBER='(0,0,0,0,0,0,0,0,0,0,0,0,0,0,0,0,0,0,0,0,0,DJ25,0,0,0,0,0,0,0,~
0,0,0,0,0,0,0,0,0,0,0)';
      BIDIRECTIONAL='TRUE';
      INPUT_LOAD='(-0.01,0.01)';
      OUTPUT_LOAD='(1.0,-1.0)';
      PINUSE='BI';
    'ESPI0_ALERT_L||AGPIO108':
      PIN_NUMBER='(0,0,0,0,0,0,0,0,0,0,0,0,0,0,0,0,0,0,0,0,0,DJ22,0,0,0,0,0,0,0,~
0,0,0,0,0,0,0,0,0,0,0)';
      BIDIRECTIONAL='TRUE';
      INPUT_LOAD='(-0.01,0.01)';
      OUTPUT_LOAD='(1.0,-1.0)';
      PINUSE='BI';
    'ESPI_CLK2||AGPIO74':
      PIN_NUMBER='(0,0,0,0,0,0,0,0,0,0,0,0,0,0,0,0,0,0,0,0,0,DF27,0,0,0,0,0,0,0,~
0,0,0,0,0,0,0,0,0,0,0)';
      BIDIRECTIONAL='TRUE';
      INPUT_LOAD='(-0.01,0.01)';
      OUTPUT_LOAD='(1.0,-1.0)';
      PINUSE='BI';
    'ESPI_CLK1||SPI_CLK1||AGPIO75':
      PIN_NUMBER='(0,0,0,0,0,0,0,0,0,0,0,0,0,0,0,0,0,0,0,0,0,DG23,0,0,0,0,0,0,0,~
0,0,0,0,0,0,0,0,0,0,0)';
      BIDIRECTIONAL='TRUE';
      INPUT_LOAD='(-0.01,0.01)';
      OUTPUT_LOAD='(1.0,-1.0)';
      PINUSE='BI';
    'ESPI_RSTOUT_L||AGPIO23':
      PIN_NUMBER='(0,0,0,0,0,0,0,0,0,0,0,0,0,0,0,0,0,0,0,0,0,DE27,0,0,0,0,0,0,0,~
0,0,0,0,0,0,0,0,0,0,0)';
      BIDIRECTIONAL='TRUE';
      INPUT_LOAD='(-0.01,0.01)';
      OUTPUT_LOAD='(1.0,-1.0)';
      PINUSE='BI';
    'RSVD_BD62':
      PIN_NUMBER='(0,0,0,0,0,0,0,0,0,0,0,0,0,0,0,0,0,0,0,0,0,0,BD62,0,0,0,0,0,0,~
0,0,0,0,0,0,0,0,0,0,0)';
      OUTPUT_TYPE='(TS,TS)';
      INPUT_LOAD='(-0.01,0.01)';
      OUTPUT_LOAD='(1.0,-1.0)';
      PINUSE='TRI';
    'RSVD_D72':
      PIN_NUMBER='(0,0,0,0,0,0,0,0,0,0,0,0,0,0,0,0,0,0,0,0,0,0,D72,0,0,0,0,0,0,0~
,0,0,0,0,0,0,0,0,0,0)';
      OUTPUT_TYPE='(TS,TS)';
      INPUT_LOAD='(-0.01,0.01)';
      OUTPUT_LOAD='(1.0,-1.0)';
      PINUSE='TRI';
    'RSVD_C54':
      PIN_NUMBER='(0,0,0,0,0,0,0,0,0,0,0,0,0,0,0,0,0,0,0,0,0,0,C54,0,0,0,0,0,0,0~
,0,0,0,0,0,0,0,0,0,0)';
      OUTPUT_TYPE='(TS,TS)';
      INPUT_LOAD='(-0.01,0.01)';
      OUTPUT_LOAD='(1.0,-1.0)';
      PINUSE='TRI';
    'RSVD_BD65':
      PIN_NUMBER='(0,0,0,0,0,0,0,0,0,0,0,0,0,0,0,0,0,0,0,0,0,0,BD65,0,0,0,0,0,0,~
0,0,0,0,0,0,0,0,0,0,0)';
      OUTPUT_TYPE='(TS,TS)';
      INPUT_LOAD='(-0.01,0.01)';
      OUTPUT_LOAD='(1.0,-1.0)';
      PINUSE='TRI';
    'RSVD_E33':
      PIN_NUMBER='(0,0,0,0,0,0,0,0,0,0,0,0,0,0,0,0,0,0,0,0,0,0,E33,0,0,0,0,0,0,0~
,0,0,0,0,0,0,0,0,0,0)';
      OUTPUT_TYPE='(TS,TS)';
      INPUT_LOAD='(-0.01,0.01)';
      OUTPUT_LOAD='(1.0,-1.0)';
      PINUSE='TRI';
    'RSVD_D4':
      PIN_NUMBER='(0,0,0,0,0,0,0,0,0,0,0,0,0,0,0,0,0,0,0,0,0,0,D4,0,0,0,0,0,0,0,~
0,0,0,0,0,0,0,0,0,0)';
      OUTPUT_TYPE='(TS,TS)';
      INPUT_LOAD='(-0.01,0.01)';
      OUTPUT_LOAD='(1.0,-1.0)';
      PINUSE='TRI';
    'RSVD_A55':
      PIN_NUMBER='(0,0,0,0,0,0,0,0,0,0,0,0,0,0,0,0,0,0,0,0,0,0,A55,0,0,0,0,0,0,0~
,0,0,0,0,0,0,0,0,0,0)';
      OUTPUT_TYPE='(TS,TS)';
      INPUT_LOAD='(-0.01,0.01)';
      OUTPUT_LOAD='(1.0,-1.0)';
      PINUSE='TRI';
    'RSVD_BD69':
      PIN_NUMBER='(0,0,0,0,0,0,0,0,0,0,0,0,0,0,0,0,0,0,0,0,0,0,BD69,0,0,0,0,0,0,~
0,0,0,0,0,0,0,0,0,0,0)';
      OUTPUT_TYPE='(TS,TS)';
      INPUT_LOAD='(-0.01,0.01)';
      OUTPUT_LOAD='(1.0,-1.0)';
      PINUSE='TRI';
    'RSVD_E36':
      PIN_NUMBER='(0,0,0,0,0,0,0,0,0,0,0,0,0,0,0,0,0,0,0,0,0,0,E36,0,0,0,0,0,0,0~
,0,0,0,0,0,0,0,0,0,0)';
      OUTPUT_TYPE='(TS,TS)';
      INPUT_LOAD='(-0.01,0.01)';
      OUTPUT_LOAD='(1.0,-1.0)';
      PINUSE='TRI';
    'RSVD_D8':
      PIN_NUMBER='(0,0,0,0,0,0,0,0,0,0,0,0,0,0,0,0,0,0,0,0,0,0,D8,0,0,0,0,0,0,0,~
0,0,0,0,0,0,0,0,0,0)';
      OUTPUT_TYPE='(TS,TS)';
      INPUT_LOAD='(-0.01,0.01)';
      OUTPUT_LOAD='(1.0,-1.0)';
      PINUSE='TRI';
    'RSVD_A56':
      PIN_NUMBER='(0,0,0,0,0,0,0,0,0,0,0,0,0,0,0,0,0,0,0,0,0,0,A56,0,0,0,0,0,0,0~
,0,0,0,0,0,0,0,0,0,0)';
      OUTPUT_TYPE='(TS,TS)';
      INPUT_LOAD='(-0.01,0.01)';
      OUTPUT_LOAD='(1.0,-1.0)';
      PINUSE='TRI';
    'RSVD_BD72':
      PIN_NUMBER='(0,0,0,0,0,0,0,0,0,0,0,0,0,0,0,0,0,0,0,0,0,0,BD72,0,0,0,0,0,0,~
0,0,0,0,0,0,0,0,0,0,0)';
      OUTPUT_TYPE='(TS,TS)';
      INPUT_LOAD='(-0.01,0.01)';
      OUTPUT_LOAD='(1.0,-1.0)';
      PINUSE='TRI';
    'RSVD_BD4':
      PIN_NUMBER='(0,0,0,0,0,0,0,0,0,0,0,0,0,0,0,0,0,0,0,0,0,0,BD4,0,0,0,0,0,0,0~
,0,0,0,0,0,0,0,0,0,0)';
      OUTPUT_TYPE='(TS,TS)';
      INPUT_LOAD='(-0.01,0.01)';
      OUTPUT_LOAD='(1.0,-1.0)';
      PINUSE='TRI';
    'RSVD_D11':
      PIN_NUMBER='(0,0,0,0,0,0,0,0,0,0,0,0,0,0,0,0,0,0,0,0,0,0,D11,0,0,0,0,0,0,0~
,0,0,0,0,0,0,0,0,0,0)';
      OUTPUT_TYPE='(TS,TS)';
      INPUT_LOAD='(-0.01,0.01)';
      OUTPUT_LOAD='(1.0,-1.0)';
      PINUSE='TRI';
    'RSVD_A57':
      PIN_NUMBER='(0,0,0,0,0,0,0,0,0,0,0,0,0,0,0,0,0,0,0,0,0,0,A57,0,0,0,0,0,0,0~
,0,0,0,0,0,0,0,0,0,0)';
      OUTPUT_TYPE='(TS,TS)';
      INPUT_LOAD='(-0.01,0.01)';
      OUTPUT_LOAD='(1.0,-1.0)';
      PINUSE='TRI';
    'RSVD_DG17':
      PIN_NUMBER='(0,0,0,0,0,0,0,0,0,0,0,0,0,0,0,0,0,0,0,0,0,0,DG17,0,0,0,0,0,0,~
0,0,0,0,0,0,0,0,0,0,0)';
      OUTPUT_TYPE='(TS,TS)';
      INPUT_LOAD='(-0.01,0.01)';
      OUTPUT_LOAD='(1.0,-1.0)';
      PINUSE='TRI';
    'RSVD_D22':
      PIN_NUMBER='(0,0,0,0,0,0,0,0,0,0,0,0,0,0,0,0,0,0,0,0,0,0,D22,0,0,0,0,0,0,0~
,0,0,0,0,0,0,0,0,0,0)';
      OUTPUT_TYPE='(TS,TS)';
      INPUT_LOAD='(-0.01,0.01)';
      OUTPUT_LOAD='(1.0,-1.0)';
      PINUSE='TRI';
    'RSVD_A59':
      PIN_NUMBER='(0,0,0,0,0,0,0,0,0,0,0,0,0,0,0,0,0,0,0,0,0,0,A59,0,0,0,0,0,0,0~
,0,0,0,0,0,0,0,0,0,0)';
      OUTPUT_TYPE='(TS,TS)';
      INPUT_LOAD='(-0.01,0.01)';
      OUTPUT_LOAD='(1.0,-1.0)';
      PINUSE='TRI';
    'RSVD_DH17':
      PIN_NUMBER='(0,0,0,0,0,0,0,0,0,0,0,0,0,0,0,0,0,0,0,0,0,0,DH17,0,0,0,0,0,0,~
0,0,0,0,0,0,0,0,0,0,0)';
      OUTPUT_TYPE='(TS,TS)';
      INPUT_LOAD='(-0.01,0.01)';
      OUTPUT_LOAD='(1.0,-1.0)';
      PINUSE='TRI';
    'RSVD_BD11':
      PIN_NUMBER='(0,0,0,0,0,0,0,0,0,0,0,0,0,0,0,0,0,0,0,0,0,0,BD11,0,0,0,0,0,0,~
0,0,0,0,0,0,0,0,0,0,0)';
      OUTPUT_TYPE='(TS,TS)';
      INPUT_LOAD='(-0.01,0.01)';
      OUTPUT_LOAD='(1.0,-1.0)';
      PINUSE='TRI';
    'RSVD_D34':
      PIN_NUMBER='(0,0,0,0,0,0,0,0,0,0,0,0,0,0,0,0,0,0,0,0,0,0,D34,0,0,0,0,0,0,0~
,0,0,0,0,0,0,0,0,0,0)';
      OUTPUT_TYPE='(TS,TS)';
      INPUT_LOAD='(-0.01,0.01)';
      OUTPUT_LOAD='(1.0,-1.0)';
      PINUSE='TRI';
    'RSVD_A31':
      PIN_NUMBER='(0,0,0,0,0,0,0,0,0,0,0,0,0,0,0,0,0,0,0,0,0,0,A31,0,0,0,0,0,0,0~
,0,0,0,0,0,0,0,0,0,0)';
      OUTPUT_TYPE='(TS,TS)';
      INPUT_LOAD='(-0.01,0.01)';
      OUTPUT_LOAD='(1.0,-1.0)';
      PINUSE='TRI';
    'RSVD_DH21':
      PIN_NUMBER='(0,0,0,0,0,0,0,0,0,0,0,0,0,0,0,0,0,0,0,0,0,0,DH21,0,0,0,0,0,0,~
0,0,0,0,0,0,0,0,0,0,0)';
      OUTPUT_TYPE='(TS,TS)';
      INPUT_LOAD='(-0.01,0.01)';
      OUTPUT_LOAD='(1.0,-1.0)';
      PINUSE='TRI';
    'RSVD_BD14':
      PIN_NUMBER='(0,0,0,0,0,0,0,0,0,0,0,0,0,0,0,0,0,0,0,0,0,0,BD14,0,0,0,0,0,0,~
0,0,0,0,0,0,0,0,0,0,0)';
      OUTPUT_TYPE='(TS,TS)';
      INPUT_LOAD='(-0.01,0.01)';
      OUTPUT_LOAD='(1.0,-1.0)';
      PINUSE='TRI';
    'RSVD_B40':
      PIN_NUMBER='(0,0,0,0,0,0,0,0,0,0,0,0,0,0,0,0,0,0,0,0,0,0,B40,0,0,0,0,0,0,0~
,0,0,0,0,0,0,0,0,0,0)';
      OUTPUT_TYPE='(TS,TS)';
      INPUT_LOAD='(-0.01,0.01)';
      OUTPUT_LOAD='(1.0,-1.0)';
      PINUSE='TRI';
    'RSVD_A35':
      PIN_NUMBER='(0,0,0,0,0,0,0,0,0,0,0,0,0,0,0,0,0,0,0,0,0,0,A35,0,0,0,0,0,0,0~
,0,0,0,0,0,0,0,0,0,0)';
      OUTPUT_TYPE='(TS,TS)';
      INPUT_LOAD='(-0.01,0.01)';
      OUTPUT_LOAD='(1.0,-1.0)';
      PINUSE='TRI';
    'RSVD_DJ4':
      PIN_NUMBER='(0,0,0,0,0,0,0,0,0,0,0,0,0,0,0,0,0,0,0,0,0,0,DJ4,0,0,0,0,0,0,0~
,0,0,0,0,0,0,0,0,0,0)';
      OUTPUT_TYPE='(TS,TS)';
      INPUT_LOAD='(-0.01,0.01)';
      OUTPUT_LOAD='(1.0,-1.0)';
      PINUSE='TRI';
    'RSVD_BD18':
      PIN_NUMBER='(0,0,0,0,0,0,0,0,0,0,0,0,0,0,0,0,0,0,0,0,0,0,BD18,0,0,0,0,0,0,~
0,0,0,0,0,0,0,0,0,0,0)';
      OUTPUT_TYPE='(TS,TS)';
      INPUT_LOAD='(-0.01,0.01)';
      OUTPUT_LOAD='(1.0,-1.0)';
      PINUSE='TRI';
    'RSVD_D58':
      PIN_NUMBER='(0,0,0,0,0,0,0,0,0,0,0,0,0,0,0,0,0,0,0,0,0,0,D58,0,0,0,0,0,0,0~
,0,0,0,0,0,0,0,0,0,0)';
      OUTPUT_TYPE='(TS,TS)';
      INPUT_LOAD='(-0.01,0.01)';
      OUTPUT_LOAD='(1.0,-1.0)';
      PINUSE='TRI';
    'RSVD_C31':
      PIN_NUMBER='(0,0,0,0,0,0,0,0,0,0,0,0,0,0,0,0,0,0,0,0,0,0,C31,0,0,0,0,0,0,0~
,0,0,0,0,0,0,0,0,0,0)';
      OUTPUT_TYPE='(TS,TS)';
      INPUT_LOAD='(-0.01,0.01)';
      OUTPUT_LOAD='(1.0,-1.0)';
      PINUSE='TRI';
    'RSVD_A41':
      PIN_NUMBER='(0,0,0,0,0,0,0,0,0,0,0,0,0,0,0,0,0,0,0,0,0,0,A41,0,0,0,0,0,0,0~
,0,0,0,0,0,0,0,0,0,0)';
      OUTPUT_TYPE='(TS,TS)';
      INPUT_LOAD='(-0.01,0.01)';
      OUTPUT_LOAD='(1.0,-1.0)';
      PINUSE='TRI';
    'RSVD_BD21':
      PIN_NUMBER='(0,0,0,0,0,0,0,0,0,0,0,0,0,0,0,0,0,0,0,0,0,0,BD21,0,0,0,0,0,0,~
0,0,0,0,0,0,0,0,0,0,0)';
      OUTPUT_TYPE='(TS,TS)';
      INPUT_LOAD='(-0.01,0.01)';
      OUTPUT_LOAD='(1.0,-1.0)';
      PINUSE='TRI';
    'RSVD_D62':
      PIN_NUMBER='(0,0,0,0,0,0,0,0,0,0,0,0,0,0,0,0,0,0,0,0,0,0,D62,0,0,0,0,0,0,0~
,0,0,0,0,0,0,0,0,0,0)';
      OUTPUT_TYPE='(TS,TS)';
      INPUT_LOAD='(-0.01,0.01)';
      OUTPUT_LOAD='(1.0,-1.0)';
      PINUSE='TRI';
    'RSVD_C34':
      PIN_NUMBER='(0,0,0,0,0,0,0,0,0,0,0,0,0,0,0,0,0,0,0,0,0,0,C34,0,0,0,0,0,0,0~
,0,0,0,0,0,0,0,0,0,0)';
      OUTPUT_TYPE='(TS,TS)';
      INPUT_LOAD='(-0.01,0.01)';
      OUTPUT_LOAD='(1.0,-1.0)';
      PINUSE='TRI';
    'RSVD_A42':
      PIN_NUMBER='(0,0,0,0,0,0,0,0,0,0,0,0,0,0,0,0,0,0,0,0,0,0,A42,0,0,0,0,0,0,0~
,0,0,0,0,0,0,0,0,0,0)';
      OUTPUT_TYPE='(TS,TS)';
      INPUT_LOAD='(-0.01,0.01)';
      OUTPUT_LOAD='(1.0,-1.0)';
      PINUSE='TRI';
    'RSVD_D65':
      PIN_NUMBER='(0,0,0,0,0,0,0,0,0,0,0,0,0,0,0,0,0,0,0,0,0,0,D65,0,0,0,0,0,0,0~
,0,0,0,0,0,0,0,0,0,0)';
      OUTPUT_TYPE='(TS,TS)';
      INPUT_LOAD='(-0.01,0.01)';
      OUTPUT_LOAD='(1.0,-1.0)';
      PINUSE='TRI';
    'RSVD_C35':
      PIN_NUMBER='(0,0,0,0,0,0,0,0,0,0,0,0,0,0,0,0,0,0,0,0,0,0,C35,0,0,0,0,0,0,0~
,0,0,0,0,0,0,0,0,0,0)';
      OUTPUT_TYPE='(TS,TS)';
      INPUT_LOAD='(-0.01,0.01)';
      OUTPUT_LOAD='(1.0,-1.0)';
      PINUSE='TRI';
    'RSVD_A45':
      PIN_NUMBER='(0,0,0,0,0,0,0,0,0,0,0,0,0,0,0,0,0,0,0,0,0,0,A45,0,0,0,0,0,0,0~
,0,0,0,0,0,0,0,0,0,0)';
      OUTPUT_TYPE='(TS,TS)';
      INPUT_LOAD='(-0.01,0.01)';
      OUTPUT_LOAD='(1.0,-1.0)';
      PINUSE='TRI';
    'RSVD_C53':
      PIN_NUMBER='(0,0,0,0,0,0,0,0,0,0,0,0,0,0,0,0,0,0,0,0,0,0,C53,0,0,0,0,0,0,0~
,0,0,0,0,0,0,0,0,0,0)';
      OUTPUT_TYPE='(TS,TS)';
      INPUT_LOAD='(-0.01,0.01)';
      OUTPUT_LOAD='(1.0,-1.0)';
      PINUSE='TRI';
    'RSVD_A48':
      PIN_NUMBER='(0,0,0,0,0,0,0,0,0,0,0,0,0,0,0,0,0,0,0,0,0,0,A48,0,0,0,0,0,0,0~
,0,0,0,0,0,0,0,0,0,0)';
      OUTPUT_TYPE='(TS,TS)';
      INPUT_LOAD='(-0.01,0.01)';
      OUTPUT_LOAD='(1.0,-1.0)';
      PINUSE='TRI';
    'RSVD_A50':
      PIN_NUMBER='(0,0,0,0,0,0,0,0,0,0,0,0,0,0,0,0,0,0,0,0,0,0,A50,0,0,0,0,0,0,0~
,0,0,0,0,0,0,0,0,0,0)';
      OUTPUT_TYPE='(TS,TS)';
      INPUT_LOAD='(-0.01,0.01)';
      OUTPUT_LOAD='(1.0,-1.0)';
      PINUSE='TRI';
    'RSVD_A51':
      PIN_NUMBER='(0,0,0,0,0,0,0,0,0,0,0,0,0,0,0,0,0,0,0,0,0,0,A51,0,0,0,0,0,0,0~
,0,0,0,0,0,0,0,0,0,0)';
      OUTPUT_TYPE='(TS,TS)';
      INPUT_LOAD='(-0.01,0.01)';
      OUTPUT_LOAD='(1.0,-1.0)';
      PINUSE='TRI';
    'RSVD_A54':
      PIN_NUMBER='(0,0,0,0,0,0,0,0,0,0,0,0,0,0,0,0,0,0,0,0,0,0,A54,0,0,0,0,0,0,0~
,0,0,0,0,0,0,0,0,0,0)';
      OUTPUT_TYPE='(TS,TS)';
      INPUT_LOAD='(-0.01,0.01)';
      OUTPUT_LOAD='(1.0,-1.0)';
      PINUSE='TRI';
    'RSVD_BD55':
      PIN_NUMBER='(0,0,0,0,0,0,0,0,0,0,0,0,0,0,0,0,0,0,0,0,0,0,BD55,0,0,0,0,0,0,~
0,0,0,0,0,0,0,0,0,0,0)';
      OUTPUT_TYPE='(TS,TS)';
      INPUT_LOAD='(-0.01,0.01)';
      OUTPUT_LOAD='(1.0,-1.0)';
      PINUSE='TRI';
    'RSVD_BD58':
      PIN_NUMBER='(0,0,0,0,0,0,0,0,0,0,0,0,0,0,0,0,0,0,0,0,0,0,BD58,0,0,0,0,0,0,~
0,0,0,0,0,0,0,0,0,0,0)';
      OUTPUT_TYPE='(TS,TS)';
      INPUT_LOAD='(-0.01,0.01)';
      OUTPUT_LOAD='(1.0,-1.0)';
      PINUSE='TRI';
    'RSVD_D36':
      PIN_NUMBER='(0,0,0,0,0,0,0,0,0,0,0,0,0,0,0,0,0,0,0,0,0,0,D36,0,0,0,0,0,0,0~
,0,0,0,0,0,0,0,0,0,0)';
      OUTPUT_TYPE='(TS,TS)';
      INPUT_LOAD='(-0.01,0.01)';
      OUTPUT_LOAD='(1.0,-1.0)';
      PINUSE='TRI';
    'RSVD_BD7':
      PIN_NUMBER='(0,0,0,0,0,0,0,0,0,0,0,0,0,0,0,0,0,0,0,0,0,0,BD7,0,0,0,0,0,0,0~
,0,0,0,0,0,0,0,0,0,0)';
      OUTPUT_TYPE='(TS,TS)';
      INPUT_LOAD='(-0.01,0.01)';
      OUTPUT_LOAD='(1.0,-1.0)';
      PINUSE='TRI';
    'RSVD_A60':
      PIN_NUMBER='(0,0,0,0,0,0,0,0,0,0,0,0,0,0,0,0,0,0,0,0,0,0,A60,0,0,0,0,0,0,0~
,0,0,0,0,0,0,0,0,0,0)';
      OUTPUT_TYPE='(TS,TS)';
      INPUT_LOAD='(-0.01,0.01)';
      OUTPUT_LOAD='(1.0,-1.0)';
      PINUSE='TRI';
    'TEST6_X3D7':
      PIN_NUMBER='(0,0,0,0,0,0,0,0,0,0,0,0,0,0,0,0,0,0,0,0,0,0,DJ57,0,0,0,0,0,0,~
0,0,0,0,0,0,0,0,0,0,0)';
      OUTPUT_LOAD='(1.0,-1.0)';
      PINUSE='OUT';
    'TEST5_CCD13':
      PIN_NUMBER='(0,0,0,0,0,0,0,0,0,0,0,0,0,0,0,0,0,0,0,0,0,0,DH14,0,0,0,0,0,0,~
0,0,0,0,0,0,0,0,0,0,0)';
      OUTPUT_TYPE='(TS,TS)';
      INPUT_LOAD='(-0.01,0.01)';
      OUTPUT_LOAD='(1.0,-1.0)';
      PINUSE='TRI';
    'TEST4_CCD13':
      PIN_NUMBER='(0,0,0,0,0,0,0,0,0,0,0,0,0,0,0,0,0,0,0,0,0,0,DH13,0,0,0,0,0,0,~
0,0,0,0,0,0,0,0,0,0,0)';
      OUTPUT_TYPE='(TS,TS)';
      INPUT_LOAD='(-0.01,0.01)';
      OUTPUT_LOAD='(1.0,-1.0)';
      PINUSE='TRI';
    'TEST5_CCD14':
      PIN_NUMBER='(0,0,0,0,0,0,0,0,0,0,0,0,0,0,0,0,0,0,0,0,0,0,DG42,0,0,0,0,0,0,~
0,0,0,0,0,0,0,0,0,0,0)';
      OUTPUT_TYPE='(TS,TS)';
      INPUT_LOAD='(-0.01,0.01)';
      OUTPUT_LOAD='(1.0,-1.0)';
      PINUSE='TRI';
    'TEST4_CCD14':
      PIN_NUMBER='(0,0,0,0,0,0,0,0,0,0,0,0,0,0,0,0,0,0,0,0,0,0,DF41,0,0,0,0,0,0,~
0,0,0,0,0,0,0,0,0,0,0)';
      OUTPUT_TYPE='(TS,TS)';
      INPUT_LOAD='(-0.01,0.01)';
      OUTPUT_LOAD='(1.0,-1.0)';
      PINUSE='TRI';
    'TEST5_CCD15':
      PIN_NUMBER='(0,0,0,0,0,0,0,0,0,0,0,0,0,0,0,0,0,0,0,0,0,0,D23,0,0,0,0,0,0,0~
,0,0,0,0,0,0,0,0,0,0)';
      OUTPUT_TYPE='(TS,TS)';
      INPUT_LOAD='(-0.01,0.01)';
      OUTPUT_LOAD='(1.0,-1.0)';
      PINUSE='TRI';
    'TEST5_CCD12':
      PIN_NUMBER='(0,0,0,0,0,0,0,0,0,0,0,0,0,0,0,0,0,0,0,0,0,0,C59,0,0,0,0,0,0,0~
,0,0,0,0,0,0,0,0,0,0)';
      OUTPUT_TYPE='(TS,TS)';
      INPUT_LOAD='(-0.01,0.01)';
      OUTPUT_LOAD='(1.0,-1.0)';
      PINUSE='TRI';
    'TEST4_CCD12':
      PIN_NUMBER='(0,0,0,0,0,0,0,0,0,0,0,0,0,0,0,0,0,0,0,0,0,0,C58,0,0,0,0,0,0,0~
,0,0,0,0,0,0,0,0,0,0)';
      OUTPUT_TYPE='(TS,TS)';
      INPUT_LOAD='(-0.01,0.01)';
      OUTPUT_LOAD='(1.0,-1.0)';
      PINUSE='TRI';
    'TEST4_CCD15':
      PIN_NUMBER='(0,0,0,0,0,0,0,0,0,0,0,0,0,0,0,0,0,0,0,0,0,0,C23,0,0,0,0,0,0,0~
,0,0,0,0,0,0,0,0,0,0)';
      OUTPUT_TYPE='(TS,TS)';
      INPUT_LOAD='(-0.01,0.01)';
      OUTPUT_LOAD='(1.0,-1.0)';
      PINUSE='TRI';
    'TEST6_X3D6':
      PIN_NUMBER='(0,0,0,0,0,0,0,0,0,0,0,0,0,0,0,0,0,0,0,0,0,0,B36,0,0,0,0,0,0,0~
,0,0,0,0,0,0,0,0,0,0)';
      OUTPUT_LOAD='(1.0,-1.0)';
      PINUSE='OUT';
    'VDDCR_CPU0_W47':
      PIN_NUMBER='(0,0,0,0,0,0,0,0,0,0,0,0,0,0,0,0,0,0,0,0,0,0,0,W47,0,0,0,0,0,0~
,0,0,0,0,0,0,0,0,0,0)';
      PINUSE='POWER';
      NO_LOAD_CHECK='Both';
      NO_IO_CHECK='Both';
      NO_ASSERT_CHECK='TRUE';
      NO_DIR_CHECK='TRUE';
      ALLOW_CONNECT='TRUE';
    'VDDCR_CPU0_W46':
      PIN_NUMBER='(0,0,0,0,0,0,0,0,0,0,0,0,0,0,0,0,0,0,0,0,0,0,0,W46,0,0,0,0,0,0~
,0,0,0,0,0,0,0,0,0,0)';
      PINUSE='POWER';
      NO_LOAD_CHECK='Both';
      NO_IO_CHECK='Both';
      NO_ASSERT_CHECK='TRUE';
      NO_DIR_CHECK='TRUE';
      ALLOW_CONNECT='TRUE';
    'VDDCR_CPU0_W44':
      PIN_NUMBER='(0,0,0,0,0,0,0,0,0,0,0,0,0,0,0,0,0,0,0,0,0,0,0,W44,0,0,0,0,0,0~
,0,0,0,0,0,0,0,0,0,0)';
      PINUSE='POWER';
      NO_LOAD_CHECK='Both';
      NO_IO_CHECK='Both';
      NO_ASSERT_CHECK='TRUE';
      NO_DIR_CHECK='TRUE';
      ALLOW_CONNECT='TRUE';
    'VDDCR_CPU0_W43':
      PIN_NUMBER='(0,0,0,0,0,0,0,0,0,0,0,0,0,0,0,0,0,0,0,0,0,0,0,W43,0,0,0,0,0,0~
,0,0,0,0,0,0,0,0,0,0)';
      PINUSE='POWER';
      NO_LOAD_CHECK='Both';
      NO_IO_CHECK='Both';
      NO_ASSERT_CHECK='TRUE';
      NO_DIR_CHECK='TRUE';
      ALLOW_CONNECT='TRUE';
    'VDDCR_CPU0_W33':
      PIN_NUMBER='(0,0,0,0,0,0,0,0,0,0,0,0,0,0,0,0,0,0,0,0,0,0,0,W33,0,0,0,0,0,0~
,0,0,0,0,0,0,0,0,0,0)';
      PINUSE='POWER';
      NO_LOAD_CHECK='Both';
      NO_IO_CHECK='Both';
      NO_ASSERT_CHECK='TRUE';
      NO_DIR_CHECK='TRUE';
      ALLOW_CONNECT='TRUE';
    'VDDCR_CPU0_W32':
      PIN_NUMBER='(0,0,0,0,0,0,0,0,0,0,0,0,0,0,0,0,0,0,0,0,0,0,0,W32,0,0,0,0,0,0~
,0,0,0,0,0,0,0,0,0,0)';
      PINUSE='POWER';
      NO_LOAD_CHECK='Both';
      NO_IO_CHECK='Both';
      NO_ASSERT_CHECK='TRUE';
      NO_DIR_CHECK='TRUE';
      ALLOW_CONNECT='TRUE';
    'VDDCR_CPU0_W30':
      PIN_NUMBER='(0,0,0,0,0,0,0,0,0,0,0,0,0,0,0,0,0,0,0,0,0,0,0,W30,0,0,0,0,0,0~
,0,0,0,0,0,0,0,0,0,0)';
      PINUSE='POWER';
      NO_LOAD_CHECK='Both';
      NO_IO_CHECK='Both';
      NO_ASSERT_CHECK='TRUE';
      NO_DIR_CHECK='TRUE';
      ALLOW_CONNECT='TRUE';
    'VDDCR_CPU0_W29':
      PIN_NUMBER='(0,0,0,0,0,0,0,0,0,0,0,0,0,0,0,0,0,0,0,0,0,0,0,W29,0,0,0,0,0,0~
,0,0,0,0,0,0,0,0,0,0)';
      PINUSE='POWER';
      NO_LOAD_CHECK='Both';
      NO_IO_CHECK='Both';
      NO_ASSERT_CHECK='TRUE';
      NO_DIR_CHECK='TRUE';
      ALLOW_CONNECT='TRUE';
    'VDDCR_CPU0_U41':
      PIN_NUMBER='(0,0,0,0,0,0,0,0,0,0,0,0,0,0,0,0,0,0,0,0,0,0,0,U41,0,0,0,0,0,0~
,0,0,0,0,0,0,0,0,0,0)';
      PINUSE='POWER';
      NO_LOAD_CHECK='Both';
      NO_IO_CHECK='Both';
      NO_ASSERT_CHECK='TRUE';
      NO_DIR_CHECK='TRUE';
      ALLOW_CONNECT='TRUE';
    'VDDCR_CPU0_U40':
      PIN_NUMBER='(0,0,0,0,0,0,0,0,0,0,0,0,0,0,0,0,0,0,0,0,0,0,0,U40,0,0,0,0,0,0~
,0,0,0,0,0,0,0,0,0,0)';
      PINUSE='POWER';
      NO_LOAD_CHECK='Both';
      NO_IO_CHECK='Both';
      NO_ASSERT_CHECK='TRUE';
      NO_DIR_CHECK='TRUE';
      ALLOW_CONNECT='TRUE';
    'VDDCR_CPU0_U36':
      PIN_NUMBER='(0,0,0,0,0,0,0,0,0,0,0,0,0,0,0,0,0,0,0,0,0,0,0,U36,0,0,0,0,0,0~
,0,0,0,0,0,0,0,0,0,0)';
      PINUSE='POWER';
      NO_LOAD_CHECK='Both';
      NO_IO_CHECK='Both';
      NO_ASSERT_CHECK='TRUE';
      NO_DIR_CHECK='TRUE';
      ALLOW_CONNECT='TRUE';
    'VDDCR_CPU0_U35':
      PIN_NUMBER='(0,0,0,0,0,0,0,0,0,0,0,0,0,0,0,0,0,0,0,0,0,0,0,U35,0,0,0,0,0,0~
,0,0,0,0,0,0,0,0,0,0)';
      PINUSE='POWER';
      NO_LOAD_CHECK='Both';
      NO_IO_CHECK='Both';
      NO_ASSERT_CHECK='TRUE';
      NO_DIR_CHECK='TRUE';
      ALLOW_CONNECT='TRUE';
    'VDDCR_CPU0_T53':
      PIN_NUMBER='(0,0,0,0,0,0,0,0,0,0,0,0,0,0,0,0,0,0,0,0,0,0,0,T53,0,0,0,0,0,0~
,0,0,0,0,0,0,0,0,0,0)';
      PINUSE='POWER';
      NO_LOAD_CHECK='Both';
      NO_IO_CHECK='Both';
      NO_ASSERT_CHECK='TRUE';
      NO_DIR_CHECK='TRUE';
      ALLOW_CONNECT='TRUE';
    'VDDCR_CPU0_T52':
      PIN_NUMBER='(0,0,0,0,0,0,0,0,0,0,0,0,0,0,0,0,0,0,0,0,0,0,0,T52,0,0,0,0,0,0~
,0,0,0,0,0,0,0,0,0,0)';
      PINUSE='POWER';
      NO_LOAD_CHECK='Both';
      NO_IO_CHECK='Both';
      NO_ASSERT_CHECK='TRUE';
      NO_DIR_CHECK='TRUE';
      ALLOW_CONNECT='TRUE';
    'VDDCR_CPU0_T50':
      PIN_NUMBER='(0,0,0,0,0,0,0,0,0,0,0,0,0,0,0,0,0,0,0,0,0,0,0,T50,0,0,0,0,0,0~
,0,0,0,0,0,0,0,0,0,0)';
      PINUSE='POWER';
      NO_LOAD_CHECK='Both';
      NO_IO_CHECK='Both';
      NO_ASSERT_CHECK='TRUE';
      NO_DIR_CHECK='TRUE';
      ALLOW_CONNECT='TRUE';
    'VDDCR_CPU0_T49':
      PIN_NUMBER='(0,0,0,0,0,0,0,0,0,0,0,0,0,0,0,0,0,0,0,0,0,0,0,T49,0,0,0,0,0,0~
,0,0,0,0,0,0,0,0,0,0)';
      PINUSE='POWER';
      NO_LOAD_CHECK='Both';
      NO_IO_CHECK='Both';
      NO_ASSERT_CHECK='TRUE';
      NO_DIR_CHECK='TRUE';
      ALLOW_CONNECT='TRUE';
    'VDDCR_CPU0_T47':
      PIN_NUMBER='(0,0,0,0,0,0,0,0,0,0,0,0,0,0,0,0,0,0,0,0,0,0,0,T47,0,0,0,0,0,0~
,0,0,0,0,0,0,0,0,0,0)';
      PINUSE='POWER';
      NO_LOAD_CHECK='Both';
      NO_IO_CHECK='Both';
      NO_ASSERT_CHECK='TRUE';
      NO_DIR_CHECK='TRUE';
      ALLOW_CONNECT='TRUE';
    'VDDCR_CPU0_T46':
      PIN_NUMBER='(0,0,0,0,0,0,0,0,0,0,0,0,0,0,0,0,0,0,0,0,0,0,0,T46,0,0,0,0,0,0~
,0,0,0,0,0,0,0,0,0,0)';
      PINUSE='POWER';
      NO_LOAD_CHECK='Both';
      NO_IO_CHECK='Both';
      NO_ASSERT_CHECK='TRUE';
      NO_DIR_CHECK='TRUE';
      ALLOW_CONNECT='TRUE';
    'VDDCR_CPU0_T44':
      PIN_NUMBER='(0,0,0,0,0,0,0,0,0,0,0,0,0,0,0,0,0,0,0,0,0,0,0,T44,0,0,0,0,0,0~
,0,0,0,0,0,0,0,0,0,0)';
      PINUSE='POWER';
      NO_LOAD_CHECK='Both';
      NO_IO_CHECK='Both';
      NO_ASSERT_CHECK='TRUE';
      NO_DIR_CHECK='TRUE';
      ALLOW_CONNECT='TRUE';
    'VDDCR_CPU0_T43':
      PIN_NUMBER='(0,0,0,0,0,0,0,0,0,0,0,0,0,0,0,0,0,0,0,0,0,0,0,T43,0,0,0,0,0,0~
,0,0,0,0,0,0,0,0,0,0)';
      PINUSE='POWER';
      NO_LOAD_CHECK='Both';
      NO_IO_CHECK='Both';
      NO_ASSERT_CHECK='TRUE';
      NO_DIR_CHECK='TRUE';
      ALLOW_CONNECT='TRUE';
    'VDDCR_CPU0_T33':
      PIN_NUMBER='(0,0,0,0,0,0,0,0,0,0,0,0,0,0,0,0,0,0,0,0,0,0,0,T33,0,0,0,0,0,0~
,0,0,0,0,0,0,0,0,0,0)';
      PINUSE='POWER';
      NO_LOAD_CHECK='Both';
      NO_IO_CHECK='Both';
      NO_ASSERT_CHECK='TRUE';
      NO_DIR_CHECK='TRUE';
      ALLOW_CONNECT='TRUE';
    'VDDCR_CPU0_T32':
      PIN_NUMBER='(0,0,0,0,0,0,0,0,0,0,0,0,0,0,0,0,0,0,0,0,0,0,0,T32,0,0,0,0,0,0~
,0,0,0,0,0,0,0,0,0,0)';
      PINUSE='POWER';
      NO_LOAD_CHECK='Both';
      NO_IO_CHECK='Both';
      NO_ASSERT_CHECK='TRUE';
      NO_DIR_CHECK='TRUE';
      ALLOW_CONNECT='TRUE';
    'VDDCR_CPU0_T30':
      PIN_NUMBER='(0,0,0,0,0,0,0,0,0,0,0,0,0,0,0,0,0,0,0,0,0,0,0,T30,0,0,0,0,0,0~
,0,0,0,0,0,0,0,0,0,0)';
      PINUSE='POWER';
      NO_LOAD_CHECK='Both';
      NO_IO_CHECK='Both';
      NO_ASSERT_CHECK='TRUE';
      NO_DIR_CHECK='TRUE';
      ALLOW_CONNECT='TRUE';
    'VDDCR_CPU0_T29':
      PIN_NUMBER='(0,0,0,0,0,0,0,0,0,0,0,0,0,0,0,0,0,0,0,0,0,0,0,T29,0,0,0,0,0,0~
,0,0,0,0,0,0,0,0,0,0)';
      PINUSE='POWER';
      NO_LOAD_CHECK='Both';
      NO_IO_CHECK='Both';
      NO_ASSERT_CHECK='TRUE';
      NO_DIR_CHECK='TRUE';
      ALLOW_CONNECT='TRUE';
    'VDDCR_CPU0_T27':
      PIN_NUMBER='(0,0,0,0,0,0,0,0,0,0,0,0,0,0,0,0,0,0,0,0,0,0,0,T27,0,0,0,0,0,0~
,0,0,0,0,0,0,0,0,0,0)';
      PINUSE='POWER';
      NO_LOAD_CHECK='Both';
      NO_IO_CHECK='Both';
      NO_ASSERT_CHECK='TRUE';
      NO_DIR_CHECK='TRUE';
      ALLOW_CONNECT='TRUE';
    'VDDCR_CPU0_T26':
      PIN_NUMBER='(0,0,0,0,0,0,0,0,0,0,0,0,0,0,0,0,0,0,0,0,0,0,0,T26,0,0,0,0,0,0~
,0,0,0,0,0,0,0,0,0,0)';
      PINUSE='POWER';
      NO_LOAD_CHECK='Both';
      NO_IO_CHECK='Both';
      NO_ASSERT_CHECK='TRUE';
      NO_DIR_CHECK='TRUE';
      ALLOW_CONNECT='TRUE';
    'VDDCR_CPU0_T24':
      PIN_NUMBER='(0,0,0,0,0,0,0,0,0,0,0,0,0,0,0,0,0,0,0,0,0,0,0,T24,0,0,0,0,0,0~
,0,0,0,0,0,0,0,0,0,0)';
      PINUSE='POWER';
      NO_LOAD_CHECK='Both';
      NO_IO_CHECK='Both';
      NO_ASSERT_CHECK='TRUE';
      NO_DIR_CHECK='TRUE';
      ALLOW_CONNECT='TRUE';
    'VDDCR_CPU0_T23':
      PIN_NUMBER='(0,0,0,0,0,0,0,0,0,0,0,0,0,0,0,0,0,0,0,0,0,0,0,T23,0,0,0,0,0,0~
,0,0,0,0,0,0,0,0,0,0)';
      PINUSE='POWER';
      NO_LOAD_CHECK='Both';
      NO_IO_CHECK='Both';
      NO_ASSERT_CHECK='TRUE';
      NO_DIR_CHECK='TRUE';
      ALLOW_CONNECT='TRUE';
    'VDDCR_CPU0_N41':
      PIN_NUMBER='(0,0,0,0,0,0,0,0,0,0,0,0,0,0,0,0,0,0,0,0,0,0,0,N41,0,0,0,0,0,0~
,0,0,0,0,0,0,0,0,0,0)';
      PINUSE='POWER';
      NO_LOAD_CHECK='Both';
      NO_IO_CHECK='Both';
      NO_ASSERT_CHECK='TRUE';
      NO_DIR_CHECK='TRUE';
      ALLOW_CONNECT='TRUE';
    'VDDCR_CPU0_N40':
      PIN_NUMBER='(0,0,0,0,0,0,0,0,0,0,0,0,0,0,0,0,0,0,0,0,0,0,0,N40,0,0,0,0,0,0~
,0,0,0,0,0,0,0,0,0,0)';
      PINUSE='POWER';
      NO_LOAD_CHECK='Both';
      NO_IO_CHECK='Both';
      NO_ASSERT_CHECK='TRUE';
      NO_DIR_CHECK='TRUE';
      ALLOW_CONNECT='TRUE';
    'VDDCR_CPU0_N36':
      PIN_NUMBER='(0,0,0,0,0,0,0,0,0,0,0,0,0,0,0,0,0,0,0,0,0,0,0,N36,0,0,0,0,0,0~
,0,0,0,0,0,0,0,0,0,0)';
      PINUSE='POWER';
      NO_LOAD_CHECK='Both';
      NO_IO_CHECK='Both';
      NO_ASSERT_CHECK='TRUE';
      NO_DIR_CHECK='TRUE';
      ALLOW_CONNECT='TRUE';
    'VDDCR_CPU0_N35':
      PIN_NUMBER='(0,0,0,0,0,0,0,0,0,0,0,0,0,0,0,0,0,0,0,0,0,0,0,N35,0,0,0,0,0,0~
,0,0,0,0,0,0,0,0,0,0)';
      PINUSE='POWER';
      NO_LOAD_CHECK='Both';
      NO_IO_CHECK='Both';
      NO_ASSERT_CHECK='TRUE';
      NO_DIR_CHECK='TRUE';
      ALLOW_CONNECT='TRUE';
    'VDDCR_CPU0_M53':
      PIN_NUMBER='(0,0,0,0,0,0,0,0,0,0,0,0,0,0,0,0,0,0,0,0,0,0,0,M53,0,0,0,0,0,0~
,0,0,0,0,0,0,0,0,0,0)';
      PINUSE='POWER';
      NO_LOAD_CHECK='Both';
      NO_IO_CHECK='Both';
      NO_ASSERT_CHECK='TRUE';
      NO_DIR_CHECK='TRUE';
      ALLOW_CONNECT='TRUE';
    'VDDCR_CPU0_M52':
      PIN_NUMBER='(0,0,0,0,0,0,0,0,0,0,0,0,0,0,0,0,0,0,0,0,0,0,0,M52,0,0,0,0,0,0~
,0,0,0,0,0,0,0,0,0,0)';
      PINUSE='POWER';
      NO_LOAD_CHECK='Both';
      NO_IO_CHECK='Both';
      NO_ASSERT_CHECK='TRUE';
      NO_DIR_CHECK='TRUE';
      ALLOW_CONNECT='TRUE';
    'VDDCR_CPU0_M50':
      PIN_NUMBER='(0,0,0,0,0,0,0,0,0,0,0,0,0,0,0,0,0,0,0,0,0,0,0,M50,0,0,0,0,0,0~
,0,0,0,0,0,0,0,0,0,0)';
      PINUSE='POWER';
      NO_LOAD_CHECK='Both';
      NO_IO_CHECK='Both';
      NO_ASSERT_CHECK='TRUE';
      NO_DIR_CHECK='TRUE';
      ALLOW_CONNECT='TRUE';
    'VDDCR_CPU0_M49':
      PIN_NUMBER='(0,0,0,0,0,0,0,0,0,0,0,0,0,0,0,0,0,0,0,0,0,0,0,M49,0,0,0,0,0,0~
,0,0,0,0,0,0,0,0,0,0)';
      PINUSE='POWER';
      NO_LOAD_CHECK='Both';
      NO_IO_CHECK='Both';
      NO_ASSERT_CHECK='TRUE';
      NO_DIR_CHECK='TRUE';
      ALLOW_CONNECT='TRUE';
    'VDDCR_CPU0_M47':
      PIN_NUMBER='(0,0,0,0,0,0,0,0,0,0,0,0,0,0,0,0,0,0,0,0,0,0,0,M47,0,0,0,0,0,0~
,0,0,0,0,0,0,0,0,0,0)';
      PINUSE='POWER';
      NO_LOAD_CHECK='Both';
      NO_IO_CHECK='Both';
      NO_ASSERT_CHECK='TRUE';
      NO_DIR_CHECK='TRUE';
      ALLOW_CONNECT='TRUE';
    'VDDCR_CPU0_M46':
      PIN_NUMBER='(0,0,0,0,0,0,0,0,0,0,0,0,0,0,0,0,0,0,0,0,0,0,0,M46,0,0,0,0,0,0~
,0,0,0,0,0,0,0,0,0,0)';
      PINUSE='POWER';
      NO_LOAD_CHECK='Both';
      NO_IO_CHECK='Both';
      NO_ASSERT_CHECK='TRUE';
      NO_DIR_CHECK='TRUE';
      ALLOW_CONNECT='TRUE';
    'VDDCR_CPU0_M44':
      PIN_NUMBER='(0,0,0,0,0,0,0,0,0,0,0,0,0,0,0,0,0,0,0,0,0,0,0,M44,0,0,0,0,0,0~
,0,0,0,0,0,0,0,0,0,0)';
      PINUSE='POWER';
      NO_LOAD_CHECK='Both';
      NO_IO_CHECK='Both';
      NO_ASSERT_CHECK='TRUE';
      NO_DIR_CHECK='TRUE';
      ALLOW_CONNECT='TRUE';
    'VDDCR_CPU0_M43':
      PIN_NUMBER='(0,0,0,0,0,0,0,0,0,0,0,0,0,0,0,0,0,0,0,0,0,0,0,M43,0,0,0,0,0,0~
,0,0,0,0,0,0,0,0,0,0)';
      PINUSE='POWER';
      NO_LOAD_CHECK='Both';
      NO_IO_CHECK='Both';
      NO_ASSERT_CHECK='TRUE';
      NO_DIR_CHECK='TRUE';
      ALLOW_CONNECT='TRUE';
    'VDDCR_CPU0_M33':
      PIN_NUMBER='(0,0,0,0,0,0,0,0,0,0,0,0,0,0,0,0,0,0,0,0,0,0,0,M33,0,0,0,0,0,0~
,0,0,0,0,0,0,0,0,0,0)';
      PINUSE='POWER';
      NO_LOAD_CHECK='Both';
      NO_IO_CHECK='Both';
      NO_ASSERT_CHECK='TRUE';
      NO_DIR_CHECK='TRUE';
      ALLOW_CONNECT='TRUE';
    'VDDCR_CPU0_M32':
      PIN_NUMBER='(0,0,0,0,0,0,0,0,0,0,0,0,0,0,0,0,0,0,0,0,0,0,0,M32,0,0,0,0,0,0~
,0,0,0,0,0,0,0,0,0,0)';
      PINUSE='POWER';
      NO_LOAD_CHECK='Both';
      NO_IO_CHECK='Both';
      NO_ASSERT_CHECK='TRUE';
      NO_DIR_CHECK='TRUE';
      ALLOW_CONNECT='TRUE';
    'VDDCR_CPU0_M30':
      PIN_NUMBER='(0,0,0,0,0,0,0,0,0,0,0,0,0,0,0,0,0,0,0,0,0,0,0,M30,0,0,0,0,0,0~
,0,0,0,0,0,0,0,0,0,0)';
      PINUSE='POWER';
      NO_LOAD_CHECK='Both';
      NO_IO_CHECK='Both';
      NO_ASSERT_CHECK='TRUE';
      NO_DIR_CHECK='TRUE';
      ALLOW_CONNECT='TRUE';
    'VDDCR_CPU0_M29':
      PIN_NUMBER='(0,0,0,0,0,0,0,0,0,0,0,0,0,0,0,0,0,0,0,0,0,0,0,M29,0,0,0,0,0,0~
,0,0,0,0,0,0,0,0,0,0)';
      PINUSE='POWER';
      NO_LOAD_CHECK='Both';
      NO_IO_CHECK='Both';
      NO_ASSERT_CHECK='TRUE';
      NO_DIR_CHECK='TRUE';
      ALLOW_CONNECT='TRUE';
    'VDDCR_CPU0_M27':
      PIN_NUMBER='(0,0,0,0,0,0,0,0,0,0,0,0,0,0,0,0,0,0,0,0,0,0,0,M27,0,0,0,0,0,0~
,0,0,0,0,0,0,0,0,0,0)';
      PINUSE='POWER';
      NO_LOAD_CHECK='Both';
      NO_IO_CHECK='Both';
      NO_ASSERT_CHECK='TRUE';
      NO_DIR_CHECK='TRUE';
      ALLOW_CONNECT='TRUE';
    'VDDCR_CPU0_M26':
      PIN_NUMBER='(0,0,0,0,0,0,0,0,0,0,0,0,0,0,0,0,0,0,0,0,0,0,0,M26,0,0,0,0,0,0~
,0,0,0,0,0,0,0,0,0,0)';
      PINUSE='POWER';
      NO_LOAD_CHECK='Both';
      NO_IO_CHECK='Both';
      NO_ASSERT_CHECK='TRUE';
      NO_DIR_CHECK='TRUE';
      ALLOW_CONNECT='TRUE';
    'VDDCR_CPU0_M24':
      PIN_NUMBER='(0,0,0,0,0,0,0,0,0,0,0,0,0,0,0,0,0,0,0,0,0,0,0,M24,0,0,0,0,0,0~
,0,0,0,0,0,0,0,0,0,0)';
      PINUSE='POWER';
      NO_LOAD_CHECK='Both';
      NO_IO_CHECK='Both';
      NO_ASSERT_CHECK='TRUE';
      NO_DIR_CHECK='TRUE';
      ALLOW_CONNECT='TRUE';
    'VDDCR_CPU0_M23':
      PIN_NUMBER='(0,0,0,0,0,0,0,0,0,0,0,0,0,0,0,0,0,0,0,0,0,0,0,M23,0,0,0,0,0,0~
,0,0,0,0,0,0,0,0,0,0)';
      PINUSE='POWER';
      NO_LOAD_CHECK='Both';
      NO_IO_CHECK='Both';
      NO_ASSERT_CHECK='TRUE';
      NO_DIR_CHECK='TRUE';
      ALLOW_CONNECT='TRUE';
    'VDDCR_CPU0_J41':
      PIN_NUMBER='(0,0,0,0,0,0,0,0,0,0,0,0,0,0,0,0,0,0,0,0,0,0,0,J41,0,0,0,0,0,0~
,0,0,0,0,0,0,0,0,0,0)';
      PINUSE='POWER';
      NO_LOAD_CHECK='Both';
      NO_IO_CHECK='Both';
      NO_ASSERT_CHECK='TRUE';
      NO_DIR_CHECK='TRUE';
      ALLOW_CONNECT='TRUE';
    'VDDCR_CPU0_J40':
      PIN_NUMBER='(0,0,0,0,0,0,0,0,0,0,0,0,0,0,0,0,0,0,0,0,0,0,0,J40,0,0,0,0,0,0~
,0,0,0,0,0,0,0,0,0,0)';
      PINUSE='POWER';
      NO_LOAD_CHECK='Both';
      NO_IO_CHECK='Both';
      NO_ASSERT_CHECK='TRUE';
      NO_DIR_CHECK='TRUE';
      ALLOW_CONNECT='TRUE';
    'VDDCR_CPU0_J36':
      PIN_NUMBER='(0,0,0,0,0,0,0,0,0,0,0,0,0,0,0,0,0,0,0,0,0,0,0,J36,0,0,0,0,0,0~
,0,0,0,0,0,0,0,0,0,0)';
      PINUSE='POWER';
      NO_LOAD_CHECK='Both';
      NO_IO_CHECK='Both';
      NO_ASSERT_CHECK='TRUE';
      NO_DIR_CHECK='TRUE';
      ALLOW_CONNECT='TRUE';
    'VDDCR_CPU0_J35':
      PIN_NUMBER='(0,0,0,0,0,0,0,0,0,0,0,0,0,0,0,0,0,0,0,0,0,0,0,J35,0,0,0,0,0,0~
,0,0,0,0,0,0,0,0,0,0)';
      PINUSE='POWER';
      NO_LOAD_CHECK='Both';
      NO_IO_CHECK='Both';
      NO_ASSERT_CHECK='TRUE';
      NO_DIR_CHECK='TRUE';
      ALLOW_CONNECT='TRUE';
    'VDDCR_CPU0_H53':
      PIN_NUMBER='(0,0,0,0,0,0,0,0,0,0,0,0,0,0,0,0,0,0,0,0,0,0,0,H53,0,0,0,0,0,0~
,0,0,0,0,0,0,0,0,0,0)';
      PINUSE='POWER';
      NO_LOAD_CHECK='Both';
      NO_IO_CHECK='Both';
      NO_ASSERT_CHECK='TRUE';
      NO_DIR_CHECK='TRUE';
      ALLOW_CONNECT='TRUE';
    'VDDCR_CPU0_H52':
      PIN_NUMBER='(0,0,0,0,0,0,0,0,0,0,0,0,0,0,0,0,0,0,0,0,0,0,0,H52,0,0,0,0,0,0~
,0,0,0,0,0,0,0,0,0,0)';
      PINUSE='POWER';
      NO_LOAD_CHECK='Both';
      NO_IO_CHECK='Both';
      NO_ASSERT_CHECK='TRUE';
      NO_DIR_CHECK='TRUE';
      ALLOW_CONNECT='TRUE';
    'VDDCR_CPU0_H50':
      PIN_NUMBER='(0,0,0,0,0,0,0,0,0,0,0,0,0,0,0,0,0,0,0,0,0,0,0,H50,0,0,0,0,0,0~
,0,0,0,0,0,0,0,0,0,0)';
      PINUSE='POWER';
      NO_LOAD_CHECK='Both';
      NO_IO_CHECK='Both';
      NO_ASSERT_CHECK='TRUE';
      NO_DIR_CHECK='TRUE';
      ALLOW_CONNECT='TRUE';
    'VDDCR_CPU0_H49':
      PIN_NUMBER='(0,0,0,0,0,0,0,0,0,0,0,0,0,0,0,0,0,0,0,0,0,0,0,H49,0,0,0,0,0,0~
,0,0,0,0,0,0,0,0,0,0)';
      PINUSE='POWER';
      NO_LOAD_CHECK='Both';
      NO_IO_CHECK='Both';
      NO_ASSERT_CHECK='TRUE';
      NO_DIR_CHECK='TRUE';
      ALLOW_CONNECT='TRUE';
    'VDDCR_CPU0_H47':
      PIN_NUMBER='(0,0,0,0,0,0,0,0,0,0,0,0,0,0,0,0,0,0,0,0,0,0,0,H47,0,0,0,0,0,0~
,0,0,0,0,0,0,0,0,0,0)';
      PINUSE='POWER';
      NO_LOAD_CHECK='Both';
      NO_IO_CHECK='Both';
      NO_ASSERT_CHECK='TRUE';
      NO_DIR_CHECK='TRUE';
      ALLOW_CONNECT='TRUE';
    'VDDCR_CPU0_H46':
      PIN_NUMBER='(0,0,0,0,0,0,0,0,0,0,0,0,0,0,0,0,0,0,0,0,0,0,0,H46,0,0,0,0,0,0~
,0,0,0,0,0,0,0,0,0,0)';
      PINUSE='POWER';
      NO_LOAD_CHECK='Both';
      NO_IO_CHECK='Both';
      NO_ASSERT_CHECK='TRUE';
      NO_DIR_CHECK='TRUE';
      ALLOW_CONNECT='TRUE';
    'VDDCR_CPU0_H44':
      PIN_NUMBER='(0,0,0,0,0,0,0,0,0,0,0,0,0,0,0,0,0,0,0,0,0,0,0,H44,0,0,0,0,0,0~
,0,0,0,0,0,0,0,0,0,0)';
      PINUSE='POWER';
      NO_LOAD_CHECK='Both';
      NO_IO_CHECK='Both';
      NO_ASSERT_CHECK='TRUE';
      NO_DIR_CHECK='TRUE';
      ALLOW_CONNECT='TRUE';
    'VDDCR_CPU0_H43':
      PIN_NUMBER='(0,0,0,0,0,0,0,0,0,0,0,0,0,0,0,0,0,0,0,0,0,0,0,H43,0,0,0,0,0,0~
,0,0,0,0,0,0,0,0,0,0)';
      PINUSE='POWER';
      NO_LOAD_CHECK='Both';
      NO_IO_CHECK='Both';
      NO_ASSERT_CHECK='TRUE';
      NO_DIR_CHECK='TRUE';
      ALLOW_CONNECT='TRUE';
    'VDDCR_CPU0_H33':
      PIN_NUMBER='(0,0,0,0,0,0,0,0,0,0,0,0,0,0,0,0,0,0,0,0,0,0,0,H33,0,0,0,0,0,0~
,0,0,0,0,0,0,0,0,0,0)';
      PINUSE='POWER';
      NO_LOAD_CHECK='Both';
      NO_IO_CHECK='Both';
      NO_ASSERT_CHECK='TRUE';
      NO_DIR_CHECK='TRUE';
      ALLOW_CONNECT='TRUE';
    'VDDCR_CPU0_H32':
      PIN_NUMBER='(0,0,0,0,0,0,0,0,0,0,0,0,0,0,0,0,0,0,0,0,0,0,0,H32,0,0,0,0,0,0~
,0,0,0,0,0,0,0,0,0,0)';
      PINUSE='POWER';
      NO_LOAD_CHECK='Both';
      NO_IO_CHECK='Both';
      NO_ASSERT_CHECK='TRUE';
      NO_DIR_CHECK='TRUE';
      ALLOW_CONNECT='TRUE';
    'VDDCR_CPU0_H30':
      PIN_NUMBER='(0,0,0,0,0,0,0,0,0,0,0,0,0,0,0,0,0,0,0,0,0,0,0,H30,0,0,0,0,0,0~
,0,0,0,0,0,0,0,0,0,0)';
      PINUSE='POWER';
      NO_LOAD_CHECK='Both';
      NO_IO_CHECK='Both';
      NO_ASSERT_CHECK='TRUE';
      NO_DIR_CHECK='TRUE';
      ALLOW_CONNECT='TRUE';
    'VDDCR_CPU0_H29':
      PIN_NUMBER='(0,0,0,0,0,0,0,0,0,0,0,0,0,0,0,0,0,0,0,0,0,0,0,H29,0,0,0,0,0,0~
,0,0,0,0,0,0,0,0,0,0)';
      PINUSE='POWER';
      NO_LOAD_CHECK='Both';
      NO_IO_CHECK='Both';
      NO_ASSERT_CHECK='TRUE';
      NO_DIR_CHECK='TRUE';
      ALLOW_CONNECT='TRUE';
    'VDDCR_CPU0_H27':
      PIN_NUMBER='(0,0,0,0,0,0,0,0,0,0,0,0,0,0,0,0,0,0,0,0,0,0,0,H27,0,0,0,0,0,0~
,0,0,0,0,0,0,0,0,0,0)';
      PINUSE='POWER';
      NO_LOAD_CHECK='Both';
      NO_IO_CHECK='Both';
      NO_ASSERT_CHECK='TRUE';
      NO_DIR_CHECK='TRUE';
      ALLOW_CONNECT='TRUE';
    'VDDCR_CPU0_H26':
      PIN_NUMBER='(0,0,0,0,0,0,0,0,0,0,0,0,0,0,0,0,0,0,0,0,0,0,0,H26,0,0,0,0,0,0~
,0,0,0,0,0,0,0,0,0,0)';
      PINUSE='POWER';
      NO_LOAD_CHECK='Both';
      NO_IO_CHECK='Both';
      NO_ASSERT_CHECK='TRUE';
      NO_DIR_CHECK='TRUE';
      ALLOW_CONNECT='TRUE';
    'VDDCR_CPU0_H24':
      PIN_NUMBER='(0,0,0,0,0,0,0,0,0,0,0,0,0,0,0,0,0,0,0,0,0,0,0,H24,0,0,0,0,0,0~
,0,0,0,0,0,0,0,0,0,0)';
      PINUSE='POWER';
      NO_LOAD_CHECK='Both';
      NO_IO_CHECK='Both';
      NO_ASSERT_CHECK='TRUE';
      NO_DIR_CHECK='TRUE';
      ALLOW_CONNECT='TRUE';
    'VDDCR_CPU0_H23':
      PIN_NUMBER='(0,0,0,0,0,0,0,0,0,0,0,0,0,0,0,0,0,0,0,0,0,0,0,H23,0,0,0,0,0,0~
,0,0,0,0,0,0,0,0,0,0)';
      PINUSE='POWER';
      NO_LOAD_CHECK='Both';
      NO_IO_CHECK='Both';
      NO_ASSERT_CHECK='TRUE';
      NO_DIR_CHECK='TRUE';
      ALLOW_CONNECT='TRUE';
    'VDDCR_CPU0_G41':
      PIN_NUMBER='(0,0,0,0,0,0,0,0,0,0,0,0,0,0,0,0,0,0,0,0,0,0,0,G41,0,0,0,0,0,0~
,0,0,0,0,0,0,0,0,0,0)';
      PINUSE='POWER';
      NO_LOAD_CHECK='Both';
      NO_IO_CHECK='Both';
      NO_ASSERT_CHECK='TRUE';
      NO_DIR_CHECK='TRUE';
      ALLOW_CONNECT='TRUE';
    'VDDCR_CPU0_G40':
      PIN_NUMBER='(0,0,0,0,0,0,0,0,0,0,0,0,0,0,0,0,0,0,0,0,0,0,0,G40,0,0,0,0,0,0~
,0,0,0,0,0,0,0,0,0,0)';
      PINUSE='POWER';
      NO_LOAD_CHECK='Both';
      NO_IO_CHECK='Both';
      NO_ASSERT_CHECK='TRUE';
      NO_DIR_CHECK='TRUE';
      ALLOW_CONNECT='TRUE';
    'VDDCR_CPU0_G36':
      PIN_NUMBER='(0,0,0,0,0,0,0,0,0,0,0,0,0,0,0,0,0,0,0,0,0,0,0,G36,0,0,0,0,0,0~
,0,0,0,0,0,0,0,0,0,0)';
      PINUSE='POWER';
      NO_LOAD_CHECK='Both';
      NO_IO_CHECK='Both';
      NO_ASSERT_CHECK='TRUE';
      NO_DIR_CHECK='TRUE';
      ALLOW_CONNECT='TRUE';
    'VDDCR_CPU0_G35':
      PIN_NUMBER='(0,0,0,0,0,0,0,0,0,0,0,0,0,0,0,0,0,0,0,0,0,0,0,G35,0,0,0,0,0,0~
,0,0,0,0,0,0,0,0,0,0)';
      PINUSE='POWER';
      NO_LOAD_CHECK='Both';
      NO_IO_CHECK='Both';
      NO_ASSERT_CHECK='TRUE';
      NO_DIR_CHECK='TRUE';
      ALLOW_CONNECT='TRUE';
    'VDDCR_CPU0_F54':
      PIN_NUMBER='(0,0,0,0,0,0,0,0,0,0,0,0,0,0,0,0,0,0,0,0,0,0,0,F54,0,0,0,0,0,0~
,0,0,0,0,0,0,0,0,0,0)';
      PINUSE='POWER';
      NO_LOAD_CHECK='Both';
      NO_IO_CHECK='Both';
      NO_ASSERT_CHECK='TRUE';
      NO_DIR_CHECK='TRUE';
      ALLOW_CONNECT='TRUE';
    'VDDCR_CPU0_F51':
      PIN_NUMBER='(0,0,0,0,0,0,0,0,0,0,0,0,0,0,0,0,0,0,0,0,0,0,0,F51,0,0,0,0,0,0~
,0,0,0,0,0,0,0,0,0,0)';
      PINUSE='POWER';
      NO_LOAD_CHECK='Both';
      NO_IO_CHECK='Both';
      NO_ASSERT_CHECK='TRUE';
      NO_DIR_CHECK='TRUE';
      ALLOW_CONNECT='TRUE';
    'VDDCR_CPU0_F48':
      PIN_NUMBER='(0,0,0,0,0,0,0,0,0,0,0,0,0,0,0,0,0,0,0,0,0,0,0,F48,0,0,0,0,0,0~
,0,0,0,0,0,0,0,0,0,0)';
      PINUSE='POWER';
      NO_LOAD_CHECK='Both';
      NO_IO_CHECK='Both';
      NO_ASSERT_CHECK='TRUE';
      NO_DIR_CHECK='TRUE';
      ALLOW_CONNECT='TRUE';
    'VDDCR_CPU0_F45':
      PIN_NUMBER='(0,0,0,0,0,0,0,0,0,0,0,0,0,0,0,0,0,0,0,0,0,0,0,F45,0,0,0,0,0,0~
,0,0,0,0,0,0,0,0,0,0)';
      PINUSE='POWER';
      NO_LOAD_CHECK='Both';
      NO_IO_CHECK='Both';
      NO_ASSERT_CHECK='TRUE';
      NO_DIR_CHECK='TRUE';
      ALLOW_CONNECT='TRUE';
    'VDDCR_CPU0_F42':
      PIN_NUMBER='(0,0,0,0,0,0,0,0,0,0,0,0,0,0,0,0,0,0,0,0,0,0,0,F42,0,0,0,0,0,0~
,0,0,0,0,0,0,0,0,0,0)';
      PINUSE='POWER';
      NO_LOAD_CHECK='Both';
      NO_IO_CHECK='Both';
      NO_ASSERT_CHECK='TRUE';
      NO_DIR_CHECK='TRUE';
      ALLOW_CONNECT='TRUE';
    'VDDCR_CPU0_F34':
      PIN_NUMBER='(0,0,0,0,0,0,0,0,0,0,0,0,0,0,0,0,0,0,0,0,0,0,0,F34,0,0,0,0,0,0~
,0,0,0,0,0,0,0,0,0,0)';
      PINUSE='POWER';
      NO_LOAD_CHECK='Both';
      NO_IO_CHECK='Both';
      NO_ASSERT_CHECK='TRUE';
      NO_DIR_CHECK='TRUE';
      ALLOW_CONNECT='TRUE';
    'VDDCR_CPU0_F31':
      PIN_NUMBER='(0,0,0,0,0,0,0,0,0,0,0,0,0,0,0,0,0,0,0,0,0,0,0,F31,0,0,0,0,0,0~
,0,0,0,0,0,0,0,0,0,0)';
      PINUSE='POWER';
      NO_LOAD_CHECK='Both';
      NO_IO_CHECK='Both';
      NO_ASSERT_CHECK='TRUE';
      NO_DIR_CHECK='TRUE';
      ALLOW_CONNECT='TRUE';
    'VDDCR_CPU0_F28':
      PIN_NUMBER='(0,0,0,0,0,0,0,0,0,0,0,0,0,0,0,0,0,0,0,0,0,0,0,F28,0,0,0,0,0,0~
,0,0,0,0,0,0,0,0,0,0)';
      PINUSE='POWER';
      NO_LOAD_CHECK='Both';
      NO_IO_CHECK='Both';
      NO_ASSERT_CHECK='TRUE';
      NO_DIR_CHECK='TRUE';
      ALLOW_CONNECT='TRUE';
    'VDDCR_CPU0_F25':
      PIN_NUMBER='(0,0,0,0,0,0,0,0,0,0,0,0,0,0,0,0,0,0,0,0,0,0,0,F25,0,0,0,0,0,0~
,0,0,0,0,0,0,0,0,0,0)';
      PINUSE='POWER';
      NO_LOAD_CHECK='Both';
      NO_IO_CHECK='Both';
      NO_ASSERT_CHECK='TRUE';
      NO_DIR_CHECK='TRUE';
      ALLOW_CONNECT='TRUE';
    'VDDCR_CPU0_F22':
      PIN_NUMBER='(0,0,0,0,0,0,0,0,0,0,0,0,0,0,0,0,0,0,0,0,0,0,0,F22,0,0,0,0,0,0~
,0,0,0,0,0,0,0,0,0,0)';
      PINUSE='POWER';
      NO_LOAD_CHECK='Both';
      NO_IO_CHECK='Both';
      NO_ASSERT_CHECK='TRUE';
      NO_DIR_CHECK='TRUE';
      ALLOW_CONNECT='TRUE';
    'VDDCR_CPU0_E54':
      PIN_NUMBER='(0,0,0,0,0,0,0,0,0,0,0,0,0,0,0,0,0,0,0,0,0,0,0,E54,0,0,0,0,0,0~
,0,0,0,0,0,0,0,0,0,0)';
      PINUSE='POWER';
      NO_LOAD_CHECK='Both';
      NO_IO_CHECK='Both';
      NO_ASSERT_CHECK='TRUE';
      NO_DIR_CHECK='TRUE';
      ALLOW_CONNECT='TRUE';
    'VDDCR_CPU0_E51':
      PIN_NUMBER='(0,0,0,0,0,0,0,0,0,0,0,0,0,0,0,0,0,0,0,0,0,0,0,E51,0,0,0,0,0,0~
,0,0,0,0,0,0,0,0,0,0)';
      PINUSE='POWER';
      NO_LOAD_CHECK='Both';
      NO_IO_CHECK='Both';
      NO_ASSERT_CHECK='TRUE';
      NO_DIR_CHECK='TRUE';
      ALLOW_CONNECT='TRUE';
    'VDDCR_CPU0_E48':
      PIN_NUMBER='(0,0,0,0,0,0,0,0,0,0,0,0,0,0,0,0,0,0,0,0,0,0,0,E48,0,0,0,0,0,0~
,0,0,0,0,0,0,0,0,0,0)';
      PINUSE='POWER';
      NO_LOAD_CHECK='Both';
      NO_IO_CHECK='Both';
      NO_ASSERT_CHECK='TRUE';
      NO_DIR_CHECK='TRUE';
      ALLOW_CONNECT='TRUE';
    'VDDCR_CPU0_E45':
      PIN_NUMBER='(0,0,0,0,0,0,0,0,0,0,0,0,0,0,0,0,0,0,0,0,0,0,0,E45,0,0,0,0,0,0~
,0,0,0,0,0,0,0,0,0,0)';
      PINUSE='POWER';
      NO_LOAD_CHECK='Both';
      NO_IO_CHECK='Both';
      NO_ASSERT_CHECK='TRUE';
      NO_DIR_CHECK='TRUE';
      ALLOW_CONNECT='TRUE';
    'VDDCR_CPU0_E42':
      PIN_NUMBER='(0,0,0,0,0,0,0,0,0,0,0,0,0,0,0,0,0,0,0,0,0,0,0,E42,0,0,0,0,0,0~
,0,0,0,0,0,0,0,0,0,0)';
      PINUSE='POWER';
      NO_LOAD_CHECK='Both';
      NO_IO_CHECK='Both';
      NO_ASSERT_CHECK='TRUE';
      NO_DIR_CHECK='TRUE';
      ALLOW_CONNECT='TRUE';
    'VDDCR_CPU0_E35':
      PIN_NUMBER='(0,0,0,0,0,0,0,0,0,0,0,0,0,0,0,0,0,0,0,0,0,0,0,E35,0,0,0,0,0,0~
,0,0,0,0,0,0,0,0,0,0)';
      PINUSE='POWER';
      NO_LOAD_CHECK='Both';
      NO_IO_CHECK='Both';
      NO_ASSERT_CHECK='TRUE';
      NO_DIR_CHECK='TRUE';
      ALLOW_CONNECT='TRUE';
    'VDDCR_CPU0_E34':
      PIN_NUMBER='(0,0,0,0,0,0,0,0,0,0,0,0,0,0,0,0,0,0,0,0,0,0,0,E34,0,0,0,0,0,0~
,0,0,0,0,0,0,0,0,0,0)';
      PINUSE='POWER';
      NO_LOAD_CHECK='Both';
      NO_IO_CHECK='Both';
      NO_ASSERT_CHECK='TRUE';
      NO_DIR_CHECK='TRUE';
      ALLOW_CONNECT='TRUE';
    'VDDCR_CPU0_E31':
      PIN_NUMBER='(0,0,0,0,0,0,0,0,0,0,0,0,0,0,0,0,0,0,0,0,0,0,0,E31,0,0,0,0,0,0~
,0,0,0,0,0,0,0,0,0,0)';
      PINUSE='POWER';
      NO_LOAD_CHECK='Both';
      NO_IO_CHECK='Both';
      NO_ASSERT_CHECK='TRUE';
      NO_DIR_CHECK='TRUE';
      ALLOW_CONNECT='TRUE';
    'VDDCR_CPU0_E28':
      PIN_NUMBER='(0,0,0,0,0,0,0,0,0,0,0,0,0,0,0,0,0,0,0,0,0,0,0,E28,0,0,0,0,0,0~
,0,0,0,0,0,0,0,0,0,0)';
      PINUSE='POWER';
      NO_LOAD_CHECK='Both';
      NO_IO_CHECK='Both';
      NO_ASSERT_CHECK='TRUE';
      NO_DIR_CHECK='TRUE';
      ALLOW_CONNECT='TRUE';
    'VDDCR_CPU0_E25':
      PIN_NUMBER='(0,0,0,0,0,0,0,0,0,0,0,0,0,0,0,0,0,0,0,0,0,0,0,E25,0,0,0,0,0,0~
,0,0,0,0,0,0,0,0,0,0)';
      PINUSE='POWER';
      NO_LOAD_CHECK='Both';
      NO_IO_CHECK='Both';
      NO_ASSERT_CHECK='TRUE';
      NO_DIR_CHECK='TRUE';
      ALLOW_CONNECT='TRUE';
    'VDDCR_CPU0_E22':
      PIN_NUMBER='(0,0,0,0,0,0,0,0,0,0,0,0,0,0,0,0,0,0,0,0,0,0,0,E22,0,0,0,0,0,0~
,0,0,0,0,0,0,0,0,0,0)';
      PINUSE='POWER';
      NO_LOAD_CHECK='Both';
      NO_IO_CHECK='Both';
      NO_ASSERT_CHECK='TRUE';
      NO_DIR_CHECK='TRUE';
      ALLOW_CONNECT='TRUE';
    'VDDCR_CPU0_D56':
      PIN_NUMBER='(0,0,0,0,0,0,0,0,0,0,0,0,0,0,0,0,0,0,0,0,0,0,0,D56,0,0,0,0,0,0~
,0,0,0,0,0,0,0,0,0,0)';
      PINUSE='POWER';
      NO_LOAD_CHECK='Both';
      NO_IO_CHECK='Both';
      NO_ASSERT_CHECK='TRUE';
      NO_DIR_CHECK='TRUE';
      ALLOW_CONNECT='TRUE';
    'VDDCR_CPU0_D55':
      PIN_NUMBER='(0,0,0,0,0,0,0,0,0,0,0,0,0,0,0,0,0,0,0,0,0,0,0,D55,0,0,0,0,0,0~
,0,0,0,0,0,0,0,0,0,0)';
      PINUSE='POWER';
      NO_LOAD_CHECK='Both';
      NO_IO_CHECK='Both';
      NO_ASSERT_CHECK='TRUE';
      NO_DIR_CHECK='TRUE';
      ALLOW_CONNECT='TRUE';
    'VDDCR_CPU0_C20':
      PIN_NUMBER='(0,0,0,0,0,0,0,0,0,0,0,0,0,0,0,0,0,0,0,0,0,0,0,C20,0,0,0,0,0,0~
,0,0,0,0,0,0,0,0,0,0)';
      PINUSE='POWER';
      NO_LOAD_CHECK='Both';
      NO_IO_CHECK='Both';
      NO_ASSERT_CHECK='TRUE';
      NO_DIR_CHECK='TRUE';
      ALLOW_CONNECT='TRUE';
    'VDDCR_CPU0_B57':
      PIN_NUMBER='(0,0,0,0,0,0,0,0,0,0,0,0,0,0,0,0,0,0,0,0,0,0,0,B57,0,0,0,0,0,0~
,0,0,0,0,0,0,0,0,0,0)';
      PINUSE='POWER';
      NO_LOAD_CHECK='Both';
      NO_IO_CHECK='Both';
      NO_ASSERT_CHECK='TRUE';
      NO_DIR_CHECK='TRUE';
      ALLOW_CONNECT='TRUE';
    'VDDCR_CPU0_B56':
      PIN_NUMBER='(0,0,0,0,0,0,0,0,0,0,0,0,0,0,0,0,0,0,0,0,0,0,0,B56,0,0,0,0,0,0~
,0,0,0,0,0,0,0,0,0,0)';
      PINUSE='POWER';
      NO_LOAD_CHECK='Both';
      NO_IO_CHECK='Both';
      NO_ASSERT_CHECK='TRUE';
      NO_DIR_CHECK='TRUE';
      ALLOW_CONNECT='TRUE';
    'VDDCR_CPU0_B54':
      PIN_NUMBER='(0,0,0,0,0,0,0,0,0,0,0,0,0,0,0,0,0,0,0,0,0,0,0,B54,0,0,0,0,0,0~
,0,0,0,0,0,0,0,0,0,0)';
      PINUSE='POWER';
      NO_LOAD_CHECK='Both';
      NO_IO_CHECK='Both';
      NO_ASSERT_CHECK='TRUE';
      NO_DIR_CHECK='TRUE';
      ALLOW_CONNECT='TRUE';
    'VDDCR_CPU0_B53':
      PIN_NUMBER='(0,0,0,0,0,0,0,0,0,0,0,0,0,0,0,0,0,0,0,0,0,0,0,B53,0,0,0,0,0,0~
,0,0,0,0,0,0,0,0,0,0)';
      PINUSE='POWER';
      NO_LOAD_CHECK='Both';
      NO_IO_CHECK='Both';
      NO_ASSERT_CHECK='TRUE';
      NO_DIR_CHECK='TRUE';
      ALLOW_CONNECT='TRUE';
    'VDDCR_CPU0_B51':
      PIN_NUMBER='(0,0,0,0,0,0,0,0,0,0,0,0,0,0,0,0,0,0,0,0,0,0,0,B51,0,0,0,0,0,0~
,0,0,0,0,0,0,0,0,0,0)';
      PINUSE='POWER';
      NO_LOAD_CHECK='Both';
      NO_IO_CHECK='Both';
      NO_ASSERT_CHECK='TRUE';
      NO_DIR_CHECK='TRUE';
      ALLOW_CONNECT='TRUE';
    'VDDCR_CPU0_B50':
      PIN_NUMBER='(0,0,0,0,0,0,0,0,0,0,0,0,0,0,0,0,0,0,0,0,0,0,0,B50,0,0,0,0,0,0~
,0,0,0,0,0,0,0,0,0,0)';
      PINUSE='POWER';
      NO_LOAD_CHECK='Both';
      NO_IO_CHECK='Both';
      NO_ASSERT_CHECK='TRUE';
      NO_DIR_CHECK='TRUE';
      ALLOW_CONNECT='TRUE';
    'VDDCR_CPU0_B48':
      PIN_NUMBER='(0,0,0,0,0,0,0,0,0,0,0,0,0,0,0,0,0,0,0,0,0,0,0,B48,0,0,0,0,0,0~
,0,0,0,0,0,0,0,0,0,0)';
      PINUSE='POWER';
      NO_LOAD_CHECK='Both';
      NO_IO_CHECK='Both';
      NO_ASSERT_CHECK='TRUE';
      NO_DIR_CHECK='TRUE';
      ALLOW_CONNECT='TRUE';
    'VDDCR_CPU0_B47':
      PIN_NUMBER='(0,0,0,0,0,0,0,0,0,0,0,0,0,0,0,0,0,0,0,0,0,0,0,B47,0,0,0,0,0,0~
,0,0,0,0,0,0,0,0,0,0)';
      PINUSE='POWER';
      NO_LOAD_CHECK='Both';
      NO_IO_CHECK='Both';
      NO_ASSERT_CHECK='TRUE';
      NO_DIR_CHECK='TRUE';
      ALLOW_CONNECT='TRUE';
    'VDDCR_CPU0_B45':
      PIN_NUMBER='(0,0,0,0,0,0,0,0,0,0,0,0,0,0,0,0,0,0,0,0,0,0,0,B45,0,0,0,0,0,0~
,0,0,0,0,0,0,0,0,0,0)';
      PINUSE='POWER';
      NO_LOAD_CHECK='Both';
      NO_IO_CHECK='Both';
      NO_ASSERT_CHECK='TRUE';
      NO_DIR_CHECK='TRUE';
      ALLOW_CONNECT='TRUE';
    'VDDCR_CPU0_B44':
      PIN_NUMBER='(0,0,0,0,0,0,0,0,0,0,0,0,0,0,0,0,0,0,0,0,0,0,0,B44,0,0,0,0,0,0~
,0,0,0,0,0,0,0,0,0,0)';
      PINUSE='POWER';
      NO_LOAD_CHECK='Both';
      NO_IO_CHECK='Both';
      NO_ASSERT_CHECK='TRUE';
      NO_DIR_CHECK='TRUE';
      ALLOW_CONNECT='TRUE';
    'VDDCR_CPU0_B42':
      PIN_NUMBER='(0,0,0,0,0,0,0,0,0,0,0,0,0,0,0,0,0,0,0,0,0,0,0,B42,0,0,0,0,0,0~
,0,0,0,0,0,0,0,0,0,0)';
      PINUSE='POWER';
      NO_LOAD_CHECK='Both';
      NO_IO_CHECK='Both';
      NO_ASSERT_CHECK='TRUE';
      NO_DIR_CHECK='TRUE';
      ALLOW_CONNECT='TRUE';
    'VDDCR_CPU0_B41':
      PIN_NUMBER='(0,0,0,0,0,0,0,0,0,0,0,0,0,0,0,0,0,0,0,0,0,0,0,B41,0,0,0,0,0,0~
,0,0,0,0,0,0,0,0,0,0)';
      PINUSE='POWER';
      NO_LOAD_CHECK='Both';
      NO_IO_CHECK='Both';
      NO_ASSERT_CHECK='TRUE';
      NO_DIR_CHECK='TRUE';
      ALLOW_CONNECT='TRUE';
    'VDDCR_CPU0_B35':
      PIN_NUMBER='(0,0,0,0,0,0,0,0,0,0,0,0,0,0,0,0,0,0,0,0,0,0,0,B35,0,0,0,0,0,0~
,0,0,0,0,0,0,0,0,0,0)';
      PINUSE='POWER';
      NO_LOAD_CHECK='Both';
      NO_IO_CHECK='Both';
      NO_ASSERT_CHECK='TRUE';
      NO_DIR_CHECK='TRUE';
      ALLOW_CONNECT='TRUE';
    'VDDCR_CPU0_B34':
      PIN_NUMBER='(0,0,0,0,0,0,0,0,0,0,0,0,0,0,0,0,0,0,0,0,0,0,0,B34,0,0,0,0,0,0~
,0,0,0,0,0,0,0,0,0,0)';
      PINUSE='POWER';
      NO_LOAD_CHECK='Both';
      NO_IO_CHECK='Both';
      NO_ASSERT_CHECK='TRUE';
      NO_DIR_CHECK='TRUE';
      ALLOW_CONNECT='TRUE';
    'VDDCR_CPU0_B32':
      PIN_NUMBER='(0,0,0,0,0,0,0,0,0,0,0,0,0,0,0,0,0,0,0,0,0,0,0,B32,0,0,0,0,0,0~
,0,0,0,0,0,0,0,0,0,0)';
      PINUSE='POWER';
      NO_LOAD_CHECK='Both';
      NO_IO_CHECK='Both';
      NO_ASSERT_CHECK='TRUE';
      NO_DIR_CHECK='TRUE';
      ALLOW_CONNECT='TRUE';
    'VDDCR_CPU0_B31':
      PIN_NUMBER='(0,0,0,0,0,0,0,0,0,0,0,0,0,0,0,0,0,0,0,0,0,0,0,B31,0,0,0,0,0,0~
,0,0,0,0,0,0,0,0,0,0)';
      PINUSE='POWER';
      NO_LOAD_CHECK='Both';
      NO_IO_CHECK='Both';
      NO_ASSERT_CHECK='TRUE';
      NO_DIR_CHECK='TRUE';
      ALLOW_CONNECT='TRUE';
    'VDDCR_CPU0_B29':
      PIN_NUMBER='(0,0,0,0,0,0,0,0,0,0,0,0,0,0,0,0,0,0,0,0,0,0,0,B29,0,0,0,0,0,0~
,0,0,0,0,0,0,0,0,0,0)';
      PINUSE='POWER';
      NO_LOAD_CHECK='Both';
      NO_IO_CHECK='Both';
      NO_ASSERT_CHECK='TRUE';
      NO_DIR_CHECK='TRUE';
      ALLOW_CONNECT='TRUE';
    'VDDCR_CPU0_B28':
      PIN_NUMBER='(0,0,0,0,0,0,0,0,0,0,0,0,0,0,0,0,0,0,0,0,0,0,0,B28,0,0,0,0,0,0~
,0,0,0,0,0,0,0,0,0,0)';
      PINUSE='POWER';
      NO_LOAD_CHECK='Both';
      NO_IO_CHECK='Both';
      NO_ASSERT_CHECK='TRUE';
      NO_DIR_CHECK='TRUE';
      ALLOW_CONNECT='TRUE';
    'VDDCR_CPU0_B26':
      PIN_NUMBER='(0,0,0,0,0,0,0,0,0,0,0,0,0,0,0,0,0,0,0,0,0,0,0,B26,0,0,0,0,0,0~
,0,0,0,0,0,0,0,0,0,0)';
      PINUSE='POWER';
      NO_LOAD_CHECK='Both';
      NO_IO_CHECK='Both';
      NO_ASSERT_CHECK='TRUE';
      NO_DIR_CHECK='TRUE';
      ALLOW_CONNECT='TRUE';
    'VDDCR_CPU0_B25':
      PIN_NUMBER='(0,0,0,0,0,0,0,0,0,0,0,0,0,0,0,0,0,0,0,0,0,0,0,B25,0,0,0,0,0,0~
,0,0,0,0,0,0,0,0,0,0)';
      PINUSE='POWER';
      NO_LOAD_CHECK='Both';
      NO_IO_CHECK='Both';
      NO_ASSERT_CHECK='TRUE';
      NO_DIR_CHECK='TRUE';
      ALLOW_CONNECT='TRUE';
    'VDDCR_CPU0_B23':
      PIN_NUMBER='(0,0,0,0,0,0,0,0,0,0,0,0,0,0,0,0,0,0,0,0,0,0,0,B23,0,0,0,0,0,0~
,0,0,0,0,0,0,0,0,0,0)';
      PINUSE='POWER';
      NO_LOAD_CHECK='Both';
      NO_IO_CHECK='Both';
      NO_ASSERT_CHECK='TRUE';
      NO_DIR_CHECK='TRUE';
      ALLOW_CONNECT='TRUE';
    'VDDCR_CPU0_B22':
      PIN_NUMBER='(0,0,0,0,0,0,0,0,0,0,0,0,0,0,0,0,0,0,0,0,0,0,0,B22,0,0,0,0,0,0~
,0,0,0,0,0,0,0,0,0,0)';
      PINUSE='POWER';
      NO_LOAD_CHECK='Both';
      NO_IO_CHECK='Both';
      NO_ASSERT_CHECK='TRUE';
      NO_DIR_CHECK='TRUE';
      ALLOW_CONNECT='TRUE';
    'VDDCR_CPU0_B20':
      PIN_NUMBER='(0,0,0,0,0,0,0,0,0,0,0,0,0,0,0,0,0,0,0,0,0,0,0,B20,0,0,0,0,0,0~
,0,0,0,0,0,0,0,0,0,0)';
      PINUSE='POWER';
      NO_LOAD_CHECK='Both';
      NO_IO_CHECK='Both';
      NO_ASSERT_CHECK='TRUE';
      NO_DIR_CHECK='TRUE';
      ALLOW_CONNECT='TRUE';
    'VDDCR_CPU0_B19':
      PIN_NUMBER='(0,0,0,0,0,0,0,0,0,0,0,0,0,0,0,0,0,0,0,0,0,0,0,B19,0,0,0,0,0,0~
,0,0,0,0,0,0,0,0,0,0)';
      PINUSE='POWER';
      NO_LOAD_CHECK='Both';
      NO_IO_CHECK='Both';
      NO_ASSERT_CHECK='TRUE';
      NO_DIR_CHECK='TRUE';
      ALLOW_CONNECT='TRUE';
    'VDDCR_CPU0_AT47':
      PIN_NUMBER='(0,0,0,0,0,0,0,0,0,0,0,0,0,0,0,0,0,0,0,0,0,0,0,AT47,0,0,0,0,0,~
0,0,0,0,0,0,0,0,0,0,0)';
      PINUSE='POWER';
      NO_LOAD_CHECK='Both';
      NO_IO_CHECK='Both';
      NO_ASSERT_CHECK='TRUE';
      NO_DIR_CHECK='TRUE';
      ALLOW_CONNECT='TRUE';
    'VDDCR_CPU0_AT45':
      PIN_NUMBER='(0,0,0,0,0,0,0,0,0,0,0,0,0,0,0,0,0,0,0,0,0,0,0,AT45,0,0,0,0,0,~
0,0,0,0,0,0,0,0,0,0,0)';
      PINUSE='POWER';
      NO_LOAD_CHECK='Both';
      NO_IO_CHECK='Both';
      NO_ASSERT_CHECK='TRUE';
      NO_DIR_CHECK='TRUE';
      ALLOW_CONNECT='TRUE';
    'VDDCR_CPU0_AT43':
      PIN_NUMBER='(0,0,0,0,0,0,0,0,0,0,0,0,0,0,0,0,0,0,0,0,0,0,0,AT43,0,0,0,0,0,~
0,0,0,0,0,0,0,0,0,0,0)';
      PINUSE='POWER';
      NO_LOAD_CHECK='Both';
      NO_IO_CHECK='Both';
      NO_ASSERT_CHECK='TRUE';
      NO_DIR_CHECK='TRUE';
      ALLOW_CONNECT='TRUE';
    'VDDCR_CPU0_AT41':
      PIN_NUMBER='(0,0,0,0,0,0,0,0,0,0,0,0,0,0,0,0,0,0,0,0,0,0,0,AT41,0,0,0,0,0,~
0,0,0,0,0,0,0,0,0,0,0)';
      PINUSE='POWER';
      NO_LOAD_CHECK='Both';
      NO_IO_CHECK='Both';
      NO_ASSERT_CHECK='TRUE';
      NO_DIR_CHECK='TRUE';
      ALLOW_CONNECT='TRUE';
    'VDDCR_CPU0_AT39':
      PIN_NUMBER='(0,0,0,0,0,0,0,0,0,0,0,0,0,0,0,0,0,0,0,0,0,0,0,AT39,0,0,0,0,0,~
0,0,0,0,0,0,0,0,0,0,0)';
      PINUSE='POWER';
      NO_LOAD_CHECK='Both';
      NO_IO_CHECK='Both';
      NO_ASSERT_CHECK='TRUE';
      NO_DIR_CHECK='TRUE';
      ALLOW_CONNECT='TRUE';
    'VDDCR_CPU0_AT36':
      PIN_NUMBER='(0,0,0,0,0,0,0,0,0,0,0,0,0,0,0,0,0,0,0,0,0,0,0,AT36,0,0,0,0,0,~
0,0,0,0,0,0,0,0,0,0,0)';
      PINUSE='POWER';
      NO_LOAD_CHECK='Both';
      NO_IO_CHECK='Both';
      NO_ASSERT_CHECK='TRUE';
      NO_DIR_CHECK='TRUE';
      ALLOW_CONNECT='TRUE';
    'VDDCR_CPU0_AT34':
      PIN_NUMBER='(0,0,0,0,0,0,0,0,0,0,0,0,0,0,0,0,0,0,0,0,0,0,0,AT34,0,0,0,0,0,~
0,0,0,0,0,0,0,0,0,0,0)';
      PINUSE='POWER';
      NO_LOAD_CHECK='Both';
      NO_IO_CHECK='Both';
      NO_ASSERT_CHECK='TRUE';
      NO_DIR_CHECK='TRUE';
      ALLOW_CONNECT='TRUE';
    'VDDCR_CPU0_AT32':
      PIN_NUMBER='(0,0,0,0,0,0,0,0,0,0,0,0,0,0,0,0,0,0,0,0,0,0,0,AT32,0,0,0,0,0,~
0,0,0,0,0,0,0,0,0,0,0)';
      PINUSE='POWER';
      NO_LOAD_CHECK='Both';
      NO_IO_CHECK='Both';
      NO_ASSERT_CHECK='TRUE';
      NO_DIR_CHECK='TRUE';
      ALLOW_CONNECT='TRUE';
    'VDDCR_CPU0_AT30':
      PIN_NUMBER='(0,0,0,0,0,0,0,0,0,0,0,0,0,0,0,0,0,0,0,0,0,0,0,AT30,0,0,0,0,0,~
0,0,0,0,0,0,0,0,0,0,0)';
      PINUSE='POWER';
      NO_LOAD_CHECK='Both';
      NO_IO_CHECK='Both';
      NO_ASSERT_CHECK='TRUE';
      NO_DIR_CHECK='TRUE';
      ALLOW_CONNECT='TRUE';
    'VDDCR_CPU0_AT28':
      PIN_NUMBER='(0,0,0,0,0,0,0,0,0,0,0,0,0,0,0,0,0,0,0,0,0,0,0,AT28,0,0,0,0,0,~
0,0,0,0,0,0,0,0,0,0,0)';
      PINUSE='POWER';
      NO_LOAD_CHECK='Both';
      NO_IO_CHECK='Both';
      NO_ASSERT_CHECK='TRUE';
      NO_DIR_CHECK='TRUE';
      ALLOW_CONNECT='TRUE';
    'VDDCR_CPU0_AT26':
      PIN_NUMBER='(0,0,0,0,0,0,0,0,0,0,0,0,0,0,0,0,0,0,0,0,0,0,0,AT26,0,0,0,0,0,~
0,0,0,0,0,0,0,0,0,0,0)';
      PINUSE='POWER';
      NO_LOAD_CHECK='Both';
      NO_IO_CHECK='Both';
      NO_ASSERT_CHECK='TRUE';
      NO_DIR_CHECK='TRUE';
      ALLOW_CONNECT='TRUE';
    'VDDCR_CPU0_AT24':
      PIN_NUMBER='(0,0,0,0,0,0,0,0,0,0,0,0,0,0,0,0,0,0,0,0,0,0,0,AT24,0,0,0,0,0,~
0,0,0,0,0,0,0,0,0,0,0)';
      PINUSE='POWER';
      NO_LOAD_CHECK='Both';
      NO_IO_CHECK='Both';
      NO_ASSERT_CHECK='TRUE';
      NO_DIR_CHECK='TRUE';
      ALLOW_CONNECT='TRUE';
    'VDDCR_CPU0_AR50':
      PIN_NUMBER='(0,0,0,0,0,0,0,0,0,0,0,0,0,0,0,0,0,0,0,0,0,0,0,AR50,0,0,0,0,0,~
0,0,0,0,0,0,0,0,0,0,0)';
      PINUSE='POWER';
      NO_LOAD_CHECK='Both';
      NO_IO_CHECK='Both';
      NO_ASSERT_CHECK='TRUE';
      NO_DIR_CHECK='TRUE';
      ALLOW_CONNECT='TRUE';
    'VDDCR_CPU0_AR48':
      PIN_NUMBER='(0,0,0,0,0,0,0,0,0,0,0,0,0,0,0,0,0,0,0,0,0,0,0,AR48,0,0,0,0,0,~
0,0,0,0,0,0,0,0,0,0,0)';
      PINUSE='POWER';
      NO_LOAD_CHECK='Both';
      NO_IO_CHECK='Both';
      NO_ASSERT_CHECK='TRUE';
      NO_DIR_CHECK='TRUE';
      ALLOW_CONNECT='TRUE';
    'VDDCR_CPU0_AR46':
      PIN_NUMBER='(0,0,0,0,0,0,0,0,0,0,0,0,0,0,0,0,0,0,0,0,0,0,0,AR46,0,0,0,0,0,~
0,0,0,0,0,0,0,0,0,0,0)';
      PINUSE='POWER';
      NO_LOAD_CHECK='Both';
      NO_IO_CHECK='Both';
      NO_ASSERT_CHECK='TRUE';
      NO_DIR_CHECK='TRUE';
      ALLOW_CONNECT='TRUE';
    'VDDCR_CPU0_AR44':
      PIN_NUMBER='(0,0,0,0,0,0,0,0,0,0,0,0,0,0,0,0,0,0,0,0,0,0,0,AR44,0,0,0,0,0,~
0,0,0,0,0,0,0,0,0,0,0)';
      PINUSE='POWER';
      NO_LOAD_CHECK='Both';
      NO_IO_CHECK='Both';
      NO_ASSERT_CHECK='TRUE';
      NO_DIR_CHECK='TRUE';
      ALLOW_CONNECT='TRUE';
    'VDDCR_CPU0_AR42':
      PIN_NUMBER='(0,0,0,0,0,0,0,0,0,0,0,0,0,0,0,0,0,0,0,0,0,0,0,AR42,0,0,0,0,0,~
0,0,0,0,0,0,0,0,0,0,0)';
      PINUSE='POWER';
      NO_LOAD_CHECK='Both';
      NO_IO_CHECK='Both';
      NO_ASSERT_CHECK='TRUE';
      NO_DIR_CHECK='TRUE';
      ALLOW_CONNECT='TRUE';
    'VDDCR_CPU0_AR40':
      PIN_NUMBER='(0,0,0,0,0,0,0,0,0,0,0,0,0,0,0,0,0,0,0,0,0,0,0,AR40,0,0,0,0,0,~
0,0,0,0,0,0,0,0,0,0,0)';
      PINUSE='POWER';
      NO_LOAD_CHECK='Both';
      NO_IO_CHECK='Both';
      NO_ASSERT_CHECK='TRUE';
      NO_DIR_CHECK='TRUE';
      ALLOW_CONNECT='TRUE';
    'VDDCR_CPU0_AR35':
      PIN_NUMBER='(0,0,0,0,0,0,0,0,0,0,0,0,0,0,0,0,0,0,0,0,0,0,0,AR35,0,0,0,0,0,~
0,0,0,0,0,0,0,0,0,0,0)';
      PINUSE='POWER';
      NO_LOAD_CHECK='Both';
      NO_IO_CHECK='Both';
      NO_ASSERT_CHECK='TRUE';
      NO_DIR_CHECK='TRUE';
      ALLOW_CONNECT='TRUE';
    'VDDCR_CPU0_AR33':
      PIN_NUMBER='(0,0,0,0,0,0,0,0,0,0,0,0,0,0,0,0,0,0,0,0,0,0,0,AR33,0,0,0,0,0,~
0,0,0,0,0,0,0,0,0,0,0)';
      PINUSE='POWER';
      NO_LOAD_CHECK='Both';
      NO_IO_CHECK='Both';
      NO_ASSERT_CHECK='TRUE';
      NO_DIR_CHECK='TRUE';
      ALLOW_CONNECT='TRUE';
    'VDDCR_CPU0_AR31':
      PIN_NUMBER='(0,0,0,0,0,0,0,0,0,0,0,0,0,0,0,0,0,0,0,0,0,0,0,AR31,0,0,0,0,0,~
0,0,0,0,0,0,0,0,0,0,0)';
      PINUSE='POWER';
      NO_LOAD_CHECK='Both';
      NO_IO_CHECK='Both';
      NO_ASSERT_CHECK='TRUE';
      NO_DIR_CHECK='TRUE';
      ALLOW_CONNECT='TRUE';
    'VDDCR_CPU0_AR29':
      PIN_NUMBER='(0,0,0,0,0,0,0,0,0,0,0,0,0,0,0,0,0,0,0,0,0,0,0,AR29,0,0,0,0,0,~
0,0,0,0,0,0,0,0,0,0,0)';
      PINUSE='POWER';
      NO_LOAD_CHECK='Both';
      NO_IO_CHECK='Both';
      NO_ASSERT_CHECK='TRUE';
      NO_DIR_CHECK='TRUE';
      ALLOW_CONNECT='TRUE';
    'VDDCR_CPU0_AR27':
      PIN_NUMBER='(0,0,0,0,0,0,0,0,0,0,0,0,0,0,0,0,0,0,0,0,0,0,0,AR27,0,0,0,0,0,~
0,0,0,0,0,0,0,0,0,0,0)';
      PINUSE='POWER';
      NO_LOAD_CHECK='Both';
      NO_IO_CHECK='Both';
      NO_ASSERT_CHECK='TRUE';
      NO_DIR_CHECK='TRUE';
      ALLOW_CONNECT='TRUE';
    'VDDCR_CPU0_AR25':
      PIN_NUMBER='(0,0,0,0,0,0,0,0,0,0,0,0,0,0,0,0,0,0,0,0,0,0,0,AR25,0,0,0,0,0,~
0,0,0,0,0,0,0,0,0,0,0)';
      PINUSE='POWER';
      NO_LOAD_CHECK='Both';
      NO_IO_CHECK='Both';
      NO_ASSERT_CHECK='TRUE';
      NO_DIR_CHECK='TRUE';
      ALLOW_CONNECT='TRUE';
    'VDDCR_CPU0_AR23':
      PIN_NUMBER='(0,0,0,0,0,0,0,0,0,0,0,0,0,0,0,0,0,0,0,0,0,0,0,AR23,0,0,0,0,0,~
0,0,0,0,0,0,0,0,0,0,0)';
      PINUSE='POWER';
      NO_LOAD_CHECK='Both';
      NO_IO_CHECK='Both';
      NO_ASSERT_CHECK='TRUE';
      NO_DIR_CHECK='TRUE';
      ALLOW_CONNECT='TRUE';
    'VDDCR_CPU0_AP53':
      PIN_NUMBER='(0,0,0,0,0,0,0,0,0,0,0,0,0,0,0,0,0,0,0,0,0,0,0,AP53,0,0,0,0,0,~
0,0,0,0,0,0,0,0,0,0,0)';
      PINUSE='POWER';
      NO_LOAD_CHECK='Both';
      NO_IO_CHECK='Both';
      NO_ASSERT_CHECK='TRUE';
      NO_DIR_CHECK='TRUE';
      ALLOW_CONNECT='TRUE';
    'VDDCR_CPU0_AP52':
      PIN_NUMBER='(0,0,0,0,0,0,0,0,0,0,0,0,0,0,0,0,0,0,0,0,0,0,0,AP52,0,0,0,0,0,~
0,0,0,0,0,0,0,0,0,0,0)';
      PINUSE='POWER';
      NO_LOAD_CHECK='Both';
      NO_IO_CHECK='Both';
      NO_ASSERT_CHECK='TRUE';
      NO_DIR_CHECK='TRUE';
      ALLOW_CONNECT='TRUE';
    'VDDCR_CPU0_AP50':
      PIN_NUMBER='(0,0,0,0,0,0,0,0,0,0,0,0,0,0,0,0,0,0,0,0,0,0,0,AP50,0,0,0,0,0,~
0,0,0,0,0,0,0,0,0,0,0)';
      PINUSE='POWER';
      NO_LOAD_CHECK='Both';
      NO_IO_CHECK='Both';
      NO_ASSERT_CHECK='TRUE';
      NO_DIR_CHECK='TRUE';
      ALLOW_CONNECT='TRUE';
    'VDDCR_CPU0_AP49':
      PIN_NUMBER='(0,0,0,0,0,0,0,0,0,0,0,0,0,0,0,0,0,0,0,0,0,0,0,AP49,0,0,0,0,0,~
0,0,0,0,0,0,0,0,0,0,0)';
      PINUSE='POWER';
      NO_LOAD_CHECK='Both';
      NO_IO_CHECK='Both';
      NO_ASSERT_CHECK='TRUE';
      NO_DIR_CHECK='TRUE';
      ALLOW_CONNECT='TRUE';
    'VDDCR_CPU0_AP47':
      PIN_NUMBER='(0,0,0,0,0,0,0,0,0,0,0,0,0,0,0,0,0,0,0,0,0,0,0,AP47,0,0,0,0,0,~
0,0,0,0,0,0,0,0,0,0,0)';
      PINUSE='POWER';
      NO_LOAD_CHECK='Both';
      NO_IO_CHECK='Both';
      NO_ASSERT_CHECK='TRUE';
      NO_DIR_CHECK='TRUE';
      ALLOW_CONNECT='TRUE';
    'VDDCR_CPU0_AP46':
      PIN_NUMBER='(0,0,0,0,0,0,0,0,0,0,0,0,0,0,0,0,0,0,0,0,0,0,0,AP46,0,0,0,0,0,~
0,0,0,0,0,0,0,0,0,0,0)';
      PINUSE='POWER';
      NO_LOAD_CHECK='Both';
      NO_IO_CHECK='Both';
      NO_ASSERT_CHECK='TRUE';
      NO_DIR_CHECK='TRUE';
      ALLOW_CONNECT='TRUE';
    'VDDCR_CPU0_AP44':
      PIN_NUMBER='(0,0,0,0,0,0,0,0,0,0,0,0,0,0,0,0,0,0,0,0,0,0,0,AP44,0,0,0,0,0,~
0,0,0,0,0,0,0,0,0,0,0)';
      PINUSE='POWER';
      NO_LOAD_CHECK='Both';
      NO_IO_CHECK='Both';
      NO_ASSERT_CHECK='TRUE';
      NO_DIR_CHECK='TRUE';
      ALLOW_CONNECT='TRUE';
    'VDDCR_CPU0_AP43':
      PIN_NUMBER='(0,0,0,0,0,0,0,0,0,0,0,0,0,0,0,0,0,0,0,0,0,0,0,AP43,0,0,0,0,0,~
0,0,0,0,0,0,0,0,0,0,0)';
      PINUSE='POWER';
      NO_LOAD_CHECK='Both';
      NO_IO_CHECK='Both';
      NO_ASSERT_CHECK='TRUE';
      NO_DIR_CHECK='TRUE';
      ALLOW_CONNECT='TRUE';
    'VDDCR_CPU0_AP33':
      PIN_NUMBER='(0,0,0,0,0,0,0,0,0,0,0,0,0,0,0,0,0,0,0,0,0,0,0,AP33,0,0,0,0,0,~
0,0,0,0,0,0,0,0,0,0,0)';
      PINUSE='POWER';
      NO_LOAD_CHECK='Both';
      NO_IO_CHECK='Both';
      NO_ASSERT_CHECK='TRUE';
      NO_DIR_CHECK='TRUE';
      ALLOW_CONNECT='TRUE';
    'VDDCR_CPU0_AP32':
      PIN_NUMBER='(0,0,0,0,0,0,0,0,0,0,0,0,0,0,0,0,0,0,0,0,0,0,0,AP32,0,0,0,0,0,~
0,0,0,0,0,0,0,0,0,0,0)';
      PINUSE='POWER';
      NO_LOAD_CHECK='Both';
      NO_IO_CHECK='Both';
      NO_ASSERT_CHECK='TRUE';
      NO_DIR_CHECK='TRUE';
      ALLOW_CONNECT='TRUE';
    'VDDCR_CPU0_AP30':
      PIN_NUMBER='(0,0,0,0,0,0,0,0,0,0,0,0,0,0,0,0,0,0,0,0,0,0,0,AP30,0,0,0,0,0,~
0,0,0,0,0,0,0,0,0,0,0)';
      PINUSE='POWER';
      NO_LOAD_CHECK='Both';
      NO_IO_CHECK='Both';
      NO_ASSERT_CHECK='TRUE';
      NO_DIR_CHECK='TRUE';
      ALLOW_CONNECT='TRUE';
    'VDDCR_CPU0_AP29':
      PIN_NUMBER='(0,0,0,0,0,0,0,0,0,0,0,0,0,0,0,0,0,0,0,0,0,0,0,AP29,0,0,0,0,0,~
0,0,0,0,0,0,0,0,0,0,0)';
      PINUSE='POWER';
      NO_LOAD_CHECK='Both';
      NO_IO_CHECK='Both';
      NO_ASSERT_CHECK='TRUE';
      NO_DIR_CHECK='TRUE';
      ALLOW_CONNECT='TRUE';
    'VDDCR_CPU0_AP27':
      PIN_NUMBER='(0,0,0,0,0,0,0,0,0,0,0,0,0,0,0,0,0,0,0,0,0,0,0,AP27,0,0,0,0,0,~
0,0,0,0,0,0,0,0,0,0,0)';
      PINUSE='POWER';
      NO_LOAD_CHECK='Both';
      NO_IO_CHECK='Both';
      NO_ASSERT_CHECK='TRUE';
      NO_DIR_CHECK='TRUE';
      ALLOW_CONNECT='TRUE';
    'VDDCR_CPU0_AP26':
      PIN_NUMBER='(0,0,0,0,0,0,0,0,0,0,0,0,0,0,0,0,0,0,0,0,0,0,0,AP26,0,0,0,0,0,~
0,0,0,0,0,0,0,0,0,0,0)';
      PINUSE='POWER';
      NO_LOAD_CHECK='Both';
      NO_IO_CHECK='Both';
      NO_ASSERT_CHECK='TRUE';
      NO_DIR_CHECK='TRUE';
      ALLOW_CONNECT='TRUE';
    'VDDCR_CPU0_AP24':
      PIN_NUMBER='(0,0,0,0,0,0,0,0,0,0,0,0,0,0,0,0,0,0,0,0,0,0,0,AP24,0,0,0,0,0,~
0,0,0,0,0,0,0,0,0,0,0)';
      PINUSE='POWER';
      NO_LOAD_CHECK='Both';
      NO_IO_CHECK='Both';
      NO_ASSERT_CHECK='TRUE';
      NO_DIR_CHECK='TRUE';
      ALLOW_CONNECT='TRUE';
    'VDDCR_CPU0_AP23':
      PIN_NUMBER='(0,0,0,0,0,0,0,0,0,0,0,0,0,0,0,0,0,0,0,0,0,0,0,AP23,0,0,0,0,0,~
0,0,0,0,0,0,0,0,0,0,0)';
      PINUSE='POWER';
      NO_LOAD_CHECK='Both';
      NO_IO_CHECK='Both';
      NO_ASSERT_CHECK='TRUE';
      NO_DIR_CHECK='TRUE';
      ALLOW_CONNECT='TRUE';
    'VDDCR_CPU0_AL41':
      PIN_NUMBER='(0,0,0,0,0,0,0,0,0,0,0,0,0,0,0,0,0,0,0,0,0,0,0,AL41,0,0,0,0,0,~
0,0,0,0,0,0,0,0,0,0,0)';
      PINUSE='POWER';
      NO_LOAD_CHECK='Both';
      NO_IO_CHECK='Both';
      NO_ASSERT_CHECK='TRUE';
      NO_DIR_CHECK='TRUE';
      ALLOW_CONNECT='TRUE';
    'VDDCR_CPU0_AL40':
      PIN_NUMBER='(0,0,0,0,0,0,0,0,0,0,0,0,0,0,0,0,0,0,0,0,0,0,0,AL40,0,0,0,0,0,~
0,0,0,0,0,0,0,0,0,0,0)';
      PINUSE='POWER';
      NO_LOAD_CHECK='Both';
      NO_IO_CHECK='Both';
      NO_ASSERT_CHECK='TRUE';
      NO_DIR_CHECK='TRUE';
      ALLOW_CONNECT='TRUE';
    'VDDCR_CPU0_AL36':
      PIN_NUMBER='(0,0,0,0,0,0,0,0,0,0,0,0,0,0,0,0,0,0,0,0,0,0,0,AL36,0,0,0,0,0,~
0,0,0,0,0,0,0,0,0,0,0)';
      PINUSE='POWER';
      NO_LOAD_CHECK='Both';
      NO_IO_CHECK='Both';
      NO_ASSERT_CHECK='TRUE';
      NO_DIR_CHECK='TRUE';
      ALLOW_CONNECT='TRUE';
    'VDDCR_CPU0_AL35':
      PIN_NUMBER='(0,0,0,0,0,0,0,0,0,0,0,0,0,0,0,0,0,0,0,0,0,0,0,AL35,0,0,0,0,0,~
0,0,0,0,0,0,0,0,0,0,0)';
      PINUSE='POWER';
      NO_LOAD_CHECK='Both';
      NO_IO_CHECK='Both';
      NO_ASSERT_CHECK='TRUE';
      NO_DIR_CHECK='TRUE';
      ALLOW_CONNECT='TRUE';
    'VDDCR_CPU0_AK53':
      PIN_NUMBER='(0,0,0,0,0,0,0,0,0,0,0,0,0,0,0,0,0,0,0,0,0,0,0,AK53,0,0,0,0,0,~
0,0,0,0,0,0,0,0,0,0,0)';
      PINUSE='POWER';
      NO_LOAD_CHECK='Both';
      NO_IO_CHECK='Both';
      NO_ASSERT_CHECK='TRUE';
      NO_DIR_CHECK='TRUE';
      ALLOW_CONNECT='TRUE';
    'VDDCR_CPU0_AK52':
      PIN_NUMBER='(0,0,0,0,0,0,0,0,0,0,0,0,0,0,0,0,0,0,0,0,0,0,0,AK52,0,0,0,0,0,~
0,0,0,0,0,0,0,0,0,0,0)';
      PINUSE='POWER';
      NO_LOAD_CHECK='Both';
      NO_IO_CHECK='Both';
      NO_ASSERT_CHECK='TRUE';
      NO_DIR_CHECK='TRUE';
      ALLOW_CONNECT='TRUE';
    'VDDCR_CPU0_AK50':
      PIN_NUMBER='(0,0,0,0,0,0,0,0,0,0,0,0,0,0,0,0,0,0,0,0,0,0,0,AK50,0,0,0,0,0,~
0,0,0,0,0,0,0,0,0,0,0)';
      PINUSE='POWER';
      NO_LOAD_CHECK='Both';
      NO_IO_CHECK='Both';
      NO_ASSERT_CHECK='TRUE';
      NO_DIR_CHECK='TRUE';
      ALLOW_CONNECT='TRUE';
    'VDDCR_CPU0_AK49':
      PIN_NUMBER='(0,0,0,0,0,0,0,0,0,0,0,0,0,0,0,0,0,0,0,0,0,0,0,AK49,0,0,0,0,0,~
0,0,0,0,0,0,0,0,0,0,0)';
      PINUSE='POWER';
      NO_LOAD_CHECK='Both';
      NO_IO_CHECK='Both';
      NO_ASSERT_CHECK='TRUE';
      NO_DIR_CHECK='TRUE';
      ALLOW_CONNECT='TRUE';
    'VDDCR_CPU0_AK47':
      PIN_NUMBER='(0,0,0,0,0,0,0,0,0,0,0,0,0,0,0,0,0,0,0,0,0,0,0,AK47,0,0,0,0,0,~
0,0,0,0,0,0,0,0,0,0,0)';
      PINUSE='POWER';
      NO_LOAD_CHECK='Both';
      NO_IO_CHECK='Both';
      NO_ASSERT_CHECK='TRUE';
      NO_DIR_CHECK='TRUE';
      ALLOW_CONNECT='TRUE';
    'VDDCR_CPU0_AK46':
      PIN_NUMBER='(0,0,0,0,0,0,0,0,0,0,0,0,0,0,0,0,0,0,0,0,0,0,0,AK46,0,0,0,0,0,~
0,0,0,0,0,0,0,0,0,0,0)';
      PINUSE='POWER';
      NO_LOAD_CHECK='Both';
      NO_IO_CHECK='Both';
      NO_ASSERT_CHECK='TRUE';
      NO_DIR_CHECK='TRUE';
      ALLOW_CONNECT='TRUE';
    'VDDCR_CPU0_AK44':
      PIN_NUMBER='(0,0,0,0,0,0,0,0,0,0,0,0,0,0,0,0,0,0,0,0,0,0,0,AK44,0,0,0,0,0,~
0,0,0,0,0,0,0,0,0,0,0)';
      PINUSE='POWER';
      NO_LOAD_CHECK='Both';
      NO_IO_CHECK='Both';
      NO_ASSERT_CHECK='TRUE';
      NO_DIR_CHECK='TRUE';
      ALLOW_CONNECT='TRUE';
    'VDDCR_CPU0_AK43':
      PIN_NUMBER='(0,0,0,0,0,0,0,0,0,0,0,0,0,0,0,0,0,0,0,0,0,0,0,AK43,0,0,0,0,0,~
0,0,0,0,0,0,0,0,0,0,0)';
      PINUSE='POWER';
      NO_LOAD_CHECK='Both';
      NO_IO_CHECK='Both';
      NO_ASSERT_CHECK='TRUE';
      NO_DIR_CHECK='TRUE';
      ALLOW_CONNECT='TRUE';
    'VDDCR_CPU0_AK33':
      PIN_NUMBER='(0,0,0,0,0,0,0,0,0,0,0,0,0,0,0,0,0,0,0,0,0,0,0,AK33,0,0,0,0,0,~
0,0,0,0,0,0,0,0,0,0,0)';
      PINUSE='POWER';
      NO_LOAD_CHECK='Both';
      NO_IO_CHECK='Both';
      NO_ASSERT_CHECK='TRUE';
      NO_DIR_CHECK='TRUE';
      ALLOW_CONNECT='TRUE';
    'VDDCR_CPU0_AK32':
      PIN_NUMBER='(0,0,0,0,0,0,0,0,0,0,0,0,0,0,0,0,0,0,0,0,0,0,0,AK32,0,0,0,0,0,~
0,0,0,0,0,0,0,0,0,0,0)';
      PINUSE='POWER';
      NO_LOAD_CHECK='Both';
      NO_IO_CHECK='Both';
      NO_ASSERT_CHECK='TRUE';
      NO_DIR_CHECK='TRUE';
      ALLOW_CONNECT='TRUE';
    'VDDCR_CPU0_AK30':
      PIN_NUMBER='(0,0,0,0,0,0,0,0,0,0,0,0,0,0,0,0,0,0,0,0,0,0,0,AK30,0,0,0,0,0,~
0,0,0,0,0,0,0,0,0,0,0)';
      PINUSE='POWER';
      NO_LOAD_CHECK='Both';
      NO_IO_CHECK='Both';
      NO_ASSERT_CHECK='TRUE';
      NO_DIR_CHECK='TRUE';
      ALLOW_CONNECT='TRUE';
    'VDDCR_CPU0_AK29':
      PIN_NUMBER='(0,0,0,0,0,0,0,0,0,0,0,0,0,0,0,0,0,0,0,0,0,0,0,AK29,0,0,0,0,0,~
0,0,0,0,0,0,0,0,0,0,0)';
      PINUSE='POWER';
      NO_LOAD_CHECK='Both';
      NO_IO_CHECK='Both';
      NO_ASSERT_CHECK='TRUE';
      NO_DIR_CHECK='TRUE';
      ALLOW_CONNECT='TRUE';
    'VDDCR_CPU0_AK27':
      PIN_NUMBER='(0,0,0,0,0,0,0,0,0,0,0,0,0,0,0,0,0,0,0,0,0,0,0,AK27,0,0,0,0,0,~
0,0,0,0,0,0,0,0,0,0,0)';
      PINUSE='POWER';
      NO_LOAD_CHECK='Both';
      NO_IO_CHECK='Both';
      NO_ASSERT_CHECK='TRUE';
      NO_DIR_CHECK='TRUE';
      ALLOW_CONNECT='TRUE';
    'VDDCR_CPU0_AK26':
      PIN_NUMBER='(0,0,0,0,0,0,0,0,0,0,0,0,0,0,0,0,0,0,0,0,0,0,0,AK26,0,0,0,0,0,~
0,0,0,0,0,0,0,0,0,0,0)';
      PINUSE='POWER';
      NO_LOAD_CHECK='Both';
      NO_IO_CHECK='Both';
      NO_ASSERT_CHECK='TRUE';
      NO_DIR_CHECK='TRUE';
      ALLOW_CONNECT='TRUE';
    'VDDCR_CPU0_AK24':
      PIN_NUMBER='(0,0,0,0,0,0,0,0,0,0,0,0,0,0,0,0,0,0,0,0,0,0,0,AK24,0,0,0,0,0,~
0,0,0,0,0,0,0,0,0,0,0)';
      PINUSE='POWER';
      NO_LOAD_CHECK='Both';
      NO_IO_CHECK='Both';
      NO_ASSERT_CHECK='TRUE';
      NO_DIR_CHECK='TRUE';
      ALLOW_CONNECT='TRUE';
    'VDDCR_CPU0_AK23':
      PIN_NUMBER='(0,0,0,0,0,0,0,0,0,0,0,0,0,0,0,0,0,0,0,0,0,0,0,AK23,0,0,0,0,0,~
0,0,0,0,0,0,0,0,0,0,0)';
      PINUSE='POWER';
      NO_LOAD_CHECK='Both';
      NO_IO_CHECK='Both';
      NO_ASSERT_CHECK='TRUE';
      NO_DIR_CHECK='TRUE';
      ALLOW_CONNECT='TRUE';
    'VDDCR_CPU0_AG41':
      PIN_NUMBER='(0,0,0,0,0,0,0,0,0,0,0,0,0,0,0,0,0,0,0,0,0,0,0,AG41,0,0,0,0,0,~
0,0,0,0,0,0,0,0,0,0,0)';
      PINUSE='POWER';
      NO_LOAD_CHECK='Both';
      NO_IO_CHECK='Both';
      NO_ASSERT_CHECK='TRUE';
      NO_DIR_CHECK='TRUE';
      ALLOW_CONNECT='TRUE';
    'VDDCR_CPU0_AG40':
      PIN_NUMBER='(0,0,0,0,0,0,0,0,0,0,0,0,0,0,0,0,0,0,0,0,0,0,0,AG40,0,0,0,0,0,~
0,0,0,0,0,0,0,0,0,0,0)';
      PINUSE='POWER';
      NO_LOAD_CHECK='Both';
      NO_IO_CHECK='Both';
      NO_ASSERT_CHECK='TRUE';
      NO_DIR_CHECK='TRUE';
      ALLOW_CONNECT='TRUE';
    'VDDCR_CPU0_AG36':
      PIN_NUMBER='(0,0,0,0,0,0,0,0,0,0,0,0,0,0,0,0,0,0,0,0,0,0,0,AG36,0,0,0,0,0,~
0,0,0,0,0,0,0,0,0,0,0)';
      PINUSE='POWER';
      NO_LOAD_CHECK='Both';
      NO_IO_CHECK='Both';
      NO_ASSERT_CHECK='TRUE';
      NO_DIR_CHECK='TRUE';
      ALLOW_CONNECT='TRUE';
    'VDDCR_CPU0_AG35':
      PIN_NUMBER='(0,0,0,0,0,0,0,0,0,0,0,0,0,0,0,0,0,0,0,0,0,0,0,AG35,0,0,0,0,0,~
0,0,0,0,0,0,0,0,0,0,0)';
      PINUSE='POWER';
      NO_LOAD_CHECK='Both';
      NO_IO_CHECK='Both';
      NO_ASSERT_CHECK='TRUE';
      NO_DIR_CHECK='TRUE';
      ALLOW_CONNECT='TRUE';
    'VDDCR_CPU0_AF53':
      PIN_NUMBER='(0,0,0,0,0,0,0,0,0,0,0,0,0,0,0,0,0,0,0,0,0,0,0,AF53,0,0,0,0,0,~
0,0,0,0,0,0,0,0,0,0,0)';
      PINUSE='POWER';
      NO_LOAD_CHECK='Both';
      NO_IO_CHECK='Both';
      NO_ASSERT_CHECK='TRUE';
      NO_DIR_CHECK='TRUE';
      ALLOW_CONNECT='TRUE';
    'VDDCR_CPU0_AF52':
      PIN_NUMBER='(0,0,0,0,0,0,0,0,0,0,0,0,0,0,0,0,0,0,0,0,0,0,0,AF52,0,0,0,0,0,~
0,0,0,0,0,0,0,0,0,0,0)';
      PINUSE='POWER';
      NO_LOAD_CHECK='Both';
      NO_IO_CHECK='Both';
      NO_ASSERT_CHECK='TRUE';
      NO_DIR_CHECK='TRUE';
      ALLOW_CONNECT='TRUE';
    'VDDCR_CPU0_AF50':
      PIN_NUMBER='(0,0,0,0,0,0,0,0,0,0,0,0,0,0,0,0,0,0,0,0,0,0,0,AF50,0,0,0,0,0,~
0,0,0,0,0,0,0,0,0,0,0)';
      PINUSE='POWER';
      NO_LOAD_CHECK='Both';
      NO_IO_CHECK='Both';
      NO_ASSERT_CHECK='TRUE';
      NO_DIR_CHECK='TRUE';
      ALLOW_CONNECT='TRUE';
    'VDDCR_CPU0_AF49':
      PIN_NUMBER='(0,0,0,0,0,0,0,0,0,0,0,0,0,0,0,0,0,0,0,0,0,0,0,AF49,0,0,0,0,0,~
0,0,0,0,0,0,0,0,0,0,0)';
      PINUSE='POWER';
      NO_LOAD_CHECK='Both';
      NO_IO_CHECK='Both';
      NO_ASSERT_CHECK='TRUE';
      NO_DIR_CHECK='TRUE';
      ALLOW_CONNECT='TRUE';
    'VDDCR_CPU0_AF47':
      PIN_NUMBER='(0,0,0,0,0,0,0,0,0,0,0,0,0,0,0,0,0,0,0,0,0,0,0,AF47,0,0,0,0,0,~
0,0,0,0,0,0,0,0,0,0,0)';
      PINUSE='POWER';
      NO_LOAD_CHECK='Both';
      NO_IO_CHECK='Both';
      NO_ASSERT_CHECK='TRUE';
      NO_DIR_CHECK='TRUE';
      ALLOW_CONNECT='TRUE';
    'VDDCR_CPU0_AF46':
      PIN_NUMBER='(0,0,0,0,0,0,0,0,0,0,0,0,0,0,0,0,0,0,0,0,0,0,0,AF46,0,0,0,0,0,~
0,0,0,0,0,0,0,0,0,0,0)';
      PINUSE='POWER';
      NO_LOAD_CHECK='Both';
      NO_IO_CHECK='Both';
      NO_ASSERT_CHECK='TRUE';
      NO_DIR_CHECK='TRUE';
      ALLOW_CONNECT='TRUE';
    'VDDCR_CPU0_AF44':
      PIN_NUMBER='(0,0,0,0,0,0,0,0,0,0,0,0,0,0,0,0,0,0,0,0,0,0,0,AF44,0,0,0,0,0,~
0,0,0,0,0,0,0,0,0,0,0)';
      PINUSE='POWER';
      NO_LOAD_CHECK='Both';
      NO_IO_CHECK='Both';
      NO_ASSERT_CHECK='TRUE';
      NO_DIR_CHECK='TRUE';
      ALLOW_CONNECT='TRUE';
    'VDDCR_CPU0_AF43':
      PIN_NUMBER='(0,0,0,0,0,0,0,0,0,0,0,0,0,0,0,0,0,0,0,0,0,0,0,AF43,0,0,0,0,0,~
0,0,0,0,0,0,0,0,0,0,0)';
      PINUSE='POWER';
      NO_LOAD_CHECK='Both';
      NO_IO_CHECK='Both';
      NO_ASSERT_CHECK='TRUE';
      NO_DIR_CHECK='TRUE';
      ALLOW_CONNECT='TRUE';
    'VDDCR_CPU0_AF33':
      PIN_NUMBER='(0,0,0,0,0,0,0,0,0,0,0,0,0,0,0,0,0,0,0,0,0,0,0,AF33,0,0,0,0,0,~
0,0,0,0,0,0,0,0,0,0,0)';
      PINUSE='POWER';
      NO_LOAD_CHECK='Both';
      NO_IO_CHECK='Both';
      NO_ASSERT_CHECK='TRUE';
      NO_DIR_CHECK='TRUE';
      ALLOW_CONNECT='TRUE';
    'VDDCR_CPU0_AF32':
      PIN_NUMBER='(0,0,0,0,0,0,0,0,0,0,0,0,0,0,0,0,0,0,0,0,0,0,0,AF32,0,0,0,0,0,~
0,0,0,0,0,0,0,0,0,0,0)';
      PINUSE='POWER';
      NO_LOAD_CHECK='Both';
      NO_IO_CHECK='Both';
      NO_ASSERT_CHECK='TRUE';
      NO_DIR_CHECK='TRUE';
      ALLOW_CONNECT='TRUE';
    'VDDCR_CPU0_AF30':
      PIN_NUMBER='(0,0,0,0,0,0,0,0,0,0,0,0,0,0,0,0,0,0,0,0,0,0,0,AF30,0,0,0,0,0,~
0,0,0,0,0,0,0,0,0,0,0)';
      PINUSE='POWER';
      NO_LOAD_CHECK='Both';
      NO_IO_CHECK='Both';
      NO_ASSERT_CHECK='TRUE';
      NO_DIR_CHECK='TRUE';
      ALLOW_CONNECT='TRUE';
    'VDDCR_CPU0_AF29':
      PIN_NUMBER='(0,0,0,0,0,0,0,0,0,0,0,0,0,0,0,0,0,0,0,0,0,0,0,AF29,0,0,0,0,0,~
0,0,0,0,0,0,0,0,0,0,0)';
      PINUSE='POWER';
      NO_LOAD_CHECK='Both';
      NO_IO_CHECK='Both';
      NO_ASSERT_CHECK='TRUE';
      NO_DIR_CHECK='TRUE';
      ALLOW_CONNECT='TRUE';
    'VDDCR_CPU0_AF27':
      PIN_NUMBER='(0,0,0,0,0,0,0,0,0,0,0,0,0,0,0,0,0,0,0,0,0,0,0,AF27,0,0,0,0,0,~
0,0,0,0,0,0,0,0,0,0,0)';
      PINUSE='POWER';
      NO_LOAD_CHECK='Both';
      NO_IO_CHECK='Both';
      NO_ASSERT_CHECK='TRUE';
      NO_DIR_CHECK='TRUE';
      ALLOW_CONNECT='TRUE';
    'VDDCR_CPU0_AF26':
      PIN_NUMBER='(0,0,0,0,0,0,0,0,0,0,0,0,0,0,0,0,0,0,0,0,0,0,0,AF26,0,0,0,0,0,~
0,0,0,0,0,0,0,0,0,0,0)';
      PINUSE='POWER';
      NO_LOAD_CHECK='Both';
      NO_IO_CHECK='Both';
      NO_ASSERT_CHECK='TRUE';
      NO_DIR_CHECK='TRUE';
      ALLOW_CONNECT='TRUE';
    'VDDCR_CPU0_AF24':
      PIN_NUMBER='(0,0,0,0,0,0,0,0,0,0,0,0,0,0,0,0,0,0,0,0,0,0,0,AF24,0,0,0,0,0,~
0,0,0,0,0,0,0,0,0,0,0)';
      PINUSE='POWER';
      NO_LOAD_CHECK='Both';
      NO_IO_CHECK='Both';
      NO_ASSERT_CHECK='TRUE';
      NO_DIR_CHECK='TRUE';
      ALLOW_CONNECT='TRUE';
    'VDDCR_CPU0_AF23':
      PIN_NUMBER='(0,0,0,0,0,0,0,0,0,0,0,0,0,0,0,0,0,0,0,0,0,0,0,AF23,0,0,0,0,0,~
0,0,0,0,0,0,0,0,0,0,0)';
      PINUSE='POWER';
      NO_LOAD_CHECK='Both';
      NO_IO_CHECK='Both';
      NO_ASSERT_CHECK='TRUE';
      NO_DIR_CHECK='TRUE';
      ALLOW_CONNECT='TRUE';
    'VDDCR_CPU0_AC41':
      PIN_NUMBER='(0,0,0,0,0,0,0,0,0,0,0,0,0,0,0,0,0,0,0,0,0,0,0,AC41,0,0,0,0,0,~
0,0,0,0,0,0,0,0,0,0,0)';
      PINUSE='POWER';
      NO_LOAD_CHECK='Both';
      NO_IO_CHECK='Both';
      NO_ASSERT_CHECK='TRUE';
      NO_DIR_CHECK='TRUE';
      ALLOW_CONNECT='TRUE';
    'VDDCR_CPU0_AC40':
      PIN_NUMBER='(0,0,0,0,0,0,0,0,0,0,0,0,0,0,0,0,0,0,0,0,0,0,0,AC40,0,0,0,0,0,~
0,0,0,0,0,0,0,0,0,0,0)';
      PINUSE='POWER';
      NO_LOAD_CHECK='Both';
      NO_IO_CHECK='Both';
      NO_ASSERT_CHECK='TRUE';
      NO_DIR_CHECK='TRUE';
      ALLOW_CONNECT='TRUE';
    'VDDCR_CPU0_AC36':
      PIN_NUMBER='(0,0,0,0,0,0,0,0,0,0,0,0,0,0,0,0,0,0,0,0,0,0,0,AC36,0,0,0,0,0,~
0,0,0,0,0,0,0,0,0,0,0)';
      PINUSE='POWER';
      NO_LOAD_CHECK='Both';
      NO_IO_CHECK='Both';
      NO_ASSERT_CHECK='TRUE';
      NO_DIR_CHECK='TRUE';
      ALLOW_CONNECT='TRUE';
    'VDDCR_CPU0_AC35':
      PIN_NUMBER='(0,0,0,0,0,0,0,0,0,0,0,0,0,0,0,0,0,0,0,0,0,0,0,AC35,0,0,0,0,0,~
0,0,0,0,0,0,0,0,0,0,0)';
      PINUSE='POWER';
      NO_LOAD_CHECK='Both';
      NO_IO_CHECK='Both';
      NO_ASSERT_CHECK='TRUE';
      NO_DIR_CHECK='TRUE';
      ALLOW_CONNECT='TRUE';
    'VDDCR_CPU0_AB53':
      PIN_NUMBER='(0,0,0,0,0,0,0,0,0,0,0,0,0,0,0,0,0,0,0,0,0,0,0,AB53,0,0,0,0,0,~
0,0,0,0,0,0,0,0,0,0,0)';
      PINUSE='POWER';
      NO_LOAD_CHECK='Both';
      NO_IO_CHECK='Both';
      NO_ASSERT_CHECK='TRUE';
      NO_DIR_CHECK='TRUE';
      ALLOW_CONNECT='TRUE';
    'VDDCR_CPU0_AB52':
      PIN_NUMBER='(0,0,0,0,0,0,0,0,0,0,0,0,0,0,0,0,0,0,0,0,0,0,0,AB52,0,0,0,0,0,~
0,0,0,0,0,0,0,0,0,0,0)';
      PINUSE='POWER';
      NO_LOAD_CHECK='Both';
      NO_IO_CHECK='Both';
      NO_ASSERT_CHECK='TRUE';
      NO_DIR_CHECK='TRUE';
      ALLOW_CONNECT='TRUE';
    'VDDCR_CPU0_AB50':
      PIN_NUMBER='(0,0,0,0,0,0,0,0,0,0,0,0,0,0,0,0,0,0,0,0,0,0,0,AB50,0,0,0,0,0,~
0,0,0,0,0,0,0,0,0,0,0)';
      PINUSE='POWER';
      NO_LOAD_CHECK='Both';
      NO_IO_CHECK='Both';
      NO_ASSERT_CHECK='TRUE';
      NO_DIR_CHECK='TRUE';
      ALLOW_CONNECT='TRUE';
    'VDDCR_CPU0_AB49':
      PIN_NUMBER='(0,0,0,0,0,0,0,0,0,0,0,0,0,0,0,0,0,0,0,0,0,0,0,AB49,0,0,0,0,0,~
0,0,0,0,0,0,0,0,0,0,0)';
      PINUSE='POWER';
      NO_LOAD_CHECK='Both';
      NO_IO_CHECK='Both';
      NO_ASSERT_CHECK='TRUE';
      NO_DIR_CHECK='TRUE';
      ALLOW_CONNECT='TRUE';
    'VDDCR_CPU0_AB47':
      PIN_NUMBER='(0,0,0,0,0,0,0,0,0,0,0,0,0,0,0,0,0,0,0,0,0,0,0,AB47,0,0,0,0,0,~
0,0,0,0,0,0,0,0,0,0,0)';
      PINUSE='POWER';
      NO_LOAD_CHECK='Both';
      NO_IO_CHECK='Both';
      NO_ASSERT_CHECK='TRUE';
      NO_DIR_CHECK='TRUE';
      ALLOW_CONNECT='TRUE';
    'VDDCR_CPU0_AB46':
      PIN_NUMBER='(0,0,0,0,0,0,0,0,0,0,0,0,0,0,0,0,0,0,0,0,0,0,0,AB46,0,0,0,0,0,~
0,0,0,0,0,0,0,0,0,0,0)';
      PINUSE='POWER';
      NO_LOAD_CHECK='Both';
      NO_IO_CHECK='Both';
      NO_ASSERT_CHECK='TRUE';
      NO_DIR_CHECK='TRUE';
      ALLOW_CONNECT='TRUE';
    'VDDCR_CPU0_AB44':
      PIN_NUMBER='(0,0,0,0,0,0,0,0,0,0,0,0,0,0,0,0,0,0,0,0,0,0,0,AB44,0,0,0,0,0,~
0,0,0,0,0,0,0,0,0,0,0)';
      PINUSE='POWER';
      NO_LOAD_CHECK='Both';
      NO_IO_CHECK='Both';
      NO_ASSERT_CHECK='TRUE';
      NO_DIR_CHECK='TRUE';
      ALLOW_CONNECT='TRUE';
    'VDDCR_CPU0_AB43':
      PIN_NUMBER='(0,0,0,0,0,0,0,0,0,0,0,0,0,0,0,0,0,0,0,0,0,0,0,AB43,0,0,0,0,0,~
0,0,0,0,0,0,0,0,0,0,0)';
      PINUSE='POWER';
      NO_LOAD_CHECK='Both';
      NO_IO_CHECK='Both';
      NO_ASSERT_CHECK='TRUE';
      NO_DIR_CHECK='TRUE';
      ALLOW_CONNECT='TRUE';
    'VDDCR_CPU0_AB33':
      PIN_NUMBER='(0,0,0,0,0,0,0,0,0,0,0,0,0,0,0,0,0,0,0,0,0,0,0,AB33,0,0,0,0,0,~
0,0,0,0,0,0,0,0,0,0,0)';
      PINUSE='POWER';
      NO_LOAD_CHECK='Both';
      NO_IO_CHECK='Both';
      NO_ASSERT_CHECK='TRUE';
      NO_DIR_CHECK='TRUE';
      ALLOW_CONNECT='TRUE';
    'VDDCR_CPU0_AB32':
      PIN_NUMBER='(0,0,0,0,0,0,0,0,0,0,0,0,0,0,0,0,0,0,0,0,0,0,0,AB32,0,0,0,0,0,~
0,0,0,0,0,0,0,0,0,0,0)';
      PINUSE='POWER';
      NO_LOAD_CHECK='Both';
      NO_IO_CHECK='Both';
      NO_ASSERT_CHECK='TRUE';
      NO_DIR_CHECK='TRUE';
      ALLOW_CONNECT='TRUE';
    'VDDCR_CPU0_AB30':
      PIN_NUMBER='(0,0,0,0,0,0,0,0,0,0,0,0,0,0,0,0,0,0,0,0,0,0,0,AB30,0,0,0,0,0,~
0,0,0,0,0,0,0,0,0,0,0)';
      PINUSE='POWER';
      NO_LOAD_CHECK='Both';
      NO_IO_CHECK='Both';
      NO_ASSERT_CHECK='TRUE';
      NO_DIR_CHECK='TRUE';
      ALLOW_CONNECT='TRUE';
    'VDDCR_CPU0_AB29':
      PIN_NUMBER='(0,0,0,0,0,0,0,0,0,0,0,0,0,0,0,0,0,0,0,0,0,0,0,AB29,0,0,0,0,0,~
0,0,0,0,0,0,0,0,0,0,0)';
      PINUSE='POWER';
      NO_LOAD_CHECK='Both';
      NO_IO_CHECK='Both';
      NO_ASSERT_CHECK='TRUE';
      NO_DIR_CHECK='TRUE';
      ALLOW_CONNECT='TRUE';
    'VDDCR_CPU0_AB27':
      PIN_NUMBER='(0,0,0,0,0,0,0,0,0,0,0,0,0,0,0,0,0,0,0,0,0,0,0,AB27,0,0,0,0,0,~
0,0,0,0,0,0,0,0,0,0,0)';
      PINUSE='POWER';
      NO_LOAD_CHECK='Both';
      NO_IO_CHECK='Both';
      NO_ASSERT_CHECK='TRUE';
      NO_DIR_CHECK='TRUE';
      ALLOW_CONNECT='TRUE';
    'VDDCR_CPU0_AB26':
      PIN_NUMBER='(0,0,0,0,0,0,0,0,0,0,0,0,0,0,0,0,0,0,0,0,0,0,0,AB26,0,0,0,0,0,~
0,0,0,0,0,0,0,0,0,0,0)';
      PINUSE='POWER';
      NO_LOAD_CHECK='Both';
      NO_IO_CHECK='Both';
      NO_ASSERT_CHECK='TRUE';
      NO_DIR_CHECK='TRUE';
      ALLOW_CONNECT='TRUE';
    'VDDCR_CPU0_AB24':
      PIN_NUMBER='(0,0,0,0,0,0,0,0,0,0,0,0,0,0,0,0,0,0,0,0,0,0,0,AB24,0,0,0,0,0,~
0,0,0,0,0,0,0,0,0,0,0)';
      PINUSE='POWER';
      NO_LOAD_CHECK='Both';
      NO_IO_CHECK='Both';
      NO_ASSERT_CHECK='TRUE';
      NO_DIR_CHECK='TRUE';
      ALLOW_CONNECT='TRUE';
    'VDDCR_CPU0_AB23':
      PIN_NUMBER='(0,0,0,0,0,0,0,0,0,0,0,0,0,0,0,0,0,0,0,0,0,0,0,AB23,0,0,0,0,0,~
0,0,0,0,0,0,0,0,0,0,0)';
      PINUSE='POWER';
      NO_LOAD_CHECK='Both';
      NO_IO_CHECK='Both';
      NO_ASSERT_CHECK='TRUE';
      NO_DIR_CHECK='TRUE';
      ALLOW_CONNECT='TRUE';
    'VDDCR_CPU0_Y41':
      PIN_NUMBER='(0,0,0,0,0,0,0,0,0,0,0,0,0,0,0,0,0,0,0,0,0,0,0,Y41,0,0,0,0,0,0~
,0,0,0,0,0,0,0,0,0,0)';
      PINUSE='POWER';
      NO_LOAD_CHECK='Both';
      NO_IO_CHECK='Both';
      NO_ASSERT_CHECK='TRUE';
      NO_DIR_CHECK='TRUE';
      ALLOW_CONNECT='TRUE';
    'VDDCR_CPU0_Y40':
      PIN_NUMBER='(0,0,0,0,0,0,0,0,0,0,0,0,0,0,0,0,0,0,0,0,0,0,0,Y40,0,0,0,0,0,0~
,0,0,0,0,0,0,0,0,0,0)';
      PINUSE='POWER';
      NO_LOAD_CHECK='Both';
      NO_IO_CHECK='Both';
      NO_ASSERT_CHECK='TRUE';
      NO_DIR_CHECK='TRUE';
      ALLOW_CONNECT='TRUE';
    'VDDCR_CPU0_Y36':
      PIN_NUMBER='(0,0,0,0,0,0,0,0,0,0,0,0,0,0,0,0,0,0,0,0,0,0,0,Y36,0,0,0,0,0,0~
,0,0,0,0,0,0,0,0,0,0)';
      PINUSE='POWER';
      NO_LOAD_CHECK='Both';
      NO_IO_CHECK='Both';
      NO_ASSERT_CHECK='TRUE';
      NO_DIR_CHECK='TRUE';
      ALLOW_CONNECT='TRUE';
    'VDDCR_CPU0_Y35':
      PIN_NUMBER='(0,0,0,0,0,0,0,0,0,0,0,0,0,0,0,0,0,0,0,0,0,0,0,Y35,0,0,0,0,0,0~
,0,0,0,0,0,0,0,0,0,0)';
      PINUSE='POWER';
      NO_LOAD_CHECK='Both';
      NO_IO_CHECK='Both';
      NO_ASSERT_CHECK='TRUE';
      NO_DIR_CHECK='TRUE';
      ALLOW_CONNECT='TRUE';
    'VDDCR_CPU0_AU42':
      PIN_NUMBER='(0,0,0,0,0,0,0,0,0,0,0,0,0,0,0,0,0,0,0,0,0,0,0,AU42,0,0,0,0,0,~
0,0,0,0,0,0,0,0,0,0,0)';
      PINUSE='POWER';
      NO_LOAD_CHECK='Both';
      NO_IO_CHECK='Both';
      NO_ASSERT_CHECK='TRUE';
      NO_DIR_CHECK='TRUE';
      ALLOW_CONNECT='TRUE';
    'VDDCR_CPU0_AU46':
      PIN_NUMBER='(0,0,0,0,0,0,0,0,0,0,0,0,0,0,0,0,0,0,0,0,0,0,0,AU46,0,0,0,0,0,~
0,0,0,0,0,0,0,0,0,0,0)';
      PINUSE='POWER';
      NO_LOAD_CHECK='Both';
      NO_IO_CHECK='Both';
      NO_ASSERT_CHECK='TRUE';
      NO_DIR_CHECK='TRUE';
      ALLOW_CONNECT='TRUE';
    'VDDCR_CPU0_AT49':
      PIN_NUMBER='(0,0,0,0,0,0,0,0,0,0,0,0,0,0,0,0,0,0,0,0,0,0,0,AT49,0,0,0,0,0,~
0,0,0,0,0,0,0,0,0,0,0)';
      PINUSE='POWER';
      NO_LOAD_CHECK='Both';
      NO_IO_CHECK='Both';
      NO_ASSERT_CHECK='TRUE';
      NO_DIR_CHECK='TRUE';
      ALLOW_CONNECT='TRUE';
    'VDDCR_CPU0_AU29':
      PIN_NUMBER='(0,0,0,0,0,0,0,0,0,0,0,0,0,0,0,0,0,0,0,0,0,0,0,AU29,0,0,0,0,0,~
0,0,0,0,0,0,0,0,0,0,0)';
      PINUSE='POWER';
      NO_LOAD_CHECK='Both';
      NO_IO_CHECK='Both';
      NO_ASSERT_CHECK='TRUE';
      NO_DIR_CHECK='TRUE';
      ALLOW_CONNECT='TRUE';
    'VDDCR_CPU0_AU44':
      PIN_NUMBER='(0,0,0,0,0,0,0,0,0,0,0,0,0,0,0,0,0,0,0,0,0,0,0,AU44,0,0,0,0,0,~
0,0,0,0,0,0,0,0,0,0,0)';
      PINUSE='POWER';
      NO_LOAD_CHECK='Both';
      NO_IO_CHECK='Both';
      NO_ASSERT_CHECK='TRUE';
      NO_DIR_CHECK='TRUE';
      ALLOW_CONNECT='TRUE';
    'VDDCR_CPU0_AU48':
      PIN_NUMBER='(0,0,0,0,0,0,0,0,0,0,0,0,0,0,0,0,0,0,0,0,0,0,0,AU48,0,0,0,0,0,~
0,0,0,0,0,0,0,0,0,0,0)';
      PINUSE='POWER';
      NO_LOAD_CHECK='Both';
      NO_IO_CHECK='Both';
      NO_ASSERT_CHECK='TRUE';
      NO_DIR_CHECK='TRUE';
      ALLOW_CONNECT='TRUE';
    'VDDCR_CPU0_AU25':
      PIN_NUMBER='(0,0,0,0,0,0,0,0,0,0,0,0,0,0,0,0,0,0,0,0,0,0,0,AU25,0,0,0,0,0,~
0,0,0,0,0,0,0,0,0,0,0)';
      PINUSE='POWER';
      NO_LOAD_CHECK='Both';
      NO_IO_CHECK='Both';
      NO_ASSERT_CHECK='TRUE';
      NO_DIR_CHECK='TRUE';
      ALLOW_CONNECT='TRUE';
    'VDDCR_CPU0_AU33':
      PIN_NUMBER='(0,0,0,0,0,0,0,0,0,0,0,0,0,0,0,0,0,0,0,0,0,0,0,AU33,0,0,0,0,0,~
0,0,0,0,0,0,0,0,0,0,0)';
      PINUSE='POWER';
      NO_LOAD_CHECK='Both';
      NO_IO_CHECK='Both';
      NO_ASSERT_CHECK='TRUE';
      NO_DIR_CHECK='TRUE';
      ALLOW_CONNECT='TRUE';
    'VDDCR_CPU1_BN31':
      PIN_NUMBER='(0,0,0,0,0,0,0,0,0,0,0,0,0,0,0,0,0,0,0,0,0,0,0,0,BN31,0,0,0,0,~
0,0,0,0,0,0,0,0,0,0,0)';
      PINUSE='POWER';
      NO_LOAD_CHECK='Both';
      NO_IO_CHECK='Both';
      NO_ASSERT_CHECK='TRUE';
      NO_DIR_CHECK='TRUE';
      ALLOW_CONNECT='TRUE';
    'VDDCR_CPU1_BN42':
      PIN_NUMBER='(0,0,0,0,0,0,0,0,0,0,0,0,0,0,0,0,0,0,0,0,0,0,0,0,BN42,0,0,0,0,~
0,0,0,0,0,0,0,0,0,0,0)';
      PINUSE='POWER';
      NO_LOAD_CHECK='Both';
      NO_IO_CHECK='Both';
      NO_ASSERT_CHECK='TRUE';
      NO_DIR_CHECK='TRUE';
      ALLOW_CONNECT='TRUE';
    'VDDCR_CPU1_BN50':
      PIN_NUMBER='(0,0,0,0,0,0,0,0,0,0,0,0,0,0,0,0,0,0,0,0,0,0,0,0,BN50,0,0,0,0,~
0,0,0,0,0,0,0,0,0,0,0)';
      PINUSE='POWER';
      NO_LOAD_CHECK='Both';
      NO_IO_CHECK='Both';
      NO_ASSERT_CHECK='TRUE';
      NO_DIR_CHECK='TRUE';
      ALLOW_CONNECT='TRUE';
    'VDDCR_CPU1_BP26':
      PIN_NUMBER='(0,0,0,0,0,0,0,0,0,0,0,0,0,0,0,0,0,0,0,0,0,0,0,0,BP26,0,0,0,0,~
0,0,0,0,0,0,0,0,0,0,0)';
      PINUSE='POWER';
      NO_LOAD_CHECK='Both';
      NO_IO_CHECK='Both';
      NO_ASSERT_CHECK='TRUE';
      NO_DIR_CHECK='TRUE';
      ALLOW_CONNECT='TRUE';
    'VDDCR_CPU1_BP30':
      PIN_NUMBER='(0,0,0,0,0,0,0,0,0,0,0,0,0,0,0,0,0,0,0,0,0,0,0,0,BP30,0,0,0,0,~
0,0,0,0,0,0,0,0,0,0,0)';
      PINUSE='POWER';
      NO_LOAD_CHECK='Both';
      NO_IO_CHECK='Both';
      NO_ASSERT_CHECK='TRUE';
      NO_DIR_CHECK='TRUE';
      ALLOW_CONNECT='TRUE';
    'VDDCR_CPU1_BP34':
      PIN_NUMBER='(0,0,0,0,0,0,0,0,0,0,0,0,0,0,0,0,0,0,0,0,0,0,0,0,BP34,0,0,0,0,~
0,0,0,0,0,0,0,0,0,0,0)';
      PINUSE='POWER';
      NO_LOAD_CHECK='Both';
      NO_IO_CHECK='Both';
      NO_ASSERT_CHECK='TRUE';
      NO_DIR_CHECK='TRUE';
      ALLOW_CONNECT='TRUE';
    'VDDCR_CPU1_BP36':
      PIN_NUMBER='(0,0,0,0,0,0,0,0,0,0,0,0,0,0,0,0,0,0,0,0,0,0,0,0,BP36,0,0,0,0,~
0,0,0,0,0,0,0,0,0,0,0)';
      PINUSE='POWER';
      NO_LOAD_CHECK='Both';
      NO_IO_CHECK='Both';
      NO_ASSERT_CHECK='TRUE';
      NO_DIR_CHECK='TRUE';
      ALLOW_CONNECT='TRUE';
    'VDDCR_CPU1_BP39':
      PIN_NUMBER='(0,0,0,0,0,0,0,0,0,0,0,0,0,0,0,0,0,0,0,0,0,0,0,0,BP39,0,0,0,0,~
0,0,0,0,0,0,0,0,0,0,0)';
      PINUSE='POWER';
      NO_LOAD_CHECK='Both';
      NO_IO_CHECK='Both';
      NO_ASSERT_CHECK='TRUE';
      NO_DIR_CHECK='TRUE';
      ALLOW_CONNECT='TRUE';
    'VDDCR_CPU1_BP41':
      PIN_NUMBER='(0,0,0,0,0,0,0,0,0,0,0,0,0,0,0,0,0,0,0,0,0,0,0,0,BP41,0,0,0,0,~
0,0,0,0,0,0,0,0,0,0,0)';
      PINUSE='POWER';
      NO_LOAD_CHECK='Both';
      NO_IO_CHECK='Both';
      NO_ASSERT_CHECK='TRUE';
      NO_DIR_CHECK='TRUE';
      ALLOW_CONNECT='TRUE';
    'VDDCR_CPU1_BP43':
      PIN_NUMBER='(0,0,0,0,0,0,0,0,0,0,0,0,0,0,0,0,0,0,0,0,0,0,0,0,BP43,0,0,0,0,~
0,0,0,0,0,0,0,0,0,0,0)';
      PINUSE='POWER';
      NO_LOAD_CHECK='Both';
      NO_IO_CHECK='Both';
      NO_ASSERT_CHECK='TRUE';
      NO_DIR_CHECK='TRUE';
      ALLOW_CONNECT='TRUE';
    'VDDCR_CPU1_BP45':
      PIN_NUMBER='(0,0,0,0,0,0,0,0,0,0,0,0,0,0,0,0,0,0,0,0,0,0,0,0,BP45,0,0,0,0,~
0,0,0,0,0,0,0,0,0,0,0)';
      PINUSE='POWER';
      NO_LOAD_CHECK='Both';
      NO_IO_CHECK='Both';
      NO_ASSERT_CHECK='TRUE';
      NO_DIR_CHECK='TRUE';
      ALLOW_CONNECT='TRUE';
    'VDDCR_CPU1_BP47':
      PIN_NUMBER='(0,0,0,0,0,0,0,0,0,0,0,0,0,0,0,0,0,0,0,0,0,0,0,0,BP47,0,0,0,0,~
0,0,0,0,0,0,0,0,0,0,0)';
      PINUSE='POWER';
      NO_LOAD_CHECK='Both';
      NO_IO_CHECK='Both';
      NO_ASSERT_CHECK='TRUE';
      NO_DIR_CHECK='TRUE';
      ALLOW_CONNECT='TRUE';
    'VDDCR_CPU1_BP49':
      PIN_NUMBER='(0,0,0,0,0,0,0,0,0,0,0,0,0,0,0,0,0,0,0,0,0,0,0,0,BP49,0,0,0,0,~
0,0,0,0,0,0,0,0,0,0,0)';
      PINUSE='POWER';
      NO_LOAD_CHECK='Both';
      NO_IO_CHECK='Both';
      NO_ASSERT_CHECK='TRUE';
      NO_DIR_CHECK='TRUE';
      ALLOW_CONNECT='TRUE';
    'VDDCR_CPU1_BR23':
      PIN_NUMBER='(0,0,0,0,0,0,0,0,0,0,0,0,0,0,0,0,0,0,0,0,0,0,0,0,BR23,0,0,0,0,~
0,0,0,0,0,0,0,0,0,0,0)';
      PINUSE='POWER';
      NO_LOAD_CHECK='Both';
      NO_IO_CHECK='Both';
      NO_ASSERT_CHECK='TRUE';
      NO_DIR_CHECK='TRUE';
      ALLOW_CONNECT='TRUE';
    'VDDCR_CPU1_BR25':
      PIN_NUMBER='(0,0,0,0,0,0,0,0,0,0,0,0,0,0,0,0,0,0,0,0,0,0,0,0,BR25,0,0,0,0,~
0,0,0,0,0,0,0,0,0,0,0)';
      PINUSE='POWER';
      NO_LOAD_CHECK='Both';
      NO_IO_CHECK='Both';
      NO_ASSERT_CHECK='TRUE';
      NO_DIR_CHECK='TRUE';
      ALLOW_CONNECT='TRUE';
    'VDDCR_CPU1_BR27':
      PIN_NUMBER='(0,0,0,0,0,0,0,0,0,0,0,0,0,0,0,0,0,0,0,0,0,0,0,0,BR27,0,0,0,0,~
0,0,0,0,0,0,0,0,0,0,0)';
      PINUSE='POWER';
      NO_LOAD_CHECK='Both';
      NO_IO_CHECK='Both';
      NO_ASSERT_CHECK='TRUE';
      NO_DIR_CHECK='TRUE';
      ALLOW_CONNECT='TRUE';
    'VDDCR_CPU1_BR29':
      PIN_NUMBER='(0,0,0,0,0,0,0,0,0,0,0,0,0,0,0,0,0,0,0,0,0,0,0,0,BR29,0,0,0,0,~
0,0,0,0,0,0,0,0,0,0,0)';
      PINUSE='POWER';
      NO_LOAD_CHECK='Both';
      NO_IO_CHECK='Both';
      NO_ASSERT_CHECK='TRUE';
      NO_DIR_CHECK='TRUE';
      ALLOW_CONNECT='TRUE';
    'VDDCR_CPU1_BR31':
      PIN_NUMBER='(0,0,0,0,0,0,0,0,0,0,0,0,0,0,0,0,0,0,0,0,0,0,0,0,BR31,0,0,0,0,~
0,0,0,0,0,0,0,0,0,0,0)';
      PINUSE='POWER';
      NO_LOAD_CHECK='Both';
      NO_IO_CHECK='Both';
      NO_ASSERT_CHECK='TRUE';
      NO_DIR_CHECK='TRUE';
      ALLOW_CONNECT='TRUE';
    'VDDCR_CPU1_BR33':
      PIN_NUMBER='(0,0,0,0,0,0,0,0,0,0,0,0,0,0,0,0,0,0,0,0,0,0,0,0,BR33,0,0,0,0,~
0,0,0,0,0,0,0,0,0,0,0)';
      PINUSE='POWER';
      NO_LOAD_CHECK='Both';
      NO_IO_CHECK='Both';
      NO_ASSERT_CHECK='TRUE';
      NO_DIR_CHECK='TRUE';
      ALLOW_CONNECT='TRUE';
    'VDDCR_CPU1_BR35':
      PIN_NUMBER='(0,0,0,0,0,0,0,0,0,0,0,0,0,0,0,0,0,0,0,0,0,0,0,0,BR35,0,0,0,0,~
0,0,0,0,0,0,0,0,0,0,0)';
      PINUSE='POWER';
      NO_LOAD_CHECK='Both';
      NO_IO_CHECK='Both';
      NO_ASSERT_CHECK='TRUE';
      NO_DIR_CHECK='TRUE';
      ALLOW_CONNECT='TRUE';
    'VDDCR_CPU1_BR40':
      PIN_NUMBER='(0,0,0,0,0,0,0,0,0,0,0,0,0,0,0,0,0,0,0,0,0,0,0,0,BR40,0,0,0,0,~
0,0,0,0,0,0,0,0,0,0,0)';
      PINUSE='POWER';
      NO_LOAD_CHECK='Both';
      NO_IO_CHECK='Both';
      NO_ASSERT_CHECK='TRUE';
      NO_DIR_CHECK='TRUE';
      ALLOW_CONNECT='TRUE';
    'VDDCR_CPU1_BR42':
      PIN_NUMBER='(0,0,0,0,0,0,0,0,0,0,0,0,0,0,0,0,0,0,0,0,0,0,0,0,BR42,0,0,0,0,~
0,0,0,0,0,0,0,0,0,0,0)';
      PINUSE='POWER';
      NO_LOAD_CHECK='Both';
      NO_IO_CHECK='Both';
      NO_ASSERT_CHECK='TRUE';
      NO_DIR_CHECK='TRUE';
      ALLOW_CONNECT='TRUE';
    'VDDCR_CPU1_BR44':
      PIN_NUMBER='(0,0,0,0,0,0,0,0,0,0,0,0,0,0,0,0,0,0,0,0,0,0,0,0,BR44,0,0,0,0,~
0,0,0,0,0,0,0,0,0,0,0)';
      PINUSE='POWER';
      NO_LOAD_CHECK='Both';
      NO_IO_CHECK='Both';
      NO_ASSERT_CHECK='TRUE';
      NO_DIR_CHECK='TRUE';
      ALLOW_CONNECT='TRUE';
    'VDDCR_CPU1_BR46':
      PIN_NUMBER='(0,0,0,0,0,0,0,0,0,0,0,0,0,0,0,0,0,0,0,0,0,0,0,0,BR46,0,0,0,0,~
0,0,0,0,0,0,0,0,0,0,0)';
      PINUSE='POWER';
      NO_LOAD_CHECK='Both';
      NO_IO_CHECK='Both';
      NO_ASSERT_CHECK='TRUE';
      NO_DIR_CHECK='TRUE';
      ALLOW_CONNECT='TRUE';
    'VDDCR_CPU1_BR48':
      PIN_NUMBER='(0,0,0,0,0,0,0,0,0,0,0,0,0,0,0,0,0,0,0,0,0,0,0,0,BR48,0,0,0,0,~
0,0,0,0,0,0,0,0,0,0,0)';
      PINUSE='POWER';
      NO_LOAD_CHECK='Both';
      NO_IO_CHECK='Both';
      NO_ASSERT_CHECK='TRUE';
      NO_DIR_CHECK='TRUE';
      ALLOW_CONNECT='TRUE';
    'VDDCR_CPU1_BR50':
      PIN_NUMBER='(0,0,0,0,0,0,0,0,0,0,0,0,0,0,0,0,0,0,0,0,0,0,0,0,BR50,0,0,0,0,~
0,0,0,0,0,0,0,0,0,0,0)';
      PINUSE='POWER';
      NO_LOAD_CHECK='Both';
      NO_IO_CHECK='Both';
      NO_ASSERT_CHECK='TRUE';
      NO_DIR_CHECK='TRUE';
      ALLOW_CONNECT='TRUE';
    'VDDCR_CPU1_BR52':
      PIN_NUMBER='(0,0,0,0,0,0,0,0,0,0,0,0,0,0,0,0,0,0,0,0,0,0,0,0,BR52,0,0,0,0,~
0,0,0,0,0,0,0,0,0,0,0)';
      PINUSE='POWER';
      NO_LOAD_CHECK='Both';
      NO_IO_CHECK='Both';
      NO_ASSERT_CHECK='TRUE';
      NO_DIR_CHECK='TRUE';
      ALLOW_CONNECT='TRUE';
    'VDDCR_CPU1_BT23':
      PIN_NUMBER='(0,0,0,0,0,0,0,0,0,0,0,0,0,0,0,0,0,0,0,0,0,0,0,0,BT23,0,0,0,0,~
0,0,0,0,0,0,0,0,0,0,0)';
      PINUSE='POWER';
      NO_LOAD_CHECK='Both';
      NO_IO_CHECK='Both';
      NO_ASSERT_CHECK='TRUE';
      NO_DIR_CHECK='TRUE';
      ALLOW_CONNECT='TRUE';
    'VDDCR_CPU1_BT24':
      PIN_NUMBER='(0,0,0,0,0,0,0,0,0,0,0,0,0,0,0,0,0,0,0,0,0,0,0,0,BT24,0,0,0,0,~
0,0,0,0,0,0,0,0,0,0,0)';
      PINUSE='POWER';
      NO_LOAD_CHECK='Both';
      NO_IO_CHECK='Both';
      NO_ASSERT_CHECK='TRUE';
      NO_DIR_CHECK='TRUE';
      ALLOW_CONNECT='TRUE';
    'VDDCR_CPU1_BT26':
      PIN_NUMBER='(0,0,0,0,0,0,0,0,0,0,0,0,0,0,0,0,0,0,0,0,0,0,0,0,BT26,0,0,0,0,~
0,0,0,0,0,0,0,0,0,0,0)';
      PINUSE='POWER';
      NO_LOAD_CHECK='Both';
      NO_IO_CHECK='Both';
      NO_ASSERT_CHECK='TRUE';
      NO_DIR_CHECK='TRUE';
      ALLOW_CONNECT='TRUE';
    'VDDCR_CPU1_BT27':
      PIN_NUMBER='(0,0,0,0,0,0,0,0,0,0,0,0,0,0,0,0,0,0,0,0,0,0,0,0,BT27,0,0,0,0,~
0,0,0,0,0,0,0,0,0,0,0)';
      PINUSE='POWER';
      NO_LOAD_CHECK='Both';
      NO_IO_CHECK='Both';
      NO_ASSERT_CHECK='TRUE';
      NO_DIR_CHECK='TRUE';
      ALLOW_CONNECT='TRUE';
    'VDDCR_CPU1_BT29':
      PIN_NUMBER='(0,0,0,0,0,0,0,0,0,0,0,0,0,0,0,0,0,0,0,0,0,0,0,0,BT29,0,0,0,0,~
0,0,0,0,0,0,0,0,0,0,0)';
      PINUSE='POWER';
      NO_LOAD_CHECK='Both';
      NO_IO_CHECK='Both';
      NO_ASSERT_CHECK='TRUE';
      NO_DIR_CHECK='TRUE';
      ALLOW_CONNECT='TRUE';
    'VDDCR_CPU1_BT30':
      PIN_NUMBER='(0,0,0,0,0,0,0,0,0,0,0,0,0,0,0,0,0,0,0,0,0,0,0,0,BT30,0,0,0,0,~
0,0,0,0,0,0,0,0,0,0,0)';
      PINUSE='POWER';
      NO_LOAD_CHECK='Both';
      NO_IO_CHECK='Both';
      NO_ASSERT_CHECK='TRUE';
      NO_DIR_CHECK='TRUE';
      ALLOW_CONNECT='TRUE';
    'VDDCR_CPU1_BT32':
      PIN_NUMBER='(0,0,0,0,0,0,0,0,0,0,0,0,0,0,0,0,0,0,0,0,0,0,0,0,BT32,0,0,0,0,~
0,0,0,0,0,0,0,0,0,0,0)';
      PINUSE='POWER';
      NO_LOAD_CHECK='Both';
      NO_IO_CHECK='Both';
      NO_ASSERT_CHECK='TRUE';
      NO_DIR_CHECK='TRUE';
      ALLOW_CONNECT='TRUE';
    'VDDCR_CPU1_BT33':
      PIN_NUMBER='(0,0,0,0,0,0,0,0,0,0,0,0,0,0,0,0,0,0,0,0,0,0,0,0,BT33,0,0,0,0,~
0,0,0,0,0,0,0,0,0,0,0)';
      PINUSE='POWER';
      NO_LOAD_CHECK='Both';
      NO_IO_CHECK='Both';
      NO_ASSERT_CHECK='TRUE';
      NO_DIR_CHECK='TRUE';
      ALLOW_CONNECT='TRUE';
    'VDDCR_CPU1_BT43':
      PIN_NUMBER='(0,0,0,0,0,0,0,0,0,0,0,0,0,0,0,0,0,0,0,0,0,0,0,0,BT43,0,0,0,0,~
0,0,0,0,0,0,0,0,0,0,0)';
      PINUSE='POWER';
      NO_LOAD_CHECK='Both';
      NO_IO_CHECK='Both';
      NO_ASSERT_CHECK='TRUE';
      NO_DIR_CHECK='TRUE';
      ALLOW_CONNECT='TRUE';
    'VDDCR_CPU1_BT44':
      PIN_NUMBER='(0,0,0,0,0,0,0,0,0,0,0,0,0,0,0,0,0,0,0,0,0,0,0,0,BT44,0,0,0,0,~
0,0,0,0,0,0,0,0,0,0,0)';
      PINUSE='POWER';
      NO_LOAD_CHECK='Both';
      NO_IO_CHECK='Both';
      NO_ASSERT_CHECK='TRUE';
      NO_DIR_CHECK='TRUE';
      ALLOW_CONNECT='TRUE';
    'VDDCR_CPU1_BT46':
      PIN_NUMBER='(0,0,0,0,0,0,0,0,0,0,0,0,0,0,0,0,0,0,0,0,0,0,0,0,BT46,0,0,0,0,~
0,0,0,0,0,0,0,0,0,0,0)';
      PINUSE='POWER';
      NO_LOAD_CHECK='Both';
      NO_IO_CHECK='Both';
      NO_ASSERT_CHECK='TRUE';
      NO_DIR_CHECK='TRUE';
      ALLOW_CONNECT='TRUE';
    'VDDCR_CPU1_BT47':
      PIN_NUMBER='(0,0,0,0,0,0,0,0,0,0,0,0,0,0,0,0,0,0,0,0,0,0,0,0,BT47,0,0,0,0,~
0,0,0,0,0,0,0,0,0,0,0)';
      PINUSE='POWER';
      NO_LOAD_CHECK='Both';
      NO_IO_CHECK='Both';
      NO_ASSERT_CHECK='TRUE';
      NO_DIR_CHECK='TRUE';
      ALLOW_CONNECT='TRUE';
    'VDDCR_CPU1_BT49':
      PIN_NUMBER='(0,0,0,0,0,0,0,0,0,0,0,0,0,0,0,0,0,0,0,0,0,0,0,0,BT49,0,0,0,0,~
0,0,0,0,0,0,0,0,0,0,0)';
      PINUSE='POWER';
      NO_LOAD_CHECK='Both';
      NO_IO_CHECK='Both';
      NO_ASSERT_CHECK='TRUE';
      NO_DIR_CHECK='TRUE';
      ALLOW_CONNECT='TRUE';
    'VDDCR_CPU1_BT50':
      PIN_NUMBER='(0,0,0,0,0,0,0,0,0,0,0,0,0,0,0,0,0,0,0,0,0,0,0,0,BT50,0,0,0,0,~
0,0,0,0,0,0,0,0,0,0,0)';
      PINUSE='POWER';
      NO_LOAD_CHECK='Both';
      NO_IO_CHECK='Both';
      NO_ASSERT_CHECK='TRUE';
      NO_DIR_CHECK='TRUE';
      ALLOW_CONNECT='TRUE';
    'VDDCR_CPU1_BT52':
      PIN_NUMBER='(0,0,0,0,0,0,0,0,0,0,0,0,0,0,0,0,0,0,0,0,0,0,0,0,BT52,0,0,0,0,~
0,0,0,0,0,0,0,0,0,0,0)';
      PINUSE='POWER';
      NO_LOAD_CHECK='Both';
      NO_IO_CHECK='Both';
      NO_ASSERT_CHECK='TRUE';
      NO_DIR_CHECK='TRUE';
      ALLOW_CONNECT='TRUE';
    'VDDCR_CPU1_BT53':
      PIN_NUMBER='(0,0,0,0,0,0,0,0,0,0,0,0,0,0,0,0,0,0,0,0,0,0,0,0,BT53,0,0,0,0,~
0,0,0,0,0,0,0,0,0,0,0)';
      PINUSE='POWER';
      NO_LOAD_CHECK='Both';
      NO_IO_CHECK='Both';
      NO_ASSERT_CHECK='TRUE';
      NO_DIR_CHECK='TRUE';
      ALLOW_CONNECT='TRUE';
    'VDDCR_CPU1_BW35':
      PIN_NUMBER='(0,0,0,0,0,0,0,0,0,0,0,0,0,0,0,0,0,0,0,0,0,0,0,0,BW35,0,0,0,0,~
0,0,0,0,0,0,0,0,0,0,0)';
      PINUSE='POWER';
      NO_LOAD_CHECK='Both';
      NO_IO_CHECK='Both';
      NO_ASSERT_CHECK='TRUE';
      NO_DIR_CHECK='TRUE';
      ALLOW_CONNECT='TRUE';
    'VDDCR_CPU1_BW36':
      PIN_NUMBER='(0,0,0,0,0,0,0,0,0,0,0,0,0,0,0,0,0,0,0,0,0,0,0,0,BW36,0,0,0,0,~
0,0,0,0,0,0,0,0,0,0,0)';
      PINUSE='POWER';
      NO_LOAD_CHECK='Both';
      NO_IO_CHECK='Both';
      NO_ASSERT_CHECK='TRUE';
      NO_DIR_CHECK='TRUE';
      ALLOW_CONNECT='TRUE';
    'VDDCR_CPU1_BW40':
      PIN_NUMBER='(0,0,0,0,0,0,0,0,0,0,0,0,0,0,0,0,0,0,0,0,0,0,0,0,BW40,0,0,0,0,~
0,0,0,0,0,0,0,0,0,0,0)';
      PINUSE='POWER';
      NO_LOAD_CHECK='Both';
      NO_IO_CHECK='Both';
      NO_ASSERT_CHECK='TRUE';
      NO_DIR_CHECK='TRUE';
      ALLOW_CONNECT='TRUE';
    'VDDCR_CPU1_BW41':
      PIN_NUMBER='(0,0,0,0,0,0,0,0,0,0,0,0,0,0,0,0,0,0,0,0,0,0,0,0,BW41,0,0,0,0,~
0,0,0,0,0,0,0,0,0,0,0)';
      PINUSE='POWER';
      NO_LOAD_CHECK='Both';
      NO_IO_CHECK='Both';
      NO_ASSERT_CHECK='TRUE';
      NO_DIR_CHECK='TRUE';
      ALLOW_CONNECT='TRUE';
    'VDDCR_CPU1_BY23':
      PIN_NUMBER='(0,0,0,0,0,0,0,0,0,0,0,0,0,0,0,0,0,0,0,0,0,0,0,0,BY23,0,0,0,0,~
0,0,0,0,0,0,0,0,0,0,0)';
      PINUSE='POWER';
      NO_LOAD_CHECK='Both';
      NO_IO_CHECK='Both';
      NO_ASSERT_CHECK='TRUE';
      NO_DIR_CHECK='TRUE';
      ALLOW_CONNECT='TRUE';
    'VDDCR_CPU1_BY24':
      PIN_NUMBER='(0,0,0,0,0,0,0,0,0,0,0,0,0,0,0,0,0,0,0,0,0,0,0,0,BY24,0,0,0,0,~
0,0,0,0,0,0,0,0,0,0,0)';
      PINUSE='POWER';
      NO_LOAD_CHECK='Both';
      NO_IO_CHECK='Both';
      NO_ASSERT_CHECK='TRUE';
      NO_DIR_CHECK='TRUE';
      ALLOW_CONNECT='TRUE';
    'VDDCR_CPU1_BY26':
      PIN_NUMBER='(0,0,0,0,0,0,0,0,0,0,0,0,0,0,0,0,0,0,0,0,0,0,0,0,BY26,0,0,0,0,~
0,0,0,0,0,0,0,0,0,0,0)';
      PINUSE='POWER';
      NO_LOAD_CHECK='Both';
      NO_IO_CHECK='Both';
      NO_ASSERT_CHECK='TRUE';
      NO_DIR_CHECK='TRUE';
      ALLOW_CONNECT='TRUE';
    'VDDCR_CPU1_BY27':
      PIN_NUMBER='(0,0,0,0,0,0,0,0,0,0,0,0,0,0,0,0,0,0,0,0,0,0,0,0,BY27,0,0,0,0,~
0,0,0,0,0,0,0,0,0,0,0)';
      PINUSE='POWER';
      NO_LOAD_CHECK='Both';
      NO_IO_CHECK='Both';
      NO_ASSERT_CHECK='TRUE';
      NO_DIR_CHECK='TRUE';
      ALLOW_CONNECT='TRUE';
    'VDDCR_CPU1_BY29':
      PIN_NUMBER='(0,0,0,0,0,0,0,0,0,0,0,0,0,0,0,0,0,0,0,0,0,0,0,0,BY29,0,0,0,0,~
0,0,0,0,0,0,0,0,0,0,0)';
      PINUSE='POWER';
      NO_LOAD_CHECK='Both';
      NO_IO_CHECK='Both';
      NO_ASSERT_CHECK='TRUE';
      NO_DIR_CHECK='TRUE';
      ALLOW_CONNECT='TRUE';
    'VDDCR_CPU1_BY30':
      PIN_NUMBER='(0,0,0,0,0,0,0,0,0,0,0,0,0,0,0,0,0,0,0,0,0,0,0,0,BY30,0,0,0,0,~
0,0,0,0,0,0,0,0,0,0,0)';
      PINUSE='POWER';
      NO_LOAD_CHECK='Both';
      NO_IO_CHECK='Both';
      NO_ASSERT_CHECK='TRUE';
      NO_DIR_CHECK='TRUE';
      ALLOW_CONNECT='TRUE';
    'VDDCR_CPU1_BY32':
      PIN_NUMBER='(0,0,0,0,0,0,0,0,0,0,0,0,0,0,0,0,0,0,0,0,0,0,0,0,BY32,0,0,0,0,~
0,0,0,0,0,0,0,0,0,0,0)';
      PINUSE='POWER';
      NO_LOAD_CHECK='Both';
      NO_IO_CHECK='Both';
      NO_ASSERT_CHECK='TRUE';
      NO_DIR_CHECK='TRUE';
      ALLOW_CONNECT='TRUE';
    'VDDCR_CPU1_BY33':
      PIN_NUMBER='(0,0,0,0,0,0,0,0,0,0,0,0,0,0,0,0,0,0,0,0,0,0,0,0,BY33,0,0,0,0,~
0,0,0,0,0,0,0,0,0,0,0)';
      PINUSE='POWER';
      NO_LOAD_CHECK='Both';
      NO_IO_CHECK='Both';
      NO_ASSERT_CHECK='TRUE';
      NO_DIR_CHECK='TRUE';
      ALLOW_CONNECT='TRUE';
    'VDDCR_CPU1_BY43':
      PIN_NUMBER='(0,0,0,0,0,0,0,0,0,0,0,0,0,0,0,0,0,0,0,0,0,0,0,0,BY43,0,0,0,0,~
0,0,0,0,0,0,0,0,0,0,0)';
      PINUSE='POWER';
      NO_LOAD_CHECK='Both';
      NO_IO_CHECK='Both';
      NO_ASSERT_CHECK='TRUE';
      NO_DIR_CHECK='TRUE';
      ALLOW_CONNECT='TRUE';
    'VDDCR_CPU1_BY44':
      PIN_NUMBER='(0,0,0,0,0,0,0,0,0,0,0,0,0,0,0,0,0,0,0,0,0,0,0,0,BY44,0,0,0,0,~
0,0,0,0,0,0,0,0,0,0,0)';
      PINUSE='POWER';
      NO_LOAD_CHECK='Both';
      NO_IO_CHECK='Both';
      NO_ASSERT_CHECK='TRUE';
      NO_DIR_CHECK='TRUE';
      ALLOW_CONNECT='TRUE';
    'VDDCR_CPU1_BY46':
      PIN_NUMBER='(0,0,0,0,0,0,0,0,0,0,0,0,0,0,0,0,0,0,0,0,0,0,0,0,BY46,0,0,0,0,~
0,0,0,0,0,0,0,0,0,0,0)';
      PINUSE='POWER';
      NO_LOAD_CHECK='Both';
      NO_IO_CHECK='Both';
      NO_ASSERT_CHECK='TRUE';
      NO_DIR_CHECK='TRUE';
      ALLOW_CONNECT='TRUE';
    'VDDCR_CPU1_BY47':
      PIN_NUMBER='(0,0,0,0,0,0,0,0,0,0,0,0,0,0,0,0,0,0,0,0,0,0,0,0,BY47,0,0,0,0,~
0,0,0,0,0,0,0,0,0,0,0)';
      PINUSE='POWER';
      NO_LOAD_CHECK='Both';
      NO_IO_CHECK='Both';
      NO_ASSERT_CHECK='TRUE';
      NO_DIR_CHECK='TRUE';
      ALLOW_CONNECT='TRUE';
    'VDDCR_CPU1_BY49':
      PIN_NUMBER='(0,0,0,0,0,0,0,0,0,0,0,0,0,0,0,0,0,0,0,0,0,0,0,0,BY49,0,0,0,0,~
0,0,0,0,0,0,0,0,0,0,0)';
      PINUSE='POWER';
      NO_LOAD_CHECK='Both';
      NO_IO_CHECK='Both';
      NO_ASSERT_CHECK='TRUE';
      NO_DIR_CHECK='TRUE';
      ALLOW_CONNECT='TRUE';
    'VDDCR_CPU1_BY50':
      PIN_NUMBER='(0,0,0,0,0,0,0,0,0,0,0,0,0,0,0,0,0,0,0,0,0,0,0,0,BY50,0,0,0,0,~
0,0,0,0,0,0,0,0,0,0,0)';
      PINUSE='POWER';
      NO_LOAD_CHECK='Both';
      NO_IO_CHECK='Both';
      NO_ASSERT_CHECK='TRUE';
      NO_DIR_CHECK='TRUE';
      ALLOW_CONNECT='TRUE';
    'VDDCR_CPU1_BY52':
      PIN_NUMBER='(0,0,0,0,0,0,0,0,0,0,0,0,0,0,0,0,0,0,0,0,0,0,0,0,BY52,0,0,0,0,~
0,0,0,0,0,0,0,0,0,0,0)';
      PINUSE='POWER';
      NO_LOAD_CHECK='Both';
      NO_IO_CHECK='Both';
      NO_ASSERT_CHECK='TRUE';
      NO_DIR_CHECK='TRUE';
      ALLOW_CONNECT='TRUE';
    'VDDCR_CPU1_BY53':
      PIN_NUMBER='(0,0,0,0,0,0,0,0,0,0,0,0,0,0,0,0,0,0,0,0,0,0,0,0,BY53,0,0,0,0,~
0,0,0,0,0,0,0,0,0,0,0)';
      PINUSE='POWER';
      NO_LOAD_CHECK='Both';
      NO_IO_CHECK='Both';
      NO_ASSERT_CHECK='TRUE';
      NO_DIR_CHECK='TRUE';
      ALLOW_CONNECT='TRUE';
    'VDDCR_CPU1_CC35':
      PIN_NUMBER='(0,0,0,0,0,0,0,0,0,0,0,0,0,0,0,0,0,0,0,0,0,0,0,0,CC35,0,0,0,0,~
0,0,0,0,0,0,0,0,0,0,0)';
      PINUSE='POWER';
      NO_LOAD_CHECK='Both';
      NO_IO_CHECK='Both';
      NO_ASSERT_CHECK='TRUE';
      NO_DIR_CHECK='TRUE';
      ALLOW_CONNECT='TRUE';
    'VDDCR_CPU1_CC36':
      PIN_NUMBER='(0,0,0,0,0,0,0,0,0,0,0,0,0,0,0,0,0,0,0,0,0,0,0,0,CC36,0,0,0,0,~
0,0,0,0,0,0,0,0,0,0,0)';
      PINUSE='POWER';
      NO_LOAD_CHECK='Both';
      NO_IO_CHECK='Both';
      NO_ASSERT_CHECK='TRUE';
      NO_DIR_CHECK='TRUE';
      ALLOW_CONNECT='TRUE';
    'VDDCR_CPU1_CC40':
      PIN_NUMBER='(0,0,0,0,0,0,0,0,0,0,0,0,0,0,0,0,0,0,0,0,0,0,0,0,CC40,0,0,0,0,~
0,0,0,0,0,0,0,0,0,0,0)';
      PINUSE='POWER';
      NO_LOAD_CHECK='Both';
      NO_IO_CHECK='Both';
      NO_ASSERT_CHECK='TRUE';
      NO_DIR_CHECK='TRUE';
      ALLOW_CONNECT='TRUE';
    'VDDCR_CPU1_CC41':
      PIN_NUMBER='(0,0,0,0,0,0,0,0,0,0,0,0,0,0,0,0,0,0,0,0,0,0,0,0,CC41,0,0,0,0,~
0,0,0,0,0,0,0,0,0,0,0)';
      PINUSE='POWER';
      NO_LOAD_CHECK='Both';
      NO_IO_CHECK='Both';
      NO_ASSERT_CHECK='TRUE';
      NO_DIR_CHECK='TRUE';
      ALLOW_CONNECT='TRUE';
    'VDDCR_CPU1_CD23':
      PIN_NUMBER='(0,0,0,0,0,0,0,0,0,0,0,0,0,0,0,0,0,0,0,0,0,0,0,0,CD23,0,0,0,0,~
0,0,0,0,0,0,0,0,0,0,0)';
      PINUSE='POWER';
      NO_LOAD_CHECK='Both';
      NO_IO_CHECK='Both';
      NO_ASSERT_CHECK='TRUE';
      NO_DIR_CHECK='TRUE';
      ALLOW_CONNECT='TRUE';
    'VDDCR_CPU1_CD24':
      PIN_NUMBER='(0,0,0,0,0,0,0,0,0,0,0,0,0,0,0,0,0,0,0,0,0,0,0,0,CD24,0,0,0,0,~
0,0,0,0,0,0,0,0,0,0,0)';
      PINUSE='POWER';
      NO_LOAD_CHECK='Both';
      NO_IO_CHECK='Both';
      NO_ASSERT_CHECK='TRUE';
      NO_DIR_CHECK='TRUE';
      ALLOW_CONNECT='TRUE';
    'VDDCR_CPU1_CD26':
      PIN_NUMBER='(0,0,0,0,0,0,0,0,0,0,0,0,0,0,0,0,0,0,0,0,0,0,0,0,CD26,0,0,0,0,~
0,0,0,0,0,0,0,0,0,0,0)';
      PINUSE='POWER';
      NO_LOAD_CHECK='Both';
      NO_IO_CHECK='Both';
      NO_ASSERT_CHECK='TRUE';
      NO_DIR_CHECK='TRUE';
      ALLOW_CONNECT='TRUE';
    'VDDCR_CPU1_CD27':
      PIN_NUMBER='(0,0,0,0,0,0,0,0,0,0,0,0,0,0,0,0,0,0,0,0,0,0,0,0,CD27,0,0,0,0,~
0,0,0,0,0,0,0,0,0,0,0)';
      PINUSE='POWER';
      NO_LOAD_CHECK='Both';
      NO_IO_CHECK='Both';
      NO_ASSERT_CHECK='TRUE';
      NO_DIR_CHECK='TRUE';
      ALLOW_CONNECT='TRUE';
    'VDDCR_CPU1_CD29':
      PIN_NUMBER='(0,0,0,0,0,0,0,0,0,0,0,0,0,0,0,0,0,0,0,0,0,0,0,0,CD29,0,0,0,0,~
0,0,0,0,0,0,0,0,0,0,0)';
      PINUSE='POWER';
      NO_LOAD_CHECK='Both';
      NO_IO_CHECK='Both';
      NO_ASSERT_CHECK='TRUE';
      NO_DIR_CHECK='TRUE';
      ALLOW_CONNECT='TRUE';
    'VDDCR_CPU1_CD30':
      PIN_NUMBER='(0,0,0,0,0,0,0,0,0,0,0,0,0,0,0,0,0,0,0,0,0,0,0,0,CD30,0,0,0,0,~
0,0,0,0,0,0,0,0,0,0,0)';
      PINUSE='POWER';
      NO_LOAD_CHECK='Both';
      NO_IO_CHECK='Both';
      NO_ASSERT_CHECK='TRUE';
      NO_DIR_CHECK='TRUE';
      ALLOW_CONNECT='TRUE';
    'VDDCR_CPU1_CD32':
      PIN_NUMBER='(0,0,0,0,0,0,0,0,0,0,0,0,0,0,0,0,0,0,0,0,0,0,0,0,CD32,0,0,0,0,~
0,0,0,0,0,0,0,0,0,0,0)';
      PINUSE='POWER';
      NO_LOAD_CHECK='Both';
      NO_IO_CHECK='Both';
      NO_ASSERT_CHECK='TRUE';
      NO_DIR_CHECK='TRUE';
      ALLOW_CONNECT='TRUE';
    'VDDCR_CPU1_CD33':
      PIN_NUMBER='(0,0,0,0,0,0,0,0,0,0,0,0,0,0,0,0,0,0,0,0,0,0,0,0,CD33,0,0,0,0,~
0,0,0,0,0,0,0,0,0,0,0)';
      PINUSE='POWER';
      NO_LOAD_CHECK='Both';
      NO_IO_CHECK='Both';
      NO_ASSERT_CHECK='TRUE';
      NO_DIR_CHECK='TRUE';
      ALLOW_CONNECT='TRUE';
    'VDDCR_CPU1_CD43':
      PIN_NUMBER='(0,0,0,0,0,0,0,0,0,0,0,0,0,0,0,0,0,0,0,0,0,0,0,0,CD43,0,0,0,0,~
0,0,0,0,0,0,0,0,0,0,0)';
      PINUSE='POWER';
      NO_LOAD_CHECK='Both';
      NO_IO_CHECK='Both';
      NO_ASSERT_CHECK='TRUE';
      NO_DIR_CHECK='TRUE';
      ALLOW_CONNECT='TRUE';
    'VDDCR_CPU1_CD44':
      PIN_NUMBER='(0,0,0,0,0,0,0,0,0,0,0,0,0,0,0,0,0,0,0,0,0,0,0,0,CD44,0,0,0,0,~
0,0,0,0,0,0,0,0,0,0,0)';
      PINUSE='POWER';
      NO_LOAD_CHECK='Both';
      NO_IO_CHECK='Both';
      NO_ASSERT_CHECK='TRUE';
      NO_DIR_CHECK='TRUE';
      ALLOW_CONNECT='TRUE';
    'VDDCR_CPU1_CD46':
      PIN_NUMBER='(0,0,0,0,0,0,0,0,0,0,0,0,0,0,0,0,0,0,0,0,0,0,0,0,CD46,0,0,0,0,~
0,0,0,0,0,0,0,0,0,0,0)';
      PINUSE='POWER';
      NO_LOAD_CHECK='Both';
      NO_IO_CHECK='Both';
      NO_ASSERT_CHECK='TRUE';
      NO_DIR_CHECK='TRUE';
      ALLOW_CONNECT='TRUE';
    'VDDCR_CPU1_CD47':
      PIN_NUMBER='(0,0,0,0,0,0,0,0,0,0,0,0,0,0,0,0,0,0,0,0,0,0,0,0,CD47,0,0,0,0,~
0,0,0,0,0,0,0,0,0,0,0)';
      PINUSE='POWER';
      NO_LOAD_CHECK='Both';
      NO_IO_CHECK='Both';
      NO_ASSERT_CHECK='TRUE';
      NO_DIR_CHECK='TRUE';
      ALLOW_CONNECT='TRUE';
    'VDDCR_CPU1_CD49':
      PIN_NUMBER='(0,0,0,0,0,0,0,0,0,0,0,0,0,0,0,0,0,0,0,0,0,0,0,0,CD49,0,0,0,0,~
0,0,0,0,0,0,0,0,0,0,0)';
      PINUSE='POWER';
      NO_LOAD_CHECK='Both';
      NO_IO_CHECK='Both';
      NO_ASSERT_CHECK='TRUE';
      NO_DIR_CHECK='TRUE';
      ALLOW_CONNECT='TRUE';
    'VDDCR_CPU1_CD50':
      PIN_NUMBER='(0,0,0,0,0,0,0,0,0,0,0,0,0,0,0,0,0,0,0,0,0,0,0,0,CD50,0,0,0,0,~
0,0,0,0,0,0,0,0,0,0,0)';
      PINUSE='POWER';
      NO_LOAD_CHECK='Both';
      NO_IO_CHECK='Both';
      NO_ASSERT_CHECK='TRUE';
      NO_DIR_CHECK='TRUE';
      ALLOW_CONNECT='TRUE';
    'VDDCR_CPU1_CD52':
      PIN_NUMBER='(0,0,0,0,0,0,0,0,0,0,0,0,0,0,0,0,0,0,0,0,0,0,0,0,CD52,0,0,0,0,~
0,0,0,0,0,0,0,0,0,0,0)';
      PINUSE='POWER';
      NO_LOAD_CHECK='Both';
      NO_IO_CHECK='Both';
      NO_ASSERT_CHECK='TRUE';
      NO_DIR_CHECK='TRUE';
      ALLOW_CONNECT='TRUE';
    'VDDCR_CPU1_CD53':
      PIN_NUMBER='(0,0,0,0,0,0,0,0,0,0,0,0,0,0,0,0,0,0,0,0,0,0,0,0,CD53,0,0,0,0,~
0,0,0,0,0,0,0,0,0,0,0)';
      PINUSE='POWER';
      NO_LOAD_CHECK='Both';
      NO_IO_CHECK='Both';
      NO_ASSERT_CHECK='TRUE';
      NO_DIR_CHECK='TRUE';
      ALLOW_CONNECT='TRUE';
    'VDDCR_CPU1_CG35':
      PIN_NUMBER='(0,0,0,0,0,0,0,0,0,0,0,0,0,0,0,0,0,0,0,0,0,0,0,0,CG35,0,0,0,0,~
0,0,0,0,0,0,0,0,0,0,0)';
      PINUSE='POWER';
      NO_LOAD_CHECK='Both';
      NO_IO_CHECK='Both';
      NO_ASSERT_CHECK='TRUE';
      NO_DIR_CHECK='TRUE';
      ALLOW_CONNECT='TRUE';
    'VDDCR_CPU1_CG36':
      PIN_NUMBER='(0,0,0,0,0,0,0,0,0,0,0,0,0,0,0,0,0,0,0,0,0,0,0,0,CG36,0,0,0,0,~
0,0,0,0,0,0,0,0,0,0,0)';
      PINUSE='POWER';
      NO_LOAD_CHECK='Both';
      NO_IO_CHECK='Both';
      NO_ASSERT_CHECK='TRUE';
      NO_DIR_CHECK='TRUE';
      ALLOW_CONNECT='TRUE';
    'VDDCR_CPU1_CG40':
      PIN_NUMBER='(0,0,0,0,0,0,0,0,0,0,0,0,0,0,0,0,0,0,0,0,0,0,0,0,CG40,0,0,0,0,~
0,0,0,0,0,0,0,0,0,0,0)';
      PINUSE='POWER';
      NO_LOAD_CHECK='Both';
      NO_IO_CHECK='Both';
      NO_ASSERT_CHECK='TRUE';
      NO_DIR_CHECK='TRUE';
      ALLOW_CONNECT='TRUE';
    'VDDCR_CPU1_CG41':
      PIN_NUMBER='(0,0,0,0,0,0,0,0,0,0,0,0,0,0,0,0,0,0,0,0,0,0,0,0,CG41,0,0,0,0,~
0,0,0,0,0,0,0,0,0,0,0)';
      PINUSE='POWER';
      NO_LOAD_CHECK='Both';
      NO_IO_CHECK='Both';
      NO_ASSERT_CHECK='TRUE';
      NO_DIR_CHECK='TRUE';
      ALLOW_CONNECT='TRUE';
    'VDDCR_CPU1_CH23':
      PIN_NUMBER='(0,0,0,0,0,0,0,0,0,0,0,0,0,0,0,0,0,0,0,0,0,0,0,0,CH23,0,0,0,0,~
0,0,0,0,0,0,0,0,0,0,0)';
      PINUSE='POWER';
      NO_LOAD_CHECK='Both';
      NO_IO_CHECK='Both';
      NO_ASSERT_CHECK='TRUE';
      NO_DIR_CHECK='TRUE';
      ALLOW_CONNECT='TRUE';
    'VDDCR_CPU1_CH24':
      PIN_NUMBER='(0,0,0,0,0,0,0,0,0,0,0,0,0,0,0,0,0,0,0,0,0,0,0,0,CH24,0,0,0,0,~
0,0,0,0,0,0,0,0,0,0,0)';
      PINUSE='POWER';
      NO_LOAD_CHECK='Both';
      NO_IO_CHECK='Both';
      NO_ASSERT_CHECK='TRUE';
      NO_DIR_CHECK='TRUE';
      ALLOW_CONNECT='TRUE';
    'VDDCR_CPU1_CH26':
      PIN_NUMBER='(0,0,0,0,0,0,0,0,0,0,0,0,0,0,0,0,0,0,0,0,0,0,0,0,CH26,0,0,0,0,~
0,0,0,0,0,0,0,0,0,0,0)';
      PINUSE='POWER';
      NO_LOAD_CHECK='Both';
      NO_IO_CHECK='Both';
      NO_ASSERT_CHECK='TRUE';
      NO_DIR_CHECK='TRUE';
      ALLOW_CONNECT='TRUE';
    'VDDCR_CPU1_CH27':
      PIN_NUMBER='(0,0,0,0,0,0,0,0,0,0,0,0,0,0,0,0,0,0,0,0,0,0,0,0,CH27,0,0,0,0,~
0,0,0,0,0,0,0,0,0,0,0)';
      PINUSE='POWER';
      NO_LOAD_CHECK='Both';
      NO_IO_CHECK='Both';
      NO_ASSERT_CHECK='TRUE';
      NO_DIR_CHECK='TRUE';
      ALLOW_CONNECT='TRUE';
    'VDDCR_CPU1_CH29':
      PIN_NUMBER='(0,0,0,0,0,0,0,0,0,0,0,0,0,0,0,0,0,0,0,0,0,0,0,0,CH29,0,0,0,0,~
0,0,0,0,0,0,0,0,0,0,0)';
      PINUSE='POWER';
      NO_LOAD_CHECK='Both';
      NO_IO_CHECK='Both';
      NO_ASSERT_CHECK='TRUE';
      NO_DIR_CHECK='TRUE';
      ALLOW_CONNECT='TRUE';
    'VDDCR_CPU1_CH30':
      PIN_NUMBER='(0,0,0,0,0,0,0,0,0,0,0,0,0,0,0,0,0,0,0,0,0,0,0,0,CH30,0,0,0,0,~
0,0,0,0,0,0,0,0,0,0,0)';
      PINUSE='POWER';
      NO_LOAD_CHECK='Both';
      NO_IO_CHECK='Both';
      NO_ASSERT_CHECK='TRUE';
      NO_DIR_CHECK='TRUE';
      ALLOW_CONNECT='TRUE';
    'VDDCR_CPU1_CH32':
      PIN_NUMBER='(0,0,0,0,0,0,0,0,0,0,0,0,0,0,0,0,0,0,0,0,0,0,0,0,CH32,0,0,0,0,~
0,0,0,0,0,0,0,0,0,0,0)';
      PINUSE='POWER';
      NO_LOAD_CHECK='Both';
      NO_IO_CHECK='Both';
      NO_ASSERT_CHECK='TRUE';
      NO_DIR_CHECK='TRUE';
      ALLOW_CONNECT='TRUE';
    'VDDCR_CPU1_CH33':
      PIN_NUMBER='(0,0,0,0,0,0,0,0,0,0,0,0,0,0,0,0,0,0,0,0,0,0,0,0,CH33,0,0,0,0,~
0,0,0,0,0,0,0,0,0,0,0)';
      PINUSE='POWER';
      NO_LOAD_CHECK='Both';
      NO_IO_CHECK='Both';
      NO_ASSERT_CHECK='TRUE';
      NO_DIR_CHECK='TRUE';
      ALLOW_CONNECT='TRUE';
    'VDDCR_CPU1_CH43':
      PIN_NUMBER='(0,0,0,0,0,0,0,0,0,0,0,0,0,0,0,0,0,0,0,0,0,0,0,0,CH43,0,0,0,0,~
0,0,0,0,0,0,0,0,0,0,0)';
      PINUSE='POWER';
      NO_LOAD_CHECK='Both';
      NO_IO_CHECK='Both';
      NO_ASSERT_CHECK='TRUE';
      NO_DIR_CHECK='TRUE';
      ALLOW_CONNECT='TRUE';
    'VDDCR_CPU1_CH44':
      PIN_NUMBER='(0,0,0,0,0,0,0,0,0,0,0,0,0,0,0,0,0,0,0,0,0,0,0,0,CH44,0,0,0,0,~
0,0,0,0,0,0,0,0,0,0,0)';
      PINUSE='POWER';
      NO_LOAD_CHECK='Both';
      NO_IO_CHECK='Both';
      NO_ASSERT_CHECK='TRUE';
      NO_DIR_CHECK='TRUE';
      ALLOW_CONNECT='TRUE';
    'VDDCR_CPU1_CH46':
      PIN_NUMBER='(0,0,0,0,0,0,0,0,0,0,0,0,0,0,0,0,0,0,0,0,0,0,0,0,CH46,0,0,0,0,~
0,0,0,0,0,0,0,0,0,0,0)';
      PINUSE='POWER';
      NO_LOAD_CHECK='Both';
      NO_IO_CHECK='Both';
      NO_ASSERT_CHECK='TRUE';
      NO_DIR_CHECK='TRUE';
      ALLOW_CONNECT='TRUE';
    'VDDCR_CPU1_CH47':
      PIN_NUMBER='(0,0,0,0,0,0,0,0,0,0,0,0,0,0,0,0,0,0,0,0,0,0,0,0,CH47,0,0,0,0,~
0,0,0,0,0,0,0,0,0,0,0)';
      PINUSE='POWER';
      NO_LOAD_CHECK='Both';
      NO_IO_CHECK='Both';
      NO_ASSERT_CHECK='TRUE';
      NO_DIR_CHECK='TRUE';
      ALLOW_CONNECT='TRUE';
    'VDDCR_CPU1_CH49':
      PIN_NUMBER='(0,0,0,0,0,0,0,0,0,0,0,0,0,0,0,0,0,0,0,0,0,0,0,0,CH49,0,0,0,0,~
0,0,0,0,0,0,0,0,0,0,0)';
      PINUSE='POWER';
      NO_LOAD_CHECK='Both';
      NO_IO_CHECK='Both';
      NO_ASSERT_CHECK='TRUE';
      NO_DIR_CHECK='TRUE';
      ALLOW_CONNECT='TRUE';
    'VDDCR_CPU1_CH50':
      PIN_NUMBER='(0,0,0,0,0,0,0,0,0,0,0,0,0,0,0,0,0,0,0,0,0,0,0,0,CH50,0,0,0,0,~
0,0,0,0,0,0,0,0,0,0,0)';
      PINUSE='POWER';
      NO_LOAD_CHECK='Both';
      NO_IO_CHECK='Both';
      NO_ASSERT_CHECK='TRUE';
      NO_DIR_CHECK='TRUE';
      ALLOW_CONNECT='TRUE';
    'VDDCR_CPU1_CH52':
      PIN_NUMBER='(0,0,0,0,0,0,0,0,0,0,0,0,0,0,0,0,0,0,0,0,0,0,0,0,CH52,0,0,0,0,~
0,0,0,0,0,0,0,0,0,0,0)';
      PINUSE='POWER';
      NO_LOAD_CHECK='Both';
      NO_IO_CHECK='Both';
      NO_ASSERT_CHECK='TRUE';
      NO_DIR_CHECK='TRUE';
      ALLOW_CONNECT='TRUE';
    'VDDCR_CPU1_CH53':
      PIN_NUMBER='(0,0,0,0,0,0,0,0,0,0,0,0,0,0,0,0,0,0,0,0,0,0,0,0,CH53,0,0,0,0,~
0,0,0,0,0,0,0,0,0,0,0)';
      PINUSE='POWER';
      NO_LOAD_CHECK='Both';
      NO_IO_CHECK='Both';
      NO_ASSERT_CHECK='TRUE';
      NO_DIR_CHECK='TRUE';
      ALLOW_CONNECT='TRUE';
    'VDDCR_CPU1_CK35':
      PIN_NUMBER='(0,0,0,0,0,0,0,0,0,0,0,0,0,0,0,0,0,0,0,0,0,0,0,0,CK35,0,0,0,0,~
0,0,0,0,0,0,0,0,0,0,0)';
      PINUSE='POWER';
      NO_LOAD_CHECK='Both';
      NO_IO_CHECK='Both';
      NO_ASSERT_CHECK='TRUE';
      NO_DIR_CHECK='TRUE';
      ALLOW_CONNECT='TRUE';
    'VDDCR_CPU1_CK36':
      PIN_NUMBER='(0,0,0,0,0,0,0,0,0,0,0,0,0,0,0,0,0,0,0,0,0,0,0,0,CK36,0,0,0,0,~
0,0,0,0,0,0,0,0,0,0,0)';
      PINUSE='POWER';
      NO_LOAD_CHECK='Both';
      NO_IO_CHECK='Both';
      NO_ASSERT_CHECK='TRUE';
      NO_DIR_CHECK='TRUE';
      ALLOW_CONNECT='TRUE';
    'VDDCR_CPU1_CK40':
      PIN_NUMBER='(0,0,0,0,0,0,0,0,0,0,0,0,0,0,0,0,0,0,0,0,0,0,0,0,CK40,0,0,0,0,~
0,0,0,0,0,0,0,0,0,0,0)';
      PINUSE='POWER';
      NO_LOAD_CHECK='Both';
      NO_IO_CHECK='Both';
      NO_ASSERT_CHECK='TRUE';
      NO_DIR_CHECK='TRUE';
      ALLOW_CONNECT='TRUE';
    'VDDCR_CPU1_CK41':
      PIN_NUMBER='(0,0,0,0,0,0,0,0,0,0,0,0,0,0,0,0,0,0,0,0,0,0,0,0,CK41,0,0,0,0,~
0,0,0,0,0,0,0,0,0,0,0)';
      PINUSE='POWER';
      NO_LOAD_CHECK='Both';
      NO_IO_CHECK='Both';
      NO_ASSERT_CHECK='TRUE';
      NO_DIR_CHECK='TRUE';
      ALLOW_CONNECT='TRUE';
    'VDDCR_CPU1_CL29':
      PIN_NUMBER='(0,0,0,0,0,0,0,0,0,0,0,0,0,0,0,0,0,0,0,0,0,0,0,0,CL29,0,0,0,0,~
0,0,0,0,0,0,0,0,0,0,0)';
      PINUSE='POWER';
      NO_LOAD_CHECK='Both';
      NO_IO_CHECK='Both';
      NO_ASSERT_CHECK='TRUE';
      NO_DIR_CHECK='TRUE';
      ALLOW_CONNECT='TRUE';
    'VDDCR_CPU1_CL30':
      PIN_NUMBER='(0,0,0,0,0,0,0,0,0,0,0,0,0,0,0,0,0,0,0,0,0,0,0,0,CL30,0,0,0,0,~
0,0,0,0,0,0,0,0,0,0,0)';
      PINUSE='POWER';
      NO_LOAD_CHECK='Both';
      NO_IO_CHECK='Both';
      NO_ASSERT_CHECK='TRUE';
      NO_DIR_CHECK='TRUE';
      ALLOW_CONNECT='TRUE';
    'VDDCR_CPU1_CL32':
      PIN_NUMBER='(0,0,0,0,0,0,0,0,0,0,0,0,0,0,0,0,0,0,0,0,0,0,0,0,CL32,0,0,0,0,~
0,0,0,0,0,0,0,0,0,0,0)';
      PINUSE='POWER';
      NO_LOAD_CHECK='Both';
      NO_IO_CHECK='Both';
      NO_ASSERT_CHECK='TRUE';
      NO_DIR_CHECK='TRUE';
      ALLOW_CONNECT='TRUE';
    'VDDCR_CPU1_CL33':
      PIN_NUMBER='(0,0,0,0,0,0,0,0,0,0,0,0,0,0,0,0,0,0,0,0,0,0,0,0,CL33,0,0,0,0,~
0,0,0,0,0,0,0,0,0,0,0)';
      PINUSE='POWER';
      NO_LOAD_CHECK='Both';
      NO_IO_CHECK='Both';
      NO_ASSERT_CHECK='TRUE';
      NO_DIR_CHECK='TRUE';
      ALLOW_CONNECT='TRUE';
    'VDDCR_CPU1_CL43':
      PIN_NUMBER='(0,0,0,0,0,0,0,0,0,0,0,0,0,0,0,0,0,0,0,0,0,0,0,0,CL43,0,0,0,0,~
0,0,0,0,0,0,0,0,0,0,0)';
      PINUSE='POWER';
      NO_LOAD_CHECK='Both';
      NO_IO_CHECK='Both';
      NO_ASSERT_CHECK='TRUE';
      NO_DIR_CHECK='TRUE';
      ALLOW_CONNECT='TRUE';
    'VDDCR_CPU1_CL44':
      PIN_NUMBER='(0,0,0,0,0,0,0,0,0,0,0,0,0,0,0,0,0,0,0,0,0,0,0,0,CL44,0,0,0,0,~
0,0,0,0,0,0,0,0,0,0,0)';
      PINUSE='POWER';
      NO_LOAD_CHECK='Both';
      NO_IO_CHECK='Both';
      NO_ASSERT_CHECK='TRUE';
      NO_DIR_CHECK='TRUE';
      ALLOW_CONNECT='TRUE';
    'VDDCR_CPU1_CL46':
      PIN_NUMBER='(0,0,0,0,0,0,0,0,0,0,0,0,0,0,0,0,0,0,0,0,0,0,0,0,CL46,0,0,0,0,~
0,0,0,0,0,0,0,0,0,0,0)';
      PINUSE='POWER';
      NO_LOAD_CHECK='Both';
      NO_IO_CHECK='Both';
      NO_ASSERT_CHECK='TRUE';
      NO_DIR_CHECK='TRUE';
      ALLOW_CONNECT='TRUE';
    'VDDCR_CPU1_CL47':
      PIN_NUMBER='(0,0,0,0,0,0,0,0,0,0,0,0,0,0,0,0,0,0,0,0,0,0,0,0,CL47,0,0,0,0,~
0,0,0,0,0,0,0,0,0,0,0)';
      PINUSE='POWER';
      NO_LOAD_CHECK='Both';
      NO_IO_CHECK='Both';
      NO_ASSERT_CHECK='TRUE';
      NO_DIR_CHECK='TRUE';
      ALLOW_CONNECT='TRUE';
    'VDDCR_CPU1_CN35':
      PIN_NUMBER='(0,0,0,0,0,0,0,0,0,0,0,0,0,0,0,0,0,0,0,0,0,0,0,0,CN35,0,0,0,0,~
0,0,0,0,0,0,0,0,0,0,0)';
      PINUSE='POWER';
      NO_LOAD_CHECK='Both';
      NO_IO_CHECK='Both';
      NO_ASSERT_CHECK='TRUE';
      NO_DIR_CHECK='TRUE';
      ALLOW_CONNECT='TRUE';
    'VDDCR_CPU1_CN36':
      PIN_NUMBER='(0,0,0,0,0,0,0,0,0,0,0,0,0,0,0,0,0,0,0,0,0,0,0,0,CN36,0,0,0,0,~
0,0,0,0,0,0,0,0,0,0,0)';
      PINUSE='POWER';
      NO_LOAD_CHECK='Both';
      NO_IO_CHECK='Both';
      NO_ASSERT_CHECK='TRUE';
      NO_DIR_CHECK='TRUE';
      ALLOW_CONNECT='TRUE';
    'VDDCR_CPU1_CN40':
      PIN_NUMBER='(0,0,0,0,0,0,0,0,0,0,0,0,0,0,0,0,0,0,0,0,0,0,0,0,CN40,0,0,0,0,~
0,0,0,0,0,0,0,0,0,0,0)';
      PINUSE='POWER';
      NO_LOAD_CHECK='Both';
      NO_IO_CHECK='Both';
      NO_ASSERT_CHECK='TRUE';
      NO_DIR_CHECK='TRUE';
      ALLOW_CONNECT='TRUE';
    'VDDCR_CPU1_CN41':
      PIN_NUMBER='(0,0,0,0,0,0,0,0,0,0,0,0,0,0,0,0,0,0,0,0,0,0,0,0,CN41,0,0,0,0,~
0,0,0,0,0,0,0,0,0,0,0)';
      PINUSE='POWER';
      NO_LOAD_CHECK='Both';
      NO_IO_CHECK='Both';
      NO_ASSERT_CHECK='TRUE';
      NO_DIR_CHECK='TRUE';
      ALLOW_CONNECT='TRUE';
    'VDDCR_CPU1_CP23':
      PIN_NUMBER='(0,0,0,0,0,0,0,0,0,0,0,0,0,0,0,0,0,0,0,0,0,0,0,0,CP23,0,0,0,0,~
0,0,0,0,0,0,0,0,0,0,0)';
      PINUSE='POWER';
      NO_LOAD_CHECK='Both';
      NO_IO_CHECK='Both';
      NO_ASSERT_CHECK='TRUE';
      NO_DIR_CHECK='TRUE';
      ALLOW_CONNECT='TRUE';
    'VDDCR_CPU1_CP24':
      PIN_NUMBER='(0,0,0,0,0,0,0,0,0,0,0,0,0,0,0,0,0,0,0,0,0,0,0,0,CP24,0,0,0,0,~
0,0,0,0,0,0,0,0,0,0,0)';
      PINUSE='POWER';
      NO_LOAD_CHECK='Both';
      NO_IO_CHECK='Both';
      NO_ASSERT_CHECK='TRUE';
      NO_DIR_CHECK='TRUE';
      ALLOW_CONNECT='TRUE';
    'VDDCR_CPU1_CP26':
      PIN_NUMBER='(0,0,0,0,0,0,0,0,0,0,0,0,0,0,0,0,0,0,0,0,0,0,0,0,CP26,0,0,0,0,~
0,0,0,0,0,0,0,0,0,0,0)';
      PINUSE='POWER';
      NO_LOAD_CHECK='Both';
      NO_IO_CHECK='Both';
      NO_ASSERT_CHECK='TRUE';
      NO_DIR_CHECK='TRUE';
      ALLOW_CONNECT='TRUE';
    'VDDCR_CPU1_CP27':
      PIN_NUMBER='(0,0,0,0,0,0,0,0,0,0,0,0,0,0,0,0,0,0,0,0,0,0,0,0,CP27,0,0,0,0,~
0,0,0,0,0,0,0,0,0,0,0)';
      PINUSE='POWER';
      NO_LOAD_CHECK='Both';
      NO_IO_CHECK='Both';
      NO_ASSERT_CHECK='TRUE';
      NO_DIR_CHECK='TRUE';
      ALLOW_CONNECT='TRUE';
    'VDDCR_CPU1_CP29':
      PIN_NUMBER='(0,0,0,0,0,0,0,0,0,0,0,0,0,0,0,0,0,0,0,0,0,0,0,0,CP29,0,0,0,0,~
0,0,0,0,0,0,0,0,0,0,0)';
      PINUSE='POWER';
      NO_LOAD_CHECK='Both';
      NO_IO_CHECK='Both';
      NO_ASSERT_CHECK='TRUE';
      NO_DIR_CHECK='TRUE';
      ALLOW_CONNECT='TRUE';
    'VDDCR_CPU1_CP30':
      PIN_NUMBER='(0,0,0,0,0,0,0,0,0,0,0,0,0,0,0,0,0,0,0,0,0,0,0,0,CP30,0,0,0,0,~
0,0,0,0,0,0,0,0,0,0,0)';
      PINUSE='POWER';
      NO_LOAD_CHECK='Both';
      NO_IO_CHECK='Both';
      NO_ASSERT_CHECK='TRUE';
      NO_DIR_CHECK='TRUE';
      ALLOW_CONNECT='TRUE';
    'VDDCR_CPU1_CP32':
      PIN_NUMBER='(0,0,0,0,0,0,0,0,0,0,0,0,0,0,0,0,0,0,0,0,0,0,0,0,CP32,0,0,0,0,~
0,0,0,0,0,0,0,0,0,0,0)';
      PINUSE='POWER';
      NO_LOAD_CHECK='Both';
      NO_IO_CHECK='Both';
      NO_ASSERT_CHECK='TRUE';
      NO_DIR_CHECK='TRUE';
      ALLOW_CONNECT='TRUE';
    'VDDCR_CPU1_CP33':
      PIN_NUMBER='(0,0,0,0,0,0,0,0,0,0,0,0,0,0,0,0,0,0,0,0,0,0,0,0,CP33,0,0,0,0,~
0,0,0,0,0,0,0,0,0,0,0)';
      PINUSE='POWER';
      NO_LOAD_CHECK='Both';
      NO_IO_CHECK='Both';
      NO_ASSERT_CHECK='TRUE';
      NO_DIR_CHECK='TRUE';
      ALLOW_CONNECT='TRUE';
    'VDDCR_CPU1_CP43':
      PIN_NUMBER='(0,0,0,0,0,0,0,0,0,0,0,0,0,0,0,0,0,0,0,0,0,0,0,0,CP43,0,0,0,0,~
0,0,0,0,0,0,0,0,0,0,0)';
      PINUSE='POWER';
      NO_LOAD_CHECK='Both';
      NO_IO_CHECK='Both';
      NO_ASSERT_CHECK='TRUE';
      NO_DIR_CHECK='TRUE';
      ALLOW_CONNECT='TRUE';
    'VDDCR_CPU1_CP44':
      PIN_NUMBER='(0,0,0,0,0,0,0,0,0,0,0,0,0,0,0,0,0,0,0,0,0,0,0,0,CP44,0,0,0,0,~
0,0,0,0,0,0,0,0,0,0,0)';
      PINUSE='POWER';
      NO_LOAD_CHECK='Both';
      NO_IO_CHECK='Both';
      NO_ASSERT_CHECK='TRUE';
      NO_DIR_CHECK='TRUE';
      ALLOW_CONNECT='TRUE';
    'VDDCR_CPU1_CP46':
      PIN_NUMBER='(0,0,0,0,0,0,0,0,0,0,0,0,0,0,0,0,0,0,0,0,0,0,0,0,CP46,0,0,0,0,~
0,0,0,0,0,0,0,0,0,0,0)';
      PINUSE='POWER';
      NO_LOAD_CHECK='Both';
      NO_IO_CHECK='Both';
      NO_ASSERT_CHECK='TRUE';
      NO_DIR_CHECK='TRUE';
      ALLOW_CONNECT='TRUE';
    'VDDCR_CPU1_CP47':
      PIN_NUMBER='(0,0,0,0,0,0,0,0,0,0,0,0,0,0,0,0,0,0,0,0,0,0,0,0,CP47,0,0,0,0,~
0,0,0,0,0,0,0,0,0,0,0)';
      PINUSE='POWER';
      NO_LOAD_CHECK='Both';
      NO_IO_CHECK='Both';
      NO_ASSERT_CHECK='TRUE';
      NO_DIR_CHECK='TRUE';
      ALLOW_CONNECT='TRUE';
    'VDDCR_CPU1_CP49':
      PIN_NUMBER='(0,0,0,0,0,0,0,0,0,0,0,0,0,0,0,0,0,0,0,0,0,0,0,0,CP49,0,0,0,0,~
0,0,0,0,0,0,0,0,0,0,0)';
      PINUSE='POWER';
      NO_LOAD_CHECK='Both';
      NO_IO_CHECK='Both';
      NO_ASSERT_CHECK='TRUE';
      NO_DIR_CHECK='TRUE';
      ALLOW_CONNECT='TRUE';
    'VDDCR_CPU1_CP50':
      PIN_NUMBER='(0,0,0,0,0,0,0,0,0,0,0,0,0,0,0,0,0,0,0,0,0,0,0,0,CP50,0,0,0,0,~
0,0,0,0,0,0,0,0,0,0,0)';
      PINUSE='POWER';
      NO_LOAD_CHECK='Both';
      NO_IO_CHECK='Both';
      NO_ASSERT_CHECK='TRUE';
      NO_DIR_CHECK='TRUE';
      ALLOW_CONNECT='TRUE';
    'VDDCR_CPU1_CP52':
      PIN_NUMBER='(0,0,0,0,0,0,0,0,0,0,0,0,0,0,0,0,0,0,0,0,0,0,0,0,CP52,0,0,0,0,~
0,0,0,0,0,0,0,0,0,0,0)';
      PINUSE='POWER';
      NO_LOAD_CHECK='Both';
      NO_IO_CHECK='Both';
      NO_ASSERT_CHECK='TRUE';
      NO_DIR_CHECK='TRUE';
      ALLOW_CONNECT='TRUE';
    'VDDCR_CPU1_CP53':
      PIN_NUMBER='(0,0,0,0,0,0,0,0,0,0,0,0,0,0,0,0,0,0,0,0,0,0,0,0,CP53,0,0,0,0,~
0,0,0,0,0,0,0,0,0,0,0)';
      PINUSE='POWER';
      NO_LOAD_CHECK='Both';
      NO_IO_CHECK='Both';
      NO_ASSERT_CHECK='TRUE';
      NO_DIR_CHECK='TRUE';
      ALLOW_CONNECT='TRUE';
    'VDDCR_CPU1_CU35':
      PIN_NUMBER='(0,0,0,0,0,0,0,0,0,0,0,0,0,0,0,0,0,0,0,0,0,0,0,0,CU35,0,0,0,0,~
0,0,0,0,0,0,0,0,0,0,0)';
      PINUSE='POWER';
      NO_LOAD_CHECK='Both';
      NO_IO_CHECK='Both';
      NO_ASSERT_CHECK='TRUE';
      NO_DIR_CHECK='TRUE';
      ALLOW_CONNECT='TRUE';
    'VDDCR_CPU1_CU36':
      PIN_NUMBER='(0,0,0,0,0,0,0,0,0,0,0,0,0,0,0,0,0,0,0,0,0,0,0,0,CU36,0,0,0,0,~
0,0,0,0,0,0,0,0,0,0,0)';
      PINUSE='POWER';
      NO_LOAD_CHECK='Both';
      NO_IO_CHECK='Both';
      NO_ASSERT_CHECK='TRUE';
      NO_DIR_CHECK='TRUE';
      ALLOW_CONNECT='TRUE';
    'VDDCR_CPU1_CU40':
      PIN_NUMBER='(0,0,0,0,0,0,0,0,0,0,0,0,0,0,0,0,0,0,0,0,0,0,0,0,CU40,0,0,0,0,~
0,0,0,0,0,0,0,0,0,0,0)';
      PINUSE='POWER';
      NO_LOAD_CHECK='Both';
      NO_IO_CHECK='Both';
      NO_ASSERT_CHECK='TRUE';
      NO_DIR_CHECK='TRUE';
      ALLOW_CONNECT='TRUE';
    'VDDCR_CPU1_CU41':
      PIN_NUMBER='(0,0,0,0,0,0,0,0,0,0,0,0,0,0,0,0,0,0,0,0,0,0,0,0,CU41,0,0,0,0,~
0,0,0,0,0,0,0,0,0,0,0)';
      PINUSE='POWER';
      NO_LOAD_CHECK='Both';
      NO_IO_CHECK='Both';
      NO_ASSERT_CHECK='TRUE';
      NO_DIR_CHECK='TRUE';
      ALLOW_CONNECT='TRUE';
    'VDDCR_CPU1_CV23':
      PIN_NUMBER='(0,0,0,0,0,0,0,0,0,0,0,0,0,0,0,0,0,0,0,0,0,0,0,0,CV23,0,0,0,0,~
0,0,0,0,0,0,0,0,0,0,0)';
      PINUSE='POWER';
      NO_LOAD_CHECK='Both';
      NO_IO_CHECK='Both';
      NO_ASSERT_CHECK='TRUE';
      NO_DIR_CHECK='TRUE';
      ALLOW_CONNECT='TRUE';
    'VDDCR_CPU1_CV24':
      PIN_NUMBER='(0,0,0,0,0,0,0,0,0,0,0,0,0,0,0,0,0,0,0,0,0,0,0,0,CV24,0,0,0,0,~
0,0,0,0,0,0,0,0,0,0,0)';
      PINUSE='POWER';
      NO_LOAD_CHECK='Both';
      NO_IO_CHECK='Both';
      NO_ASSERT_CHECK='TRUE';
      NO_DIR_CHECK='TRUE';
      ALLOW_CONNECT='TRUE';
    'VDDCR_CPU1_CV26':
      PIN_NUMBER='(0,0,0,0,0,0,0,0,0,0,0,0,0,0,0,0,0,0,0,0,0,0,0,0,CV26,0,0,0,0,~
0,0,0,0,0,0,0,0,0,0,0)';
      PINUSE='POWER';
      NO_LOAD_CHECK='Both';
      NO_IO_CHECK='Both';
      NO_ASSERT_CHECK='TRUE';
      NO_DIR_CHECK='TRUE';
      ALLOW_CONNECT='TRUE';
    'VDDCR_CPU1_CV27':
      PIN_NUMBER='(0,0,0,0,0,0,0,0,0,0,0,0,0,0,0,0,0,0,0,0,0,0,0,0,CV27,0,0,0,0,~
0,0,0,0,0,0,0,0,0,0,0)';
      PINUSE='POWER';
      NO_LOAD_CHECK='Both';
      NO_IO_CHECK='Both';
      NO_ASSERT_CHECK='TRUE';
      NO_DIR_CHECK='TRUE';
      ALLOW_CONNECT='TRUE';
    'VDDCR_CPU1_CV29':
      PIN_NUMBER='(0,0,0,0,0,0,0,0,0,0,0,0,0,0,0,0,0,0,0,0,0,0,0,0,CV29,0,0,0,0,~
0,0,0,0,0,0,0,0,0,0,0)';
      PINUSE='POWER';
      NO_LOAD_CHECK='Both';
      NO_IO_CHECK='Both';
      NO_ASSERT_CHECK='TRUE';
      NO_DIR_CHECK='TRUE';
      ALLOW_CONNECT='TRUE';
    'VDDCR_CPU1_CV30':
      PIN_NUMBER='(0,0,0,0,0,0,0,0,0,0,0,0,0,0,0,0,0,0,0,0,0,0,0,0,CV30,0,0,0,0,~
0,0,0,0,0,0,0,0,0,0,0)';
      PINUSE='POWER';
      NO_LOAD_CHECK='Both';
      NO_IO_CHECK='Both';
      NO_ASSERT_CHECK='TRUE';
      NO_DIR_CHECK='TRUE';
      ALLOW_CONNECT='TRUE';
    'VDDCR_CPU1_CV32':
      PIN_NUMBER='(0,0,0,0,0,0,0,0,0,0,0,0,0,0,0,0,0,0,0,0,0,0,0,0,CV32,0,0,0,0,~
0,0,0,0,0,0,0,0,0,0,0)';
      PINUSE='POWER';
      NO_LOAD_CHECK='Both';
      NO_IO_CHECK='Both';
      NO_ASSERT_CHECK='TRUE';
      NO_DIR_CHECK='TRUE';
      ALLOW_CONNECT='TRUE';
    'VDDCR_CPU1_CV33':
      PIN_NUMBER='(0,0,0,0,0,0,0,0,0,0,0,0,0,0,0,0,0,0,0,0,0,0,0,0,CV33,0,0,0,0,~
0,0,0,0,0,0,0,0,0,0,0)';
      PINUSE='POWER';
      NO_LOAD_CHECK='Both';
      NO_IO_CHECK='Both';
      NO_ASSERT_CHECK='TRUE';
      NO_DIR_CHECK='TRUE';
      ALLOW_CONNECT='TRUE';
    'VDDCR_CPU1_CV43':
      PIN_NUMBER='(0,0,0,0,0,0,0,0,0,0,0,0,0,0,0,0,0,0,0,0,0,0,0,0,CV43,0,0,0,0,~
0,0,0,0,0,0,0,0,0,0,0)';
      PINUSE='POWER';
      NO_LOAD_CHECK='Both';
      NO_IO_CHECK='Both';
      NO_ASSERT_CHECK='TRUE';
      NO_DIR_CHECK='TRUE';
      ALLOW_CONNECT='TRUE';
    'VDDCR_CPU1_CV44':
      PIN_NUMBER='(0,0,0,0,0,0,0,0,0,0,0,0,0,0,0,0,0,0,0,0,0,0,0,0,CV44,0,0,0,0,~
0,0,0,0,0,0,0,0,0,0,0)';
      PINUSE='POWER';
      NO_LOAD_CHECK='Both';
      NO_IO_CHECK='Both';
      NO_ASSERT_CHECK='TRUE';
      NO_DIR_CHECK='TRUE';
      ALLOW_CONNECT='TRUE';
    'VDDCR_CPU1_CV46':
      PIN_NUMBER='(0,0,0,0,0,0,0,0,0,0,0,0,0,0,0,0,0,0,0,0,0,0,0,0,CV46,0,0,0,0,~
0,0,0,0,0,0,0,0,0,0,0)';
      PINUSE='POWER';
      NO_LOAD_CHECK='Both';
      NO_IO_CHECK='Both';
      NO_ASSERT_CHECK='TRUE';
      NO_DIR_CHECK='TRUE';
      ALLOW_CONNECT='TRUE';
    'VDDCR_CPU1_CV47':
      PIN_NUMBER='(0,0,0,0,0,0,0,0,0,0,0,0,0,0,0,0,0,0,0,0,0,0,0,0,CV47,0,0,0,0,~
0,0,0,0,0,0,0,0,0,0,0)';
      PINUSE='POWER';
      NO_LOAD_CHECK='Both';
      NO_IO_CHECK='Both';
      NO_ASSERT_CHECK='TRUE';
      NO_DIR_CHECK='TRUE';
      ALLOW_CONNECT='TRUE';
    'VDDCR_CPU1_CV49':
      PIN_NUMBER='(0,0,0,0,0,0,0,0,0,0,0,0,0,0,0,0,0,0,0,0,0,0,0,0,CV49,0,0,0,0,~
0,0,0,0,0,0,0,0,0,0,0)';
      PINUSE='POWER';
      NO_LOAD_CHECK='Both';
      NO_IO_CHECK='Both';
      NO_ASSERT_CHECK='TRUE';
      NO_DIR_CHECK='TRUE';
      ALLOW_CONNECT='TRUE';
    'VDDCR_CPU1_CV50':
      PIN_NUMBER='(0,0,0,0,0,0,0,0,0,0,0,0,0,0,0,0,0,0,0,0,0,0,0,0,CV50,0,0,0,0,~
0,0,0,0,0,0,0,0,0,0,0)';
      PINUSE='POWER';
      NO_LOAD_CHECK='Both';
      NO_IO_CHECK='Both';
      NO_ASSERT_CHECK='TRUE';
      NO_DIR_CHECK='TRUE';
      ALLOW_CONNECT='TRUE';
    'VDDCR_CPU1_CV52':
      PIN_NUMBER='(0,0,0,0,0,0,0,0,0,0,0,0,0,0,0,0,0,0,0,0,0,0,0,0,CV52,0,0,0,0,~
0,0,0,0,0,0,0,0,0,0,0)';
      PINUSE='POWER';
      NO_LOAD_CHECK='Both';
      NO_IO_CHECK='Both';
      NO_ASSERT_CHECK='TRUE';
      NO_DIR_CHECK='TRUE';
      ALLOW_CONNECT='TRUE';
    'VDDCR_CPU1_CV53':
      PIN_NUMBER='(0,0,0,0,0,0,0,0,0,0,0,0,0,0,0,0,0,0,0,0,0,0,0,0,CV53,0,0,0,0,~
0,0,0,0,0,0,0,0,0,0,0)';
      PINUSE='POWER';
      NO_LOAD_CHECK='Both';
      NO_IO_CHECK='Both';
      NO_ASSERT_CHECK='TRUE';
      NO_DIR_CHECK='TRUE';
      ALLOW_CONNECT='TRUE';
    'VDDCR_CPU1_DA35':
      PIN_NUMBER='(0,0,0,0,0,0,0,0,0,0,0,0,0,0,0,0,0,0,0,0,0,0,0,0,DA35,0,0,0,0,~
0,0,0,0,0,0,0,0,0,0,0)';
      PINUSE='POWER';
      NO_LOAD_CHECK='Both';
      NO_IO_CHECK='Both';
      NO_ASSERT_CHECK='TRUE';
      NO_DIR_CHECK='TRUE';
      ALLOW_CONNECT='TRUE';
    'VDDCR_CPU1_DA36':
      PIN_NUMBER='(0,0,0,0,0,0,0,0,0,0,0,0,0,0,0,0,0,0,0,0,0,0,0,0,DA36,0,0,0,0,~
0,0,0,0,0,0,0,0,0,0,0)';
      PINUSE='POWER';
      NO_LOAD_CHECK='Both';
      NO_IO_CHECK='Both';
      NO_ASSERT_CHECK='TRUE';
      NO_DIR_CHECK='TRUE';
      ALLOW_CONNECT='TRUE';
    'VDDCR_CPU1_DA40':
      PIN_NUMBER='(0,0,0,0,0,0,0,0,0,0,0,0,0,0,0,0,0,0,0,0,0,0,0,0,DA40,0,0,0,0,~
0,0,0,0,0,0,0,0,0,0,0)';
      PINUSE='POWER';
      NO_LOAD_CHECK='Both';
      NO_IO_CHECK='Both';
      NO_ASSERT_CHECK='TRUE';
      NO_DIR_CHECK='TRUE';
      ALLOW_CONNECT='TRUE';
    'VDDCR_CPU1_DA41':
      PIN_NUMBER='(0,0,0,0,0,0,0,0,0,0,0,0,0,0,0,0,0,0,0,0,0,0,0,0,DA41,0,0,0,0,~
0,0,0,0,0,0,0,0,0,0,0)';
      PINUSE='POWER';
      NO_LOAD_CHECK='Both';
      NO_IO_CHECK='Both';
      NO_ASSERT_CHECK='TRUE';
      NO_DIR_CHECK='TRUE';
      ALLOW_CONNECT='TRUE';
    'VDDCR_CPU1_DB23':
      PIN_NUMBER='(0,0,0,0,0,0,0,0,0,0,0,0,0,0,0,0,0,0,0,0,0,0,0,0,DB23,0,0,0,0,~
0,0,0,0,0,0,0,0,0,0,0)';
      PINUSE='POWER';
      NO_LOAD_CHECK='Both';
      NO_IO_CHECK='Both';
      NO_ASSERT_CHECK='TRUE';
      NO_DIR_CHECK='TRUE';
      ALLOW_CONNECT='TRUE';
    'VDDCR_CPU1_DB24':
      PIN_NUMBER='(0,0,0,0,0,0,0,0,0,0,0,0,0,0,0,0,0,0,0,0,0,0,0,0,DB24,0,0,0,0,~
0,0,0,0,0,0,0,0,0,0,0)';
      PINUSE='POWER';
      NO_LOAD_CHECK='Both';
      NO_IO_CHECK='Both';
      NO_ASSERT_CHECK='TRUE';
      NO_DIR_CHECK='TRUE';
      ALLOW_CONNECT='TRUE';
    'VDDCR_CPU1_DB26':
      PIN_NUMBER='(0,0,0,0,0,0,0,0,0,0,0,0,0,0,0,0,0,0,0,0,0,0,0,0,DB26,0,0,0,0,~
0,0,0,0,0,0,0,0,0,0,0)';
      PINUSE='POWER';
      NO_LOAD_CHECK='Both';
      NO_IO_CHECK='Both';
      NO_ASSERT_CHECK='TRUE';
      NO_DIR_CHECK='TRUE';
      ALLOW_CONNECT='TRUE';
    'VDDCR_CPU1_DB27':
      PIN_NUMBER='(0,0,0,0,0,0,0,0,0,0,0,0,0,0,0,0,0,0,0,0,0,0,0,0,DB27,0,0,0,0,~
0,0,0,0,0,0,0,0,0,0,0)';
      PINUSE='POWER';
      NO_LOAD_CHECK='Both';
      NO_IO_CHECK='Both';
      NO_ASSERT_CHECK='TRUE';
      NO_DIR_CHECK='TRUE';
      ALLOW_CONNECT='TRUE';
    'VDDCR_CPU1_DB29':
      PIN_NUMBER='(0,0,0,0,0,0,0,0,0,0,0,0,0,0,0,0,0,0,0,0,0,0,0,0,DB29,0,0,0,0,~
0,0,0,0,0,0,0,0,0,0,0)';
      PINUSE='POWER';
      NO_LOAD_CHECK='Both';
      NO_IO_CHECK='Both';
      NO_ASSERT_CHECK='TRUE';
      NO_DIR_CHECK='TRUE';
      ALLOW_CONNECT='TRUE';
    'VDDCR_CPU1_DB30':
      PIN_NUMBER='(0,0,0,0,0,0,0,0,0,0,0,0,0,0,0,0,0,0,0,0,0,0,0,0,DB30,0,0,0,0,~
0,0,0,0,0,0,0,0,0,0,0)';
      PINUSE='POWER';
      NO_LOAD_CHECK='Both';
      NO_IO_CHECK='Both';
      NO_ASSERT_CHECK='TRUE';
      NO_DIR_CHECK='TRUE';
      ALLOW_CONNECT='TRUE';
    'VDDCR_CPU1_DB32':
      PIN_NUMBER='(0,0,0,0,0,0,0,0,0,0,0,0,0,0,0,0,0,0,0,0,0,0,0,0,DB32,0,0,0,0,~
0,0,0,0,0,0,0,0,0,0,0)';
      PINUSE='POWER';
      NO_LOAD_CHECK='Both';
      NO_IO_CHECK='Both';
      NO_ASSERT_CHECK='TRUE';
      NO_DIR_CHECK='TRUE';
      ALLOW_CONNECT='TRUE';
    'VDDCR_CPU1_DB33':
      PIN_NUMBER='(0,0,0,0,0,0,0,0,0,0,0,0,0,0,0,0,0,0,0,0,0,0,0,0,DB33,0,0,0,0,~
0,0,0,0,0,0,0,0,0,0,0)';
      PINUSE='POWER';
      NO_LOAD_CHECK='Both';
      NO_IO_CHECK='Both';
      NO_ASSERT_CHECK='TRUE';
      NO_DIR_CHECK='TRUE';
      ALLOW_CONNECT='TRUE';
    'VDDCR_CPU1_DB43':
      PIN_NUMBER='(0,0,0,0,0,0,0,0,0,0,0,0,0,0,0,0,0,0,0,0,0,0,0,0,DB43,0,0,0,0,~
0,0,0,0,0,0,0,0,0,0,0)';
      PINUSE='POWER';
      NO_LOAD_CHECK='Both';
      NO_IO_CHECK='Both';
      NO_ASSERT_CHECK='TRUE';
      NO_DIR_CHECK='TRUE';
      ALLOW_CONNECT='TRUE';
    'VDDCR_CPU1_DB44':
      PIN_NUMBER='(0,0,0,0,0,0,0,0,0,0,0,0,0,0,0,0,0,0,0,0,0,0,0,0,DB44,0,0,0,0,~
0,0,0,0,0,0,0,0,0,0,0)';
      PINUSE='POWER';
      NO_LOAD_CHECK='Both';
      NO_IO_CHECK='Both';
      NO_ASSERT_CHECK='TRUE';
      NO_DIR_CHECK='TRUE';
      ALLOW_CONNECT='TRUE';
    'VDDCR_CPU1_DB46':
      PIN_NUMBER='(0,0,0,0,0,0,0,0,0,0,0,0,0,0,0,0,0,0,0,0,0,0,0,0,DB46,0,0,0,0,~
0,0,0,0,0,0,0,0,0,0,0)';
      PINUSE='POWER';
      NO_LOAD_CHECK='Both';
      NO_IO_CHECK='Both';
      NO_ASSERT_CHECK='TRUE';
      NO_DIR_CHECK='TRUE';
      ALLOW_CONNECT='TRUE';
    'VDDCR_CPU1_DB47':
      PIN_NUMBER='(0,0,0,0,0,0,0,0,0,0,0,0,0,0,0,0,0,0,0,0,0,0,0,0,DB47,0,0,0,0,~
0,0,0,0,0,0,0,0,0,0,0)';
      PINUSE='POWER';
      NO_LOAD_CHECK='Both';
      NO_IO_CHECK='Both';
      NO_ASSERT_CHECK='TRUE';
      NO_DIR_CHECK='TRUE';
      ALLOW_CONNECT='TRUE';
    'VDDCR_CPU1_DB49':
      PIN_NUMBER='(0,0,0,0,0,0,0,0,0,0,0,0,0,0,0,0,0,0,0,0,0,0,0,0,DB49,0,0,0,0,~
0,0,0,0,0,0,0,0,0,0,0)';
      PINUSE='POWER';
      NO_LOAD_CHECK='Both';
      NO_IO_CHECK='Both';
      NO_ASSERT_CHECK='TRUE';
      NO_DIR_CHECK='TRUE';
      ALLOW_CONNECT='TRUE';
    'VDDCR_CPU1_DB50':
      PIN_NUMBER='(0,0,0,0,0,0,0,0,0,0,0,0,0,0,0,0,0,0,0,0,0,0,0,0,DB50,0,0,0,0,~
0,0,0,0,0,0,0,0,0,0,0)';
      PINUSE='POWER';
      NO_LOAD_CHECK='Both';
      NO_IO_CHECK='Both';
      NO_ASSERT_CHECK='TRUE';
      NO_DIR_CHECK='TRUE';
      ALLOW_CONNECT='TRUE';
    'VDDCR_CPU1_DB52':
      PIN_NUMBER='(0,0,0,0,0,0,0,0,0,0,0,0,0,0,0,0,0,0,0,0,0,0,0,0,DB52,0,0,0,0,~
0,0,0,0,0,0,0,0,0,0,0)';
      PINUSE='POWER';
      NO_LOAD_CHECK='Both';
      NO_IO_CHECK='Both';
      NO_ASSERT_CHECK='TRUE';
      NO_DIR_CHECK='TRUE';
      ALLOW_CONNECT='TRUE';
    'VDDCR_CPU1_DB53':
      PIN_NUMBER='(0,0,0,0,0,0,0,0,0,0,0,0,0,0,0,0,0,0,0,0,0,0,0,0,DB53,0,0,0,0,~
0,0,0,0,0,0,0,0,0,0,0)';
      PINUSE='POWER';
      NO_LOAD_CHECK='Both';
      NO_IO_CHECK='Both';
      NO_ASSERT_CHECK='TRUE';
      NO_DIR_CHECK='TRUE';
      ALLOW_CONNECT='TRUE';
    'VDDCR_CPU1_DC35':
      PIN_NUMBER='(0,0,0,0,0,0,0,0,0,0,0,0,0,0,0,0,0,0,0,0,0,0,0,0,DC35,0,0,0,0,~
0,0,0,0,0,0,0,0,0,0,0)';
      PINUSE='POWER';
      NO_LOAD_CHECK='Both';
      NO_IO_CHECK='Both';
      NO_ASSERT_CHECK='TRUE';
      NO_DIR_CHECK='TRUE';
      ALLOW_CONNECT='TRUE';
    'VDDCR_CPU1_DC36':
      PIN_NUMBER='(0,0,0,0,0,0,0,0,0,0,0,0,0,0,0,0,0,0,0,0,0,0,0,0,DC36,0,0,0,0,~
0,0,0,0,0,0,0,0,0,0,0)';
      PINUSE='POWER';
      NO_LOAD_CHECK='Both';
      NO_IO_CHECK='Both';
      NO_ASSERT_CHECK='TRUE';
      NO_DIR_CHECK='TRUE';
      ALLOW_CONNECT='TRUE';
    'VDDCR_CPU1_DC40':
      PIN_NUMBER='(0,0,0,0,0,0,0,0,0,0,0,0,0,0,0,0,0,0,0,0,0,0,0,0,DC40,0,0,0,0,~
0,0,0,0,0,0,0,0,0,0,0)';
      PINUSE='POWER';
      NO_LOAD_CHECK='Both';
      NO_IO_CHECK='Both';
      NO_ASSERT_CHECK='TRUE';
      NO_DIR_CHECK='TRUE';
      ALLOW_CONNECT='TRUE';
    'VDDCR_CPU1_DC41':
      PIN_NUMBER='(0,0,0,0,0,0,0,0,0,0,0,0,0,0,0,0,0,0,0,0,0,0,0,0,DC41,0,0,0,0,~
0,0,0,0,0,0,0,0,0,0,0)';
      PINUSE='POWER';
      NO_LOAD_CHECK='Both';
      NO_IO_CHECK='Both';
      NO_ASSERT_CHECK='TRUE';
      NO_DIR_CHECK='TRUE';
      ALLOW_CONNECT='TRUE';
    'VDDCR_CPU1_DD22':
      PIN_NUMBER='(0,0,0,0,0,0,0,0,0,0,0,0,0,0,0,0,0,0,0,0,0,0,0,0,DD22,0,0,0,0,~
0,0,0,0,0,0,0,0,0,0,0)';
      PINUSE='POWER';
      NO_LOAD_CHECK='Both';
      NO_IO_CHECK='Both';
      NO_ASSERT_CHECK='TRUE';
      NO_DIR_CHECK='TRUE';
      ALLOW_CONNECT='TRUE';
    'VDDCR_CPU1_DD25':
      PIN_NUMBER='(0,0,0,0,0,0,0,0,0,0,0,0,0,0,0,0,0,0,0,0,0,0,0,0,DD25,0,0,0,0,~
0,0,0,0,0,0,0,0,0,0,0)';
      PINUSE='POWER';
      NO_LOAD_CHECK='Both';
      NO_IO_CHECK='Both';
      NO_ASSERT_CHECK='TRUE';
      NO_DIR_CHECK='TRUE';
      ALLOW_CONNECT='TRUE';
    'VDDCR_CPU1_DD28':
      PIN_NUMBER='(0,0,0,0,0,0,0,0,0,0,0,0,0,0,0,0,0,0,0,0,0,0,0,0,DD28,0,0,0,0,~
0,0,0,0,0,0,0,0,0,0,0)';
      PINUSE='POWER';
      NO_LOAD_CHECK='Both';
      NO_IO_CHECK='Both';
      NO_ASSERT_CHECK='TRUE';
      NO_DIR_CHECK='TRUE';
      ALLOW_CONNECT='TRUE';
    'VDDCR_CPU1_DD31':
      PIN_NUMBER='(0,0,0,0,0,0,0,0,0,0,0,0,0,0,0,0,0,0,0,0,0,0,0,0,DD31,0,0,0,0,~
0,0,0,0,0,0,0,0,0,0,0)';
      PINUSE='POWER';
      NO_LOAD_CHECK='Both';
      NO_IO_CHECK='Both';
      NO_ASSERT_CHECK='TRUE';
      NO_DIR_CHECK='TRUE';
      ALLOW_CONNECT='TRUE';
    'VDDCR_CPU1_DD34':
      PIN_NUMBER='(0,0,0,0,0,0,0,0,0,0,0,0,0,0,0,0,0,0,0,0,0,0,0,0,DD34,0,0,0,0,~
0,0,0,0,0,0,0,0,0,0,0)';
      PINUSE='POWER';
      NO_LOAD_CHECK='Both';
      NO_IO_CHECK='Both';
      NO_ASSERT_CHECK='TRUE';
      NO_DIR_CHECK='TRUE';
      ALLOW_CONNECT='TRUE';
    'VDDCR_CPU1_DD42':
      PIN_NUMBER='(0,0,0,0,0,0,0,0,0,0,0,0,0,0,0,0,0,0,0,0,0,0,0,0,DD42,0,0,0,0,~
0,0,0,0,0,0,0,0,0,0,0)';
      PINUSE='POWER';
      NO_LOAD_CHECK='Both';
      NO_IO_CHECK='Both';
      NO_ASSERT_CHECK='TRUE';
      NO_DIR_CHECK='TRUE';
      ALLOW_CONNECT='TRUE';
    'VDDCR_CPU1_DD45':
      PIN_NUMBER='(0,0,0,0,0,0,0,0,0,0,0,0,0,0,0,0,0,0,0,0,0,0,0,0,DD45,0,0,0,0,~
0,0,0,0,0,0,0,0,0,0,0)';
      PINUSE='POWER';
      NO_LOAD_CHECK='Both';
      NO_IO_CHECK='Both';
      NO_ASSERT_CHECK='TRUE';
      NO_DIR_CHECK='TRUE';
      ALLOW_CONNECT='TRUE';
    'VDDCR_CPU1_DD48':
      PIN_NUMBER='(0,0,0,0,0,0,0,0,0,0,0,0,0,0,0,0,0,0,0,0,0,0,0,0,DD48,0,0,0,0,~
0,0,0,0,0,0,0,0,0,0,0)';
      PINUSE='POWER';
      NO_LOAD_CHECK='Both';
      NO_IO_CHECK='Both';
      NO_ASSERT_CHECK='TRUE';
      NO_DIR_CHECK='TRUE';
      ALLOW_CONNECT='TRUE';
    'VDDCR_CPU1_DD51':
      PIN_NUMBER='(0,0,0,0,0,0,0,0,0,0,0,0,0,0,0,0,0,0,0,0,0,0,0,0,DD51,0,0,0,0,~
0,0,0,0,0,0,0,0,0,0,0)';
      PINUSE='POWER';
      NO_LOAD_CHECK='Both';
      NO_IO_CHECK='Both';
      NO_ASSERT_CHECK='TRUE';
      NO_DIR_CHECK='TRUE';
      ALLOW_CONNECT='TRUE';
    'VDDCR_CPU1_DD54':
      PIN_NUMBER='(0,0,0,0,0,0,0,0,0,0,0,0,0,0,0,0,0,0,0,0,0,0,0,0,DD54,0,0,0,0,~
0,0,0,0,0,0,0,0,0,0,0)';
      PINUSE='POWER';
      NO_LOAD_CHECK='Both';
      NO_IO_CHECK='Both';
      NO_ASSERT_CHECK='TRUE';
      NO_DIR_CHECK='TRUE';
      ALLOW_CONNECT='TRUE';
    'VDDCR_CPU1_DE22':
      PIN_NUMBER='(0,0,0,0,0,0,0,0,0,0,0,0,0,0,0,0,0,0,0,0,0,0,0,0,DE22,0,0,0,0,~
0,0,0,0,0,0,0,0,0,0,0)';
      PINUSE='POWER';
      NO_LOAD_CHECK='Both';
      NO_IO_CHECK='Both';
      NO_ASSERT_CHECK='TRUE';
      NO_DIR_CHECK='TRUE';
      ALLOW_CONNECT='TRUE';
    'VDDCR_CPU1_DE25':
      PIN_NUMBER='(0,0,0,0,0,0,0,0,0,0,0,0,0,0,0,0,0,0,0,0,0,0,0,0,DE25,0,0,0,0,~
0,0,0,0,0,0,0,0,0,0,0)';
      PINUSE='POWER';
      NO_LOAD_CHECK='Both';
      NO_IO_CHECK='Both';
      NO_ASSERT_CHECK='TRUE';
      NO_DIR_CHECK='TRUE';
      ALLOW_CONNECT='TRUE';
    'VDDCR_CPU1_DE28':
      PIN_NUMBER='(0,0,0,0,0,0,0,0,0,0,0,0,0,0,0,0,0,0,0,0,0,0,0,0,DE28,0,0,0,0,~
0,0,0,0,0,0,0,0,0,0,0)';
      PINUSE='POWER';
      NO_LOAD_CHECK='Both';
      NO_IO_CHECK='Both';
      NO_ASSERT_CHECK='TRUE';
      NO_DIR_CHECK='TRUE';
      ALLOW_CONNECT='TRUE';
    'VDDCR_CPU1_DE31':
      PIN_NUMBER='(0,0,0,0,0,0,0,0,0,0,0,0,0,0,0,0,0,0,0,0,0,0,0,0,DE31,0,0,0,0,~
0,0,0,0,0,0,0,0,0,0,0)';
      PINUSE='POWER';
      NO_LOAD_CHECK='Both';
      NO_IO_CHECK='Both';
      NO_ASSERT_CHECK='TRUE';
      NO_DIR_CHECK='TRUE';
      ALLOW_CONNECT='TRUE';
    'VDDCR_CPU1_DE34':
      PIN_NUMBER='(0,0,0,0,0,0,0,0,0,0,0,0,0,0,0,0,0,0,0,0,0,0,0,0,DE34,0,0,0,0,~
0,0,0,0,0,0,0,0,0,0,0)';
      PINUSE='POWER';
      NO_LOAD_CHECK='Both';
      NO_IO_CHECK='Both';
      NO_ASSERT_CHECK='TRUE';
      NO_DIR_CHECK='TRUE';
      ALLOW_CONNECT='TRUE';
    'VDDCR_CPU1_DE35':
      PIN_NUMBER='(0,0,0,0,0,0,0,0,0,0,0,0,0,0,0,0,0,0,0,0,0,0,0,0,DE35,0,0,0,0,~
0,0,0,0,0,0,0,0,0,0,0)';
      PINUSE='POWER';
      NO_LOAD_CHECK='Both';
      NO_IO_CHECK='Both';
      NO_ASSERT_CHECK='TRUE';
      NO_DIR_CHECK='TRUE';
      ALLOW_CONNECT='TRUE';
    'VDDCR_CPU1_DE41':
      PIN_NUMBER='(0,0,0,0,0,0,0,0,0,0,0,0,0,0,0,0,0,0,0,0,0,0,0,0,DE41,0,0,0,0,~
0,0,0,0,0,0,0,0,0,0,0)';
      PINUSE='POWER';
      NO_LOAD_CHECK='Both';
      NO_IO_CHECK='Both';
      NO_ASSERT_CHECK='TRUE';
      NO_DIR_CHECK='TRUE';
      ALLOW_CONNECT='TRUE';
    'VDDCR_CPU1_DE42':
      PIN_NUMBER='(0,0,0,0,0,0,0,0,0,0,0,0,0,0,0,0,0,0,0,0,0,0,0,0,DE42,0,0,0,0,~
0,0,0,0,0,0,0,0,0,0,0)';
      PINUSE='POWER';
      NO_LOAD_CHECK='Both';
      NO_IO_CHECK='Both';
      NO_ASSERT_CHECK='TRUE';
      NO_DIR_CHECK='TRUE';
      ALLOW_CONNECT='TRUE';
    'VDDCR_CPU1_DE45':
      PIN_NUMBER='(0,0,0,0,0,0,0,0,0,0,0,0,0,0,0,0,0,0,0,0,0,0,0,0,DE45,0,0,0,0,~
0,0,0,0,0,0,0,0,0,0,0)';
      PINUSE='POWER';
      NO_LOAD_CHECK='Both';
      NO_IO_CHECK='Both';
      NO_ASSERT_CHECK='TRUE';
      NO_DIR_CHECK='TRUE';
      ALLOW_CONNECT='TRUE';
    'VDDCR_CPU1_DE48':
      PIN_NUMBER='(0,0,0,0,0,0,0,0,0,0,0,0,0,0,0,0,0,0,0,0,0,0,0,0,DE48,0,0,0,0,~
0,0,0,0,0,0,0,0,0,0,0)';
      PINUSE='POWER';
      NO_LOAD_CHECK='Both';
      NO_IO_CHECK='Both';
      NO_ASSERT_CHECK='TRUE';
      NO_DIR_CHECK='TRUE';
      ALLOW_CONNECT='TRUE';
    'VDDCR_CPU1_DE51':
      PIN_NUMBER='(0,0,0,0,0,0,0,0,0,0,0,0,0,0,0,0,0,0,0,0,0,0,0,0,DE51,0,0,0,0,~
0,0,0,0,0,0,0,0,0,0,0)';
      PINUSE='POWER';
      NO_LOAD_CHECK='Both';
      NO_IO_CHECK='Both';
      NO_ASSERT_CHECK='TRUE';
      NO_DIR_CHECK='TRUE';
      ALLOW_CONNECT='TRUE';
    'VDDCR_CPU1_DE54':
      PIN_NUMBER='(0,0,0,0,0,0,0,0,0,0,0,0,0,0,0,0,0,0,0,0,0,0,0,0,DE54,0,0,0,0,~
0,0,0,0,0,0,0,0,0,0,0)';
      PINUSE='POWER';
      NO_LOAD_CHECK='Both';
      NO_IO_CHECK='Both';
      NO_ASSERT_CHECK='TRUE';
      NO_DIR_CHECK='TRUE';
      ALLOW_CONNECT='TRUE';
    'VDDCR_CPU1_DG19':
      PIN_NUMBER='(0,0,0,0,0,0,0,0,0,0,0,0,0,0,0,0,0,0,0,0,0,0,0,0,DG19,0,0,0,0,~
0,0,0,0,0,0,0,0,0,0,0)';
      PINUSE='POWER';
      NO_LOAD_CHECK='Both';
      NO_IO_CHECK='Both';
      NO_ASSERT_CHECK='TRUE';
      NO_DIR_CHECK='TRUE';
      ALLOW_CONNECT='TRUE';
    'VDDCR_CPU1_DG57':
      PIN_NUMBER='(0,0,0,0,0,0,0,0,0,0,0,0,0,0,0,0,0,0,0,0,0,0,0,0,DG57,0,0,0,0,~
0,0,0,0,0,0,0,0,0,0,0)';
      PINUSE='POWER';
      NO_LOAD_CHECK='Both';
      NO_IO_CHECK='Both';
      NO_ASSERT_CHECK='TRUE';
      NO_DIR_CHECK='TRUE';
      ALLOW_CONNECT='TRUE';
    'VDDCR_CPU1_DH19':
      PIN_NUMBER='(0,0,0,0,0,0,0,0,0,0,0,0,0,0,0,0,0,0,0,0,0,0,0,0,DH19,0,0,0,0,~
0,0,0,0,0,0,0,0,0,0,0)';
      PINUSE='POWER';
      NO_LOAD_CHECK='Both';
      NO_IO_CHECK='Both';
      NO_ASSERT_CHECK='TRUE';
      NO_DIR_CHECK='TRUE';
      ALLOW_CONNECT='TRUE';
    'VDDCR_CPU1_DH20':
      PIN_NUMBER='(0,0,0,0,0,0,0,0,0,0,0,0,0,0,0,0,0,0,0,0,0,0,0,0,DH20,0,0,0,0,~
0,0,0,0,0,0,0,0,0,0,0)';
      PINUSE='POWER';
      NO_LOAD_CHECK='Both';
      NO_IO_CHECK='Both';
      NO_ASSERT_CHECK='TRUE';
      NO_DIR_CHECK='TRUE';
      ALLOW_CONNECT='TRUE';
    'VDDCR_CPU1_DH22':
      PIN_NUMBER='(0,0,0,0,0,0,0,0,0,0,0,0,0,0,0,0,0,0,0,0,0,0,0,0,DH22,0,0,0,0,~
0,0,0,0,0,0,0,0,0,0,0)';
      PINUSE='POWER';
      NO_LOAD_CHECK='Both';
      NO_IO_CHECK='Both';
      NO_ASSERT_CHECK='TRUE';
      NO_DIR_CHECK='TRUE';
      ALLOW_CONNECT='TRUE';
    'VDDCR_CPU1_DH23':
      PIN_NUMBER='(0,0,0,0,0,0,0,0,0,0,0,0,0,0,0,0,0,0,0,0,0,0,0,0,DH23,0,0,0,0,~
0,0,0,0,0,0,0,0,0,0,0)';
      PINUSE='POWER';
      NO_LOAD_CHECK='Both';
      NO_IO_CHECK='Both';
      NO_ASSERT_CHECK='TRUE';
      NO_DIR_CHECK='TRUE';
      ALLOW_CONNECT='TRUE';
    'VDDCR_CPU1_DH25':
      PIN_NUMBER='(0,0,0,0,0,0,0,0,0,0,0,0,0,0,0,0,0,0,0,0,0,0,0,0,DH25,0,0,0,0,~
0,0,0,0,0,0,0,0,0,0,0)';
      PINUSE='POWER';
      NO_LOAD_CHECK='Both';
      NO_IO_CHECK='Both';
      NO_ASSERT_CHECK='TRUE';
      NO_DIR_CHECK='TRUE';
      ALLOW_CONNECT='TRUE';
    'VDDCR_CPU1_DH26':
      PIN_NUMBER='(0,0,0,0,0,0,0,0,0,0,0,0,0,0,0,0,0,0,0,0,0,0,0,0,DH26,0,0,0,0,~
0,0,0,0,0,0,0,0,0,0,0)';
      PINUSE='POWER';
      NO_LOAD_CHECK='Both';
      NO_IO_CHECK='Both';
      NO_ASSERT_CHECK='TRUE';
      NO_DIR_CHECK='TRUE';
      ALLOW_CONNECT='TRUE';
    'VDDCR_CPU1_DH28':
      PIN_NUMBER='(0,0,0,0,0,0,0,0,0,0,0,0,0,0,0,0,0,0,0,0,0,0,0,0,DH28,0,0,0,0,~
0,0,0,0,0,0,0,0,0,0,0)';
      PINUSE='POWER';
      NO_LOAD_CHECK='Both';
      NO_IO_CHECK='Both';
      NO_ASSERT_CHECK='TRUE';
      NO_DIR_CHECK='TRUE';
      ALLOW_CONNECT='TRUE';
    'VDDCR_CPU1_DH29':
      PIN_NUMBER='(0,0,0,0,0,0,0,0,0,0,0,0,0,0,0,0,0,0,0,0,0,0,0,0,DH29,0,0,0,0,~
0,0,0,0,0,0,0,0,0,0,0)';
      PINUSE='POWER';
      NO_LOAD_CHECK='Both';
      NO_IO_CHECK='Both';
      NO_ASSERT_CHECK='TRUE';
      NO_DIR_CHECK='TRUE';
      ALLOW_CONNECT='TRUE';
    'VDDCR_CPU1_DH31':
      PIN_NUMBER='(0,0,0,0,0,0,0,0,0,0,0,0,0,0,0,0,0,0,0,0,0,0,0,0,DH31,0,0,0,0,~
0,0,0,0,0,0,0,0,0,0,0)';
      PINUSE='POWER';
      NO_LOAD_CHECK='Both';
      NO_IO_CHECK='Both';
      NO_ASSERT_CHECK='TRUE';
      NO_DIR_CHECK='TRUE';
      ALLOW_CONNECT='TRUE';
    'VDDCR_CPU1_DH32':
      PIN_NUMBER='(0,0,0,0,0,0,0,0,0,0,0,0,0,0,0,0,0,0,0,0,0,0,0,0,DH32,0,0,0,0,~
0,0,0,0,0,0,0,0,0,0,0)';
      PINUSE='POWER';
      NO_LOAD_CHECK='Both';
      NO_IO_CHECK='Both';
      NO_ASSERT_CHECK='TRUE';
      NO_DIR_CHECK='TRUE';
      ALLOW_CONNECT='TRUE';
    'VDDCR_CPU1_DH34':
      PIN_NUMBER='(0,0,0,0,0,0,0,0,0,0,0,0,0,0,0,0,0,0,0,0,0,0,0,0,DH34,0,0,0,0,~
0,0,0,0,0,0,0,0,0,0,0)';
      PINUSE='POWER';
      NO_LOAD_CHECK='Both';
      NO_IO_CHECK='Both';
      NO_ASSERT_CHECK='TRUE';
      NO_DIR_CHECK='TRUE';
      ALLOW_CONNECT='TRUE';
    'VDDCR_CPU1_DH35':
      PIN_NUMBER='(0,0,0,0,0,0,0,0,0,0,0,0,0,0,0,0,0,0,0,0,0,0,0,0,DH35,0,0,0,0,~
0,0,0,0,0,0,0,0,0,0,0)';
      PINUSE='POWER';
      NO_LOAD_CHECK='Both';
      NO_IO_CHECK='Both';
      NO_ASSERT_CHECK='TRUE';
      NO_DIR_CHECK='TRUE';
      ALLOW_CONNECT='TRUE';
    'VDDCR_CPU1_DH41':
      PIN_NUMBER='(0,0,0,0,0,0,0,0,0,0,0,0,0,0,0,0,0,0,0,0,0,0,0,0,DH41,0,0,0,0,~
0,0,0,0,0,0,0,0,0,0,0)';
      PINUSE='POWER';
      NO_LOAD_CHECK='Both';
      NO_IO_CHECK='Both';
      NO_ASSERT_CHECK='TRUE';
      NO_DIR_CHECK='TRUE';
      ALLOW_CONNECT='TRUE';
    'VDDCR_CPU1_DH42':
      PIN_NUMBER='(0,0,0,0,0,0,0,0,0,0,0,0,0,0,0,0,0,0,0,0,0,0,0,0,DH42,0,0,0,0,~
0,0,0,0,0,0,0,0,0,0,0)';
      PINUSE='POWER';
      NO_LOAD_CHECK='Both';
      NO_IO_CHECK='Both';
      NO_ASSERT_CHECK='TRUE';
      NO_DIR_CHECK='TRUE';
      ALLOW_CONNECT='TRUE';
    'VDDCR_CPU1_DH44':
      PIN_NUMBER='(0,0,0,0,0,0,0,0,0,0,0,0,0,0,0,0,0,0,0,0,0,0,0,0,DH44,0,0,0,0,~
0,0,0,0,0,0,0,0,0,0,0)';
      PINUSE='POWER';
      NO_LOAD_CHECK='Both';
      NO_IO_CHECK='Both';
      NO_ASSERT_CHECK='TRUE';
      NO_DIR_CHECK='TRUE';
      ALLOW_CONNECT='TRUE';
    'VDDCR_CPU1_DH53':
      PIN_NUMBER='(0,0,0,0,0,0,0,0,0,0,0,0,0,0,0,0,0,0,0,0,0,0,0,0,DH53,0,0,0,0,~
0,0,0,0,0,0,0,0,0,0,0)';
      PINUSE='POWER';
      NO_LOAD_CHECK='Both';
      NO_IO_CHECK='Both';
      NO_ASSERT_CHECK='TRUE';
      NO_DIR_CHECK='TRUE';
      ALLOW_CONNECT='TRUE';
    'VDDCR_CPU1_DH54':
      PIN_NUMBER='(0,0,0,0,0,0,0,0,0,0,0,0,0,0,0,0,0,0,0,0,0,0,0,0,DH54,0,0,0,0,~
0,0,0,0,0,0,0,0,0,0,0)';
      PINUSE='POWER';
      NO_LOAD_CHECK='Both';
      NO_IO_CHECK='Both';
      NO_ASSERT_CHECK='TRUE';
      NO_DIR_CHECK='TRUE';
      ALLOW_CONNECT='TRUE';
    'VDDCR_CPU1_DH56':
      PIN_NUMBER='(0,0,0,0,0,0,0,0,0,0,0,0,0,0,0,0,0,0,0,0,0,0,0,0,DH56,0,0,0,0,~
0,0,0,0,0,0,0,0,0,0,0)';
      PINUSE='POWER';
      NO_LOAD_CHECK='Both';
      NO_IO_CHECK='Both';
      NO_ASSERT_CHECK='TRUE';
      NO_DIR_CHECK='TRUE';
      ALLOW_CONNECT='TRUE';
    'VDDCR_CPU1_DH57':
      PIN_NUMBER='(0,0,0,0,0,0,0,0,0,0,0,0,0,0,0,0,0,0,0,0,0,0,0,0,DH57,0,0,0,0,~
0,0,0,0,0,0,0,0,0,0,0)';
      PINUSE='POWER';
      NO_LOAD_CHECK='Both';
      NO_IO_CHECK='Both';
      NO_ASSERT_CHECK='TRUE';
      NO_DIR_CHECK='TRUE';
      ALLOW_CONNECT='TRUE';
    'VDDCR_CPU1_DH45':
      PIN_NUMBER='(0,0,0,0,0,0,0,0,0,0,0,0,0,0,0,0,0,0,0,0,0,0,0,0,DH45,0,0,0,0,~
0,0,0,0,0,0,0,0,0,0,0)';
      PINUSE='POWER';
      NO_LOAD_CHECK='Both';
      NO_IO_CHECK='Both';
      NO_ASSERT_CHECK='TRUE';
      NO_DIR_CHECK='TRUE';
      ALLOW_CONNECT='TRUE';
    'VDDCR_CPU1_DH47':
      PIN_NUMBER='(0,0,0,0,0,0,0,0,0,0,0,0,0,0,0,0,0,0,0,0,0,0,0,0,DH47,0,0,0,0,~
0,0,0,0,0,0,0,0,0,0,0)';
      PINUSE='POWER';
      NO_LOAD_CHECK='Both';
      NO_IO_CHECK='Both';
      NO_ASSERT_CHECK='TRUE';
      NO_DIR_CHECK='TRUE';
      ALLOW_CONNECT='TRUE';
    'VDDCR_CPU1_DH48':
      PIN_NUMBER='(0,0,0,0,0,0,0,0,0,0,0,0,0,0,0,0,0,0,0,0,0,0,0,0,DH48,0,0,0,0,~
0,0,0,0,0,0,0,0,0,0,0)';
      PINUSE='POWER';
      NO_LOAD_CHECK='Both';
      NO_IO_CHECK='Both';
      NO_ASSERT_CHECK='TRUE';
      NO_DIR_CHECK='TRUE';
      ALLOW_CONNECT='TRUE';
    'VDDCR_CPU1_DH50':
      PIN_NUMBER='(0,0,0,0,0,0,0,0,0,0,0,0,0,0,0,0,0,0,0,0,0,0,0,0,DH50,0,0,0,0,~
0,0,0,0,0,0,0,0,0,0,0)';
      PINUSE='POWER';
      NO_LOAD_CHECK='Both';
      NO_IO_CHECK='Both';
      NO_ASSERT_CHECK='TRUE';
      NO_DIR_CHECK='TRUE';
      ALLOW_CONNECT='TRUE';
    'VDDCR_CPU1_DH51':
      PIN_NUMBER='(0,0,0,0,0,0,0,0,0,0,0,0,0,0,0,0,0,0,0,0,0,0,0,0,DH51,0,0,0,0,~
0,0,0,0,0,0,0,0,0,0,0)';
      PINUSE='POWER';
      NO_LOAD_CHECK='Both';
      NO_IO_CHECK='Both';
      NO_ASSERT_CHECK='TRUE';
      NO_DIR_CHECK='TRUE';
      ALLOW_CONNECT='TRUE';
    'VDDCR_CPU1_BP24':
      PIN_NUMBER='(0,0,0,0,0,0,0,0,0,0,0,0,0,0,0,0,0,0,0,0,0,0,0,0,BP24,0,0,0,0,~
0,0,0,0,0,0,0,0,0,0,0)';
      PINUSE='POWER';
      NO_LOAD_CHECK='Both';
      NO_IO_CHECK='Both';
      NO_ASSERT_CHECK='TRUE';
      NO_DIR_CHECK='TRUE';
      ALLOW_CONNECT='TRUE';
    'VDDCR_CPU1_BP28':
      PIN_NUMBER='(0,0,0,0,0,0,0,0,0,0,0,0,0,0,0,0,0,0,0,0,0,0,0,0,BP28,0,0,0,0,~
0,0,0,0,0,0,0,0,0,0,0)';
      PINUSE='POWER';
      NO_LOAD_CHECK='Both';
      NO_IO_CHECK='Both';
      NO_ASSERT_CHECK='TRUE';
      NO_DIR_CHECK='TRUE';
      ALLOW_CONNECT='TRUE';
    'VDDCR_CPU1_BP32':
      PIN_NUMBER='(0,0,0,0,0,0,0,0,0,0,0,0,0,0,0,0,0,0,0,0,0,0,0,0,BP32,0,0,0,0,~
0,0,0,0,0,0,0,0,0,0,0)';
      PINUSE='POWER';
      NO_LOAD_CHECK='Both';
      NO_IO_CHECK='Both';
      NO_ASSERT_CHECK='TRUE';
      NO_DIR_CHECK='TRUE';
      ALLOW_CONNECT='TRUE';
    'VDDCR_CPU1_BN27':
      PIN_NUMBER='(0,0,0,0,0,0,0,0,0,0,0,0,0,0,0,0,0,0,0,0,0,0,0,0,BN27,0,0,0,0,~
0,0,0,0,0,0,0,0,0,0,0)';
      PINUSE='POWER';
      NO_LOAD_CHECK='Both';
      NO_IO_CHECK='Both';
      NO_ASSERT_CHECK='TRUE';
      NO_DIR_CHECK='TRUE';
      ALLOW_CONNECT='TRUE';
    'VDDCR_CPU1_BN35':
      PIN_NUMBER='(0,0,0,0,0,0,0,0,0,0,0,0,0,0,0,0,0,0,0,0,0,0,0,0,BN35,0,0,0,0,~
0,0,0,0,0,0,0,0,0,0,0)';
      PINUSE='POWER';
      NO_LOAD_CHECK='Both';
      NO_IO_CHECK='Both';
      NO_ASSERT_CHECK='TRUE';
      NO_DIR_CHECK='TRUE';
      ALLOW_CONNECT='TRUE';
    'VDDCR_CPU1_BN46':
      PIN_NUMBER='(0,0,0,0,0,0,0,0,0,0,0,0,0,0,0,0,0,0,0,0,0,0,0,0,BN46,0,0,0,0,~
0,0,0,0,0,0,0,0,0,0,0)';
      PINUSE='POWER';
      NO_LOAD_CHECK='Both';
      NO_IO_CHECK='Both';
      NO_ASSERT_CHECK='TRUE';
      NO_DIR_CHECK='TRUE';
      ALLOW_CONNECT='TRUE';
    'VDDCR_SOC_B5':
      PIN_NUMBER='(0,0,0,0,0,0,0,0,0,0,0,0,0,0,0,0,0,0,0,0,0,0,0,0,0,B5,0,0,0,0,~
0,0,0,0,0,0,0,0,0,0)';
      PINUSE='POWER';
      NO_LOAD_CHECK='Both';
      NO_IO_CHECK='Both';
      NO_ASSERT_CHECK='TRUE';
      NO_DIR_CHECK='TRUE';
      ALLOW_CONNECT='TRUE';
    'VDDCR_SOC_C4':
      PIN_NUMBER='(0,0,0,0,0,0,0,0,0,0,0,0,0,0,0,0,0,0,0,0,0,0,0,0,0,C4,0,0,0,0,~
0,0,0,0,0,0,0,0,0,0)';
      PINUSE='POWER';
      NO_LOAD_CHECK='Both';
      NO_IO_CHECK='Both';
      NO_ASSERT_CHECK='TRUE';
      NO_DIR_CHECK='TRUE';
      ALLOW_CONNECT='TRUE';
    'VDDCR_SOC_E4':
      PIN_NUMBER='(0,0,0,0,0,0,0,0,0,0,0,0,0,0,0,0,0,0,0,0,0,0,0,0,0,E4,0,0,0,0,~
0,0,0,0,0,0,0,0,0,0)';
      PINUSE='POWER';
      NO_LOAD_CHECK='Both';
      NO_IO_CHECK='Both';
      NO_ASSERT_CHECK='TRUE';
      NO_DIR_CHECK='TRUE';
      ALLOW_CONNECT='TRUE';
    'VDDCR_SOC_E11':
      PIN_NUMBER='(0,0,0,0,0,0,0,0,0,0,0,0,0,0,0,0,0,0,0,0,0,0,0,0,0,E11,0,0,0,0~
,0,0,0,0,0,0,0,0,0,0)';
      PINUSE='POWER';
      NO_LOAD_CHECK='Both';
      NO_IO_CHECK='Both';
      NO_ASSERT_CHECK='TRUE';
      NO_DIR_CHECK='TRUE';
      ALLOW_CONNECT='TRUE';
    'VDDCR_SOC_H5':
      PIN_NUMBER='(0,0,0,0,0,0,0,0,0,0,0,0,0,0,0,0,0,0,0,0,0,0,0,0,0,H5,0,0,0,0,~
0,0,0,0,0,0,0,0,0,0)';
      PINUSE='POWER';
      NO_LOAD_CHECK='Both';
      NO_IO_CHECK='Both';
      NO_ASSERT_CHECK='TRUE';
      NO_DIR_CHECK='TRUE';
      ALLOW_CONNECT='TRUE';
    'VDDCR_SOC_H12':
      PIN_NUMBER='(0,0,0,0,0,0,0,0,0,0,0,0,0,0,0,0,0,0,0,0,0,0,0,0,0,H12,0,0,0,0~
,0,0,0,0,0,0,0,0,0,0)';
      PINUSE='POWER';
      NO_LOAD_CHECK='Both';
      NO_IO_CHECK='Both';
      NO_ASSERT_CHECK='TRUE';
      NO_DIR_CHECK='TRUE';
      ALLOW_CONNECT='TRUE';
    'VDDCR_SOC_H19':
      PIN_NUMBER='(0,0,0,0,0,0,0,0,0,0,0,0,0,0,0,0,0,0,0,0,0,0,0,0,0,H19,0,0,0,0~
,0,0,0,0,0,0,0,0,0,0)';
      PINUSE='POWER';
      NO_LOAD_CHECK='Both';
      NO_IO_CHECK='Both';
      NO_ASSERT_CHECK='TRUE';
      NO_DIR_CHECK='TRUE';
      ALLOW_CONNECT='TRUE';
    'VDDCR_SOC_K22':
      PIN_NUMBER='(0,0,0,0,0,0,0,0,0,0,0,0,0,0,0,0,0,0,0,0,0,0,0,0,0,K22,0,0,0,0~
,0,0,0,0,0,0,0,0,0,0)';
      PINUSE='POWER';
      NO_LOAD_CHECK='Both';
      NO_IO_CHECK='Both';
      NO_ASSERT_CHECK='TRUE';
      NO_DIR_CHECK='TRUE';
      ALLOW_CONNECT='TRUE';
    'VDDCR_SOC_L4':
      PIN_NUMBER='(0,0,0,0,0,0,0,0,0,0,0,0,0,0,0,0,0,0,0,0,0,0,0,0,0,L4,0,0,0,0,~
0,0,0,0,0,0,0,0,0,0)';
      PINUSE='POWER';
      NO_LOAD_CHECK='Both';
      NO_IO_CHECK='Both';
      NO_ASSERT_CHECK='TRUE';
      NO_DIR_CHECK='TRUE';
      ALLOW_CONNECT='TRUE';
    'VDDCR_SOC_L11':
      PIN_NUMBER='(0,0,0,0,0,0,0,0,0,0,0,0,0,0,0,0,0,0,0,0,0,0,0,0,0,L11,0,0,0,0~
,0,0,0,0,0,0,0,0,0,0)';
      PINUSE='POWER';
      NO_LOAD_CHECK='Both';
      NO_IO_CHECK='Both';
      NO_ASSERT_CHECK='TRUE';
      NO_DIR_CHECK='TRUE';
      ALLOW_CONNECT='TRUE';
    'VDDCR_SOC_L18':
      PIN_NUMBER='(0,0,0,0,0,0,0,0,0,0,0,0,0,0,0,0,0,0,0,0,0,0,0,0,0,L18,0,0,0,0~
,0,0,0,0,0,0,0,0,0,0)';
      PINUSE='POWER';
      NO_LOAD_CHECK='Both';
      NO_IO_CHECK='Both';
      NO_ASSERT_CHECK='TRUE';
      NO_DIR_CHECK='TRUE';
      ALLOW_CONNECT='TRUE';
    'VDDCR_SOC_P5':
      PIN_NUMBER='(0,0,0,0,0,0,0,0,0,0,0,0,0,0,0,0,0,0,0,0,0,0,0,0,0,P5,0,0,0,0,~
0,0,0,0,0,0,0,0,0,0)';
      PINUSE='POWER';
      NO_LOAD_CHECK='Both';
      NO_IO_CHECK='Both';
      NO_ASSERT_CHECK='TRUE';
      NO_DIR_CHECK='TRUE';
      ALLOW_CONNECT='TRUE';
    'VDDCR_SOC_P12':
      PIN_NUMBER='(0,0,0,0,0,0,0,0,0,0,0,0,0,0,0,0,0,0,0,0,0,0,0,0,0,P12,0,0,0,0~
,0,0,0,0,0,0,0,0,0,0)';
      PINUSE='POWER';
      NO_LOAD_CHECK='Both';
      NO_IO_CHECK='Both';
      NO_ASSERT_CHECK='TRUE';
      NO_DIR_CHECK='TRUE';
      ALLOW_CONNECT='TRUE';
    'VDDCR_SOC_P19':
      PIN_NUMBER='(0,0,0,0,0,0,0,0,0,0,0,0,0,0,0,0,0,0,0,0,0,0,0,0,0,P19,0,0,0,0~
,0,0,0,0,0,0,0,0,0,0)';
      PINUSE='POWER';
      NO_LOAD_CHECK='Both';
      NO_IO_CHECK='Both';
      NO_ASSERT_CHECK='TRUE';
      NO_DIR_CHECK='TRUE';
      ALLOW_CONNECT='TRUE';
    'VDDCR_SOC_P22':
      PIN_NUMBER='(0,0,0,0,0,0,0,0,0,0,0,0,0,0,0,0,0,0,0,0,0,0,0,0,0,P22,0,0,0,0~
,0,0,0,0,0,0,0,0,0,0)';
      PINUSE='POWER';
      NO_LOAD_CHECK='Both';
      NO_IO_CHECK='Both';
      NO_ASSERT_CHECK='TRUE';
      NO_DIR_CHECK='TRUE';
      ALLOW_CONNECT='TRUE';
    'VDDCR_SOC_U4':
      PIN_NUMBER='(0,0,0,0,0,0,0,0,0,0,0,0,0,0,0,0,0,0,0,0,0,0,0,0,0,U4,0,0,0,0,~
0,0,0,0,0,0,0,0,0,0)';
      PINUSE='POWER';
      NO_LOAD_CHECK='Both';
      NO_IO_CHECK='Both';
      NO_ASSERT_CHECK='TRUE';
      NO_DIR_CHECK='TRUE';
      ALLOW_CONNECT='TRUE';
    'VDDCR_SOC_U11':
      PIN_NUMBER='(0,0,0,0,0,0,0,0,0,0,0,0,0,0,0,0,0,0,0,0,0,0,0,0,0,U11,0,0,0,0~
,0,0,0,0,0,0,0,0,0,0)';
      PINUSE='POWER';
      NO_LOAD_CHECK='Both';
      NO_IO_CHECK='Both';
      NO_ASSERT_CHECK='TRUE';
      NO_DIR_CHECK='TRUE';
      ALLOW_CONNECT='TRUE';
    'VDDCR_SOC_U18':
      PIN_NUMBER='(0,0,0,0,0,0,0,0,0,0,0,0,0,0,0,0,0,0,0,0,0,0,0,0,0,U18,0,0,0,0~
,0,0,0,0,0,0,0,0,0,0)';
      PINUSE='POWER';
      NO_LOAD_CHECK='Both';
      NO_IO_CHECK='Both';
      NO_ASSERT_CHECK='TRUE';
      NO_DIR_CHECK='TRUE';
      ALLOW_CONNECT='TRUE';
    'VDDCR_SOC_V22':
      PIN_NUMBER='(0,0,0,0,0,0,0,0,0,0,0,0,0,0,0,0,0,0,0,0,0,0,0,0,0,V22,0,0,0,0~
,0,0,0,0,0,0,0,0,0,0)';
      PINUSE='POWER';
      NO_LOAD_CHECK='Both';
      NO_IO_CHECK='Both';
      NO_ASSERT_CHECK='TRUE';
      NO_DIR_CHECK='TRUE';
      ALLOW_CONNECT='TRUE';
    'VDDCR_SOC_Y5':
      PIN_NUMBER='(0,0,0,0,0,0,0,0,0,0,0,0,0,0,0,0,0,0,0,0,0,0,0,0,0,Y5,0,0,0,0,~
0,0,0,0,0,0,0,0,0,0)';
      PINUSE='POWER';
      NO_LOAD_CHECK='Both';
      NO_IO_CHECK='Both';
      NO_ASSERT_CHECK='TRUE';
      NO_DIR_CHECK='TRUE';
      ALLOW_CONNECT='TRUE';
    'VDDCR_SOC_Y12':
      PIN_NUMBER='(0,0,0,0,0,0,0,0,0,0,0,0,0,0,0,0,0,0,0,0,0,0,0,0,0,Y12,0,0,0,0~
,0,0,0,0,0,0,0,0,0,0)';
      PINUSE='POWER';
      NO_LOAD_CHECK='Both';
      NO_IO_CHECK='Both';
      NO_ASSERT_CHECK='TRUE';
      NO_DIR_CHECK='TRUE';
      ALLOW_CONNECT='TRUE';
    'VDDCR_SOC_Y19':
      PIN_NUMBER='(0,0,0,0,0,0,0,0,0,0,0,0,0,0,0,0,0,0,0,0,0,0,0,0,0,Y19,0,0,0,0~
,0,0,0,0,0,0,0,0,0,0)';
      PINUSE='POWER';
      NO_LOAD_CHECK='Both';
      NO_IO_CHECK='Both';
      NO_ASSERT_CHECK='TRUE';
      NO_DIR_CHECK='TRUE';
      ALLOW_CONNECT='TRUE';
    'VDDCR_SOC_AA22':
      PIN_NUMBER='(0,0,0,0,0,0,0,0,0,0,0,0,0,0,0,0,0,0,0,0,0,0,0,0,0,AA22,0,0,0,~
0,0,0,0,0,0,0,0,0,0,0)';
      PINUSE='POWER';
      NO_LOAD_CHECK='Both';
      NO_IO_CHECK='Both';
      NO_ASSERT_CHECK='TRUE';
      NO_DIR_CHECK='TRUE';
      ALLOW_CONNECT='TRUE';
    'VDDCR_SOC_AC4':
      PIN_NUMBER='(0,0,0,0,0,0,0,0,0,0,0,0,0,0,0,0,0,0,0,0,0,0,0,0,0,AC4,0,0,0,0~
,0,0,0,0,0,0,0,0,0,0)';
      PINUSE='POWER';
      NO_LOAD_CHECK='Both';
      NO_IO_CHECK='Both';
      NO_ASSERT_CHECK='TRUE';
      NO_DIR_CHECK='TRUE';
      ALLOW_CONNECT='TRUE';
    'VDDCR_SOC_AC11':
      PIN_NUMBER='(0,0,0,0,0,0,0,0,0,0,0,0,0,0,0,0,0,0,0,0,0,0,0,0,0,AC11,0,0,0,~
0,0,0,0,0,0,0,0,0,0,0)';
      PINUSE='POWER';
      NO_LOAD_CHECK='Both';
      NO_IO_CHECK='Both';
      NO_ASSERT_CHECK='TRUE';
      NO_DIR_CHECK='TRUE';
      ALLOW_CONNECT='TRUE';
    'VDDCR_SOC_AC18':
      PIN_NUMBER='(0,0,0,0,0,0,0,0,0,0,0,0,0,0,0,0,0,0,0,0,0,0,0,0,0,AC18,0,0,0,~
0,0,0,0,0,0,0,0,0,0,0)';
      PINUSE='POWER';
      NO_LOAD_CHECK='Both';
      NO_IO_CHECK='Both';
      NO_ASSERT_CHECK='TRUE';
      NO_DIR_CHECK='TRUE';
      ALLOW_CONNECT='TRUE';
    'VDDCR_SOC_AD22':
      PIN_NUMBER='(0,0,0,0,0,0,0,0,0,0,0,0,0,0,0,0,0,0,0,0,0,0,0,0,0,AD22,0,0,0,~
0,0,0,0,0,0,0,0,0,0,0)';
      PINUSE='POWER';
      NO_LOAD_CHECK='Both';
      NO_IO_CHECK='Both';
      NO_ASSERT_CHECK='TRUE';
      NO_DIR_CHECK='TRUE';
      ALLOW_CONNECT='TRUE';
    'VDDCR_SOC_AF5':
      PIN_NUMBER='(0,0,0,0,0,0,0,0,0,0,0,0,0,0,0,0,0,0,0,0,0,0,0,0,0,AF5,0,0,0,0~
,0,0,0,0,0,0,0,0,0,0)';
      PINUSE='POWER';
      NO_LOAD_CHECK='Both';
      NO_IO_CHECK='Both';
      NO_ASSERT_CHECK='TRUE';
      NO_DIR_CHECK='TRUE';
      ALLOW_CONNECT='TRUE';
    'VDDCR_SOC_AF12':
      PIN_NUMBER='(0,0,0,0,0,0,0,0,0,0,0,0,0,0,0,0,0,0,0,0,0,0,0,0,0,AF12,0,0,0,~
0,0,0,0,0,0,0,0,0,0,0)';
      PINUSE='POWER';
      NO_LOAD_CHECK='Both';
      NO_IO_CHECK='Both';
      NO_ASSERT_CHECK='TRUE';
      NO_DIR_CHECK='TRUE';
      ALLOW_CONNECT='TRUE';
    'VDDCR_SOC_AF19':
      PIN_NUMBER='(0,0,0,0,0,0,0,0,0,0,0,0,0,0,0,0,0,0,0,0,0,0,0,0,0,AF19,0,0,0,~
0,0,0,0,0,0,0,0,0,0,0)';
      PINUSE='POWER';
      NO_LOAD_CHECK='Both';
      NO_IO_CHECK='Both';
      NO_ASSERT_CHECK='TRUE';
      NO_DIR_CHECK='TRUE';
      ALLOW_CONNECT='TRUE';
    'VDDCR_SOC_AH22':
      PIN_NUMBER='(0,0,0,0,0,0,0,0,0,0,0,0,0,0,0,0,0,0,0,0,0,0,0,0,0,AH22,0,0,0,~
0,0,0,0,0,0,0,0,0,0,0)';
      PINUSE='POWER';
      NO_LOAD_CHECK='Both';
      NO_IO_CHECK='Both';
      NO_ASSERT_CHECK='TRUE';
      NO_DIR_CHECK='TRUE';
      ALLOW_CONNECT='TRUE';
    'VDDCR_SOC_AJ4':
      PIN_NUMBER='(0,0,0,0,0,0,0,0,0,0,0,0,0,0,0,0,0,0,0,0,0,0,0,0,0,AJ4,0,0,0,0~
,0,0,0,0,0,0,0,0,0,0)';
      PINUSE='POWER';
      NO_LOAD_CHECK='Both';
      NO_IO_CHECK='Both';
      NO_ASSERT_CHECK='TRUE';
      NO_DIR_CHECK='TRUE';
      ALLOW_CONNECT='TRUE';
    'VDDCR_SOC_AJ11':
      PIN_NUMBER='(0,0,0,0,0,0,0,0,0,0,0,0,0,0,0,0,0,0,0,0,0,0,0,0,0,AJ11,0,0,0,~
0,0,0,0,0,0,0,0,0,0,0)';
      PINUSE='POWER';
      NO_LOAD_CHECK='Both';
      NO_IO_CHECK='Both';
      NO_ASSERT_CHECK='TRUE';
      NO_DIR_CHECK='TRUE';
      ALLOW_CONNECT='TRUE';
    'VDDCR_SOC_AJ18':
      PIN_NUMBER='(0,0,0,0,0,0,0,0,0,0,0,0,0,0,0,0,0,0,0,0,0,0,0,0,0,AJ18,0,0,0,~
0,0,0,0,0,0,0,0,0,0,0)';
      PINUSE='POWER';
      NO_LOAD_CHECK='Both';
      NO_IO_CHECK='Both';
      NO_ASSERT_CHECK='TRUE';
      NO_DIR_CHECK='TRUE';
      ALLOW_CONNECT='TRUE';
    'VDDCR_SOC_AM5':
      PIN_NUMBER='(0,0,0,0,0,0,0,0,0,0,0,0,0,0,0,0,0,0,0,0,0,0,0,0,0,AM5,0,0,0,0~
,0,0,0,0,0,0,0,0,0,0)';
      PINUSE='POWER';
      NO_LOAD_CHECK='Both';
      NO_IO_CHECK='Both';
      NO_ASSERT_CHECK='TRUE';
      NO_DIR_CHECK='TRUE';
      ALLOW_CONNECT='TRUE';
    'VDDCR_SOC_AM12':
      PIN_NUMBER='(0,0,0,0,0,0,0,0,0,0,0,0,0,0,0,0,0,0,0,0,0,0,0,0,0,AM12,0,0,0,~
0,0,0,0,0,0,0,0,0,0,0)';
      PINUSE='POWER';
      NO_LOAD_CHECK='Both';
      NO_IO_CHECK='Both';
      NO_ASSERT_CHECK='TRUE';
      NO_DIR_CHECK='TRUE';
      ALLOW_CONNECT='TRUE';
    'VDDCR_SOC_AM19':
      PIN_NUMBER='(0,0,0,0,0,0,0,0,0,0,0,0,0,0,0,0,0,0,0,0,0,0,0,0,0,AM19,0,0,0,~
0,0,0,0,0,0,0,0,0,0,0)';
      PINUSE='POWER';
      NO_LOAD_CHECK='Both';
      NO_IO_CHECK='Both';
      NO_ASSERT_CHECK='TRUE';
      NO_DIR_CHECK='TRUE';
      ALLOW_CONNECT='TRUE';
    'VDDCR_SOC_AM22':
      PIN_NUMBER='(0,0,0,0,0,0,0,0,0,0,0,0,0,0,0,0,0,0,0,0,0,0,0,0,0,AM22,0,0,0,~
0,0,0,0,0,0,0,0,0,0,0)';
      PINUSE='POWER';
      NO_LOAD_CHECK='Both';
      NO_IO_CHECK='Both';
      NO_ASSERT_CHECK='TRUE';
      NO_DIR_CHECK='TRUE';
      ALLOW_CONNECT='TRUE';
    'VDDCR_SOC_AR4':
      PIN_NUMBER='(0,0,0,0,0,0,0,0,0,0,0,0,0,0,0,0,0,0,0,0,0,0,0,0,0,AR4,0,0,0,0~
,0,0,0,0,0,0,0,0,0,0)';
      PINUSE='POWER';
      NO_LOAD_CHECK='Both';
      NO_IO_CHECK='Both';
      NO_ASSERT_CHECK='TRUE';
      NO_DIR_CHECK='TRUE';
      ALLOW_CONNECT='TRUE';
    'VDDCR_SOC_AR11':
      PIN_NUMBER='(0,0,0,0,0,0,0,0,0,0,0,0,0,0,0,0,0,0,0,0,0,0,0,0,0,AR11,0,0,0,~
0,0,0,0,0,0,0,0,0,0,0)';
      PINUSE='POWER';
      NO_LOAD_CHECK='Both';
      NO_IO_CHECK='Both';
      NO_ASSERT_CHECK='TRUE';
      NO_DIR_CHECK='TRUE';
      ALLOW_CONNECT='TRUE';
    'VDDCR_SOC_AR18':
      PIN_NUMBER='(0,0,0,0,0,0,0,0,0,0,0,0,0,0,0,0,0,0,0,0,0,0,0,0,0,AR18,0,0,0,~
0,0,0,0,0,0,0,0,0,0,0)';
      PINUSE='POWER';
      NO_LOAD_CHECK='Both';
      NO_IO_CHECK='Both';
      NO_ASSERT_CHECK='TRUE';
      NO_DIR_CHECK='TRUE';
      ALLOW_CONNECT='TRUE';
    'VDDCR_SOC_AT22':
      PIN_NUMBER='(0,0,0,0,0,0,0,0,0,0,0,0,0,0,0,0,0,0,0,0,0,0,0,0,0,AT22,0,0,0,~
0,0,0,0,0,0,0,0,0,0,0)';
      PINUSE='POWER';
      NO_LOAD_CHECK='Both';
      NO_IO_CHECK='Both';
      NO_ASSERT_CHECK='TRUE';
      NO_DIR_CHECK='TRUE';
      ALLOW_CONNECT='TRUE';
    'VDDCR_SOC_AU23':
      PIN_NUMBER='(0,0,0,0,0,0,0,0,0,0,0,0,0,0,0,0,0,0,0,0,0,0,0,0,0,AU23,0,0,0,~
0,0,0,0,0,0,0,0,0,0,0)';
      PINUSE='POWER';
      NO_LOAD_CHECK='Both';
      NO_IO_CHECK='Both';
      NO_ASSERT_CHECK='TRUE';
      NO_DIR_CHECK='TRUE';
      ALLOW_CONNECT='TRUE';
    'VDDCR_SOC_AU27':
      PIN_NUMBER='(0,0,0,0,0,0,0,0,0,0,0,0,0,0,0,0,0,0,0,0,0,0,0,0,0,AU27,0,0,0,~
0,0,0,0,0,0,0,0,0,0,0)';
      PINUSE='POWER';
      NO_LOAD_CHECK='Both';
      NO_IO_CHECK='Both';
      NO_ASSERT_CHECK='TRUE';
      NO_DIR_CHECK='TRUE';
      ALLOW_CONNECT='TRUE';
    'VDDCR_SOC_AU31':
      PIN_NUMBER='(0,0,0,0,0,0,0,0,0,0,0,0,0,0,0,0,0,0,0,0,0,0,0,0,0,AU31,0,0,0,~
0,0,0,0,0,0,0,0,0,0,0)';
      PINUSE='POWER';
      NO_LOAD_CHECK='Both';
      NO_IO_CHECK='Both';
      NO_ASSERT_CHECK='TRUE';
      NO_DIR_CHECK='TRUE';
      ALLOW_CONNECT='TRUE';
    'VDDCR_SOC_AU35':
      PIN_NUMBER='(0,0,0,0,0,0,0,0,0,0,0,0,0,0,0,0,0,0,0,0,0,0,0,0,0,AU35,0,0,0,~
0,0,0,0,0,0,0,0,0,0,0)';
      PINUSE='POWER';
      NO_LOAD_CHECK='Both';
      NO_IO_CHECK='Both';
      NO_ASSERT_CHECK='TRUE';
      NO_DIR_CHECK='TRUE';
      ALLOW_CONNECT='TRUE';
    'VDDCR_SOC_AU40':
      PIN_NUMBER='(0,0,0,0,0,0,0,0,0,0,0,0,0,0,0,0,0,0,0,0,0,0,0,0,0,AU40,0,0,0,~
0,0,0,0,0,0,0,0,0,0,0)';
      PINUSE='POWER';
      NO_LOAD_CHECK='Both';
      NO_IO_CHECK='Both';
      NO_ASSERT_CHECK='TRUE';
      NO_DIR_CHECK='TRUE';
      ALLOW_CONNECT='TRUE';
    'VDDCR_SOC_AV5':
      PIN_NUMBER='(0,0,0,0,0,0,0,0,0,0,0,0,0,0,0,0,0,0,0,0,0,0,0,0,0,AV5,0,0,0,0~
,0,0,0,0,0,0,0,0,0,0)';
      PINUSE='POWER';
      NO_LOAD_CHECK='Both';
      NO_IO_CHECK='Both';
      NO_ASSERT_CHECK='TRUE';
      NO_DIR_CHECK='TRUE';
      ALLOW_CONNECT='TRUE';
    'VDDCR_SOC_AV12':
      PIN_NUMBER='(0,0,0,0,0,0,0,0,0,0,0,0,0,0,0,0,0,0,0,0,0,0,0,0,0,AV12,0,0,0,~
0,0,0,0,0,0,0,0,0,0,0)';
      PINUSE='POWER';
      NO_LOAD_CHECK='Both';
      NO_IO_CHECK='Both';
      NO_ASSERT_CHECK='TRUE';
      NO_DIR_CHECK='TRUE';
      ALLOW_CONNECT='TRUE';
    'VDDCR_SOC_AV19':
      PIN_NUMBER='(0,0,0,0,0,0,0,0,0,0,0,0,0,0,0,0,0,0,0,0,0,0,0,0,0,AV19,0,0,0,~
0,0,0,0,0,0,0,0,0,0,0)';
      PINUSE='POWER';
      NO_LOAD_CHECK='Both';
      NO_IO_CHECK='Both';
      NO_ASSERT_CHECK='TRUE';
      NO_DIR_CHECK='TRUE';
      ALLOW_CONNECT='TRUE';
    'VDDCR_SOC_AV22':
      PIN_NUMBER='(0,0,0,0,0,0,0,0,0,0,0,0,0,0,0,0,0,0,0,0,0,0,0,0,0,AV22,0,0,0,~
0,0,0,0,0,0,0,0,0,0,0)';
      PINUSE='POWER';
      NO_LOAD_CHECK='Both';
      NO_IO_CHECK='Both';
      NO_ASSERT_CHECK='TRUE';
      NO_DIR_CHECK='TRUE';
      ALLOW_CONNECT='TRUE';
    'VDDCR_SOC_AV24':
      PIN_NUMBER='(0,0,0,0,0,0,0,0,0,0,0,0,0,0,0,0,0,0,0,0,0,0,0,0,0,AV24,0,0,0,~
0,0,0,0,0,0,0,0,0,0,0)';
      PINUSE='POWER';
      NO_LOAD_CHECK='Both';
      NO_IO_CHECK='Both';
      NO_ASSERT_CHECK='TRUE';
      NO_DIR_CHECK='TRUE';
      ALLOW_CONNECT='TRUE';
    'VDDCR_SOC_AV26':
      PIN_NUMBER='(0,0,0,0,0,0,0,0,0,0,0,0,0,0,0,0,0,0,0,0,0,0,0,0,0,AV26,0,0,0,~
0,0,0,0,0,0,0,0,0,0,0)';
      PINUSE='POWER';
      NO_LOAD_CHECK='Both';
      NO_IO_CHECK='Both';
      NO_ASSERT_CHECK='TRUE';
      NO_DIR_CHECK='TRUE';
      ALLOW_CONNECT='TRUE';
    'VDDCR_SOC_AV28':
      PIN_NUMBER='(0,0,0,0,0,0,0,0,0,0,0,0,0,0,0,0,0,0,0,0,0,0,0,0,0,AV28,0,0,0,~
0,0,0,0,0,0,0,0,0,0,0)';
      PINUSE='POWER';
      NO_LOAD_CHECK='Both';
      NO_IO_CHECK='Both';
      NO_ASSERT_CHECK='TRUE';
      NO_DIR_CHECK='TRUE';
      ALLOW_CONNECT='TRUE';
    'VDDCR_SOC_AV30':
      PIN_NUMBER='(0,0,0,0,0,0,0,0,0,0,0,0,0,0,0,0,0,0,0,0,0,0,0,0,0,AV30,0,0,0,~
0,0,0,0,0,0,0,0,0,0,0)';
      PINUSE='POWER';
      NO_LOAD_CHECK='Both';
      NO_IO_CHECK='Both';
      NO_ASSERT_CHECK='TRUE';
      NO_DIR_CHECK='TRUE';
      ALLOW_CONNECT='TRUE';
    'VDDCR_SOC_AV32':
      PIN_NUMBER='(0,0,0,0,0,0,0,0,0,0,0,0,0,0,0,0,0,0,0,0,0,0,0,0,0,AV32,0,0,0,~
0,0,0,0,0,0,0,0,0,0,0)';
      PINUSE='POWER';
      NO_LOAD_CHECK='Both';
      NO_IO_CHECK='Both';
      NO_ASSERT_CHECK='TRUE';
      NO_DIR_CHECK='TRUE';
      ALLOW_CONNECT='TRUE';
    'VDDCR_SOC_AV34':
      PIN_NUMBER='(0,0,0,0,0,0,0,0,0,0,0,0,0,0,0,0,0,0,0,0,0,0,0,0,0,AV34,0,0,0,~
0,0,0,0,0,0,0,0,0,0,0)';
      PINUSE='POWER';
      NO_LOAD_CHECK='Both';
      NO_IO_CHECK='Both';
      NO_ASSERT_CHECK='TRUE';
      NO_DIR_CHECK='TRUE';
      ALLOW_CONNECT='TRUE';
    'VDDCR_SOC_AV36':
      PIN_NUMBER='(0,0,0,0,0,0,0,0,0,0,0,0,0,0,0,0,0,0,0,0,0,0,0,0,0,AV36,0,0,0,~
0,0,0,0,0,0,0,0,0,0,0)';
      PINUSE='POWER';
      NO_LOAD_CHECK='Both';
      NO_IO_CHECK='Both';
      NO_ASSERT_CHECK='TRUE';
      NO_DIR_CHECK='TRUE';
      ALLOW_CONNECT='TRUE';
    'VDDCR_SOC_AV39':
      PIN_NUMBER='(0,0,0,0,0,0,0,0,0,0,0,0,0,0,0,0,0,0,0,0,0,0,0,0,0,AV39,0,0,0,~
0,0,0,0,0,0,0,0,0,0,0)';
      PINUSE='POWER';
      NO_LOAD_CHECK='Both';
      NO_IO_CHECK='Both';
      NO_ASSERT_CHECK='TRUE';
      NO_DIR_CHECK='TRUE';
      ALLOW_CONNECT='TRUE';
    'VDDCR_SOC_AV41':
      PIN_NUMBER='(0,0,0,0,0,0,0,0,0,0,0,0,0,0,0,0,0,0,0,0,0,0,0,0,0,AV41,0,0,0,~
0,0,0,0,0,0,0,0,0,0,0)';
      PINUSE='POWER';
      NO_LOAD_CHECK='Both';
      NO_IO_CHECK='Both';
      NO_ASSERT_CHECK='TRUE';
      NO_DIR_CHECK='TRUE';
      ALLOW_CONNECT='TRUE';
    'VDDCR_SOC_AV43':
      PIN_NUMBER='(0,0,0,0,0,0,0,0,0,0,0,0,0,0,0,0,0,0,0,0,0,0,0,0,0,AV43,0,0,0,~
0,0,0,0,0,0,0,0,0,0,0)';
      PINUSE='POWER';
      NO_LOAD_CHECK='Both';
      NO_IO_CHECK='Both';
      NO_ASSERT_CHECK='TRUE';
      NO_DIR_CHECK='TRUE';
      ALLOW_CONNECT='TRUE';
    'VDDCR_SOC_AV45':
      PIN_NUMBER='(0,0,0,0,0,0,0,0,0,0,0,0,0,0,0,0,0,0,0,0,0,0,0,0,0,AV45,0,0,0,~
0,0,0,0,0,0,0,0,0,0,0)';
      PINUSE='POWER';
      NO_LOAD_CHECK='Both';
      NO_IO_CHECK='Both';
      NO_ASSERT_CHECK='TRUE';
      NO_DIR_CHECK='TRUE';
      ALLOW_CONNECT='TRUE';
    'VDDCR_SOC_AV47':
      PIN_NUMBER='(0,0,0,0,0,0,0,0,0,0,0,0,0,0,0,0,0,0,0,0,0,0,0,0,0,AV47,0,0,0,~
0,0,0,0,0,0,0,0,0,0,0)';
      PINUSE='POWER';
      NO_LOAD_CHECK='Both';
      NO_IO_CHECK='Both';
      NO_ASSERT_CHECK='TRUE';
      NO_DIR_CHECK='TRUE';
      ALLOW_CONNECT='TRUE';
    'VDDCR_SOC_AW23':
      PIN_NUMBER='(0,0,0,0,0,0,0,0,0,0,0,0,0,0,0,0,0,0,0,0,0,0,0,0,0,AW23,0,0,0,~
0,0,0,0,0,0,0,0,0,0,0)';
      PINUSE='POWER';
      NO_LOAD_CHECK='Both';
      NO_IO_CHECK='Both';
      NO_ASSERT_CHECK='TRUE';
      NO_DIR_CHECK='TRUE';
      ALLOW_CONNECT='TRUE';
    'VDDCR_SOC_AW25':
      PIN_NUMBER='(0,0,0,0,0,0,0,0,0,0,0,0,0,0,0,0,0,0,0,0,0,0,0,0,0,AW25,0,0,0,~
0,0,0,0,0,0,0,0,0,0,0)';
      PINUSE='POWER';
      NO_LOAD_CHECK='Both';
      NO_IO_CHECK='Both';
      NO_ASSERT_CHECK='TRUE';
      NO_DIR_CHECK='TRUE';
      ALLOW_CONNECT='TRUE';
    'VDDCR_SOC_AW27':
      PIN_NUMBER='(0,0,0,0,0,0,0,0,0,0,0,0,0,0,0,0,0,0,0,0,0,0,0,0,0,AW27,0,0,0,~
0,0,0,0,0,0,0,0,0,0,0)';
      PINUSE='POWER';
      NO_LOAD_CHECK='Both';
      NO_IO_CHECK='Both';
      NO_ASSERT_CHECK='TRUE';
      NO_DIR_CHECK='TRUE';
      ALLOW_CONNECT='TRUE';
    'VDDCR_SOC_AW48':
      PIN_NUMBER='(0,0,0,0,0,0,0,0,0,0,0,0,0,0,0,0,0,0,0,0,0,0,0,0,0,AW48,0,0,0,~
0,0,0,0,0,0,0,0,0,0,0)';
      PINUSE='POWER';
      NO_LOAD_CHECK='Both';
      NO_IO_CHECK='Both';
      NO_ASSERT_CHECK='TRUE';
      NO_DIR_CHECK='TRUE';
      ALLOW_CONNECT='TRUE';
    'VDDCR_SOC_AY22':
      PIN_NUMBER='(0,0,0,0,0,0,0,0,0,0,0,0,0,0,0,0,0,0,0,0,0,0,0,0,0,AY22,0,0,0,~
0,0,0,0,0,0,0,0,0,0,0)';
      PINUSE='POWER';
      NO_LOAD_CHECK='Both';
      NO_IO_CHECK='Both';
      NO_ASSERT_CHECK='TRUE';
      NO_DIR_CHECK='TRUE';
      ALLOW_CONNECT='TRUE';
    'VDDCR_SOC_AY24':
      PIN_NUMBER='(0,0,0,0,0,0,0,0,0,0,0,0,0,0,0,0,0,0,0,0,0,0,0,0,0,AY24,0,0,0,~
0,0,0,0,0,0,0,0,0,0,0)';
      PINUSE='POWER';
      NO_LOAD_CHECK='Both';
      NO_IO_CHECK='Both';
      NO_ASSERT_CHECK='TRUE';
      NO_DIR_CHECK='TRUE';
      ALLOW_CONNECT='TRUE';
    'VDDCR_SOC_AY26':
      PIN_NUMBER='(0,0,0,0,0,0,0,0,0,0,0,0,0,0,0,0,0,0,0,0,0,0,0,0,0,AY26,0,0,0,~
0,0,0,0,0,0,0,0,0,0,0)';
      PINUSE='POWER';
      NO_LOAD_CHECK='Both';
      NO_IO_CHECK='Both';
      NO_ASSERT_CHECK='TRUE';
      NO_DIR_CHECK='TRUE';
      ALLOW_CONNECT='TRUE';
    'VDDCR_SOC_AY28':
      PIN_NUMBER='(0,0,0,0,0,0,0,0,0,0,0,0,0,0,0,0,0,0,0,0,0,0,0,0,0,AY28,0,0,0,~
0,0,0,0,0,0,0,0,0,0,0)';
      PINUSE='POWER';
      NO_LOAD_CHECK='Both';
      NO_IO_CHECK='Both';
      NO_ASSERT_CHECK='TRUE';
      NO_DIR_CHECK='TRUE';
      ALLOW_CONNECT='TRUE';
    'VDDCR_SOC_AY49':
      PIN_NUMBER='(0,0,0,0,0,0,0,0,0,0,0,0,0,0,0,0,0,0,0,0,0,0,0,0,0,AY49,0,0,0,~
0,0,0,0,0,0,0,0,0,0,0)';
      PINUSE='POWER';
      NO_LOAD_CHECK='Both';
      NO_IO_CHECK='Both';
      NO_ASSERT_CHECK='TRUE';
      NO_DIR_CHECK='TRUE';
      ALLOW_CONNECT='TRUE';
    'VDDCR_SOC_BA4':
      PIN_NUMBER='(0,0,0,0,0,0,0,0,0,0,0,0,0,0,0,0,0,0,0,0,0,0,0,0,0,BA4,0,0,0,0~
,0,0,0,0,0,0,0,0,0,0)';
      PINUSE='POWER';
      NO_LOAD_CHECK='Both';
      NO_IO_CHECK='Both';
      NO_ASSERT_CHECK='TRUE';
      NO_DIR_CHECK='TRUE';
      ALLOW_CONNECT='TRUE';
    'VDDCR_SOC_BA11':
      PIN_NUMBER='(0,0,0,0,0,0,0,0,0,0,0,0,0,0,0,0,0,0,0,0,0,0,0,0,0,BA11,0,0,0,~
0,0,0,0,0,0,0,0,0,0,0)';
      PINUSE='POWER';
      NO_LOAD_CHECK='Both';
      NO_IO_CHECK='Both';
      NO_ASSERT_CHECK='TRUE';
      NO_DIR_CHECK='TRUE';
      ALLOW_CONNECT='TRUE';
    'VDDCR_SOC_BA18':
      PIN_NUMBER='(0,0,0,0,0,0,0,0,0,0,0,0,0,0,0,0,0,0,0,0,0,0,0,0,0,BA18,0,0,0,~
0,0,0,0,0,0,0,0,0,0,0)';
      PINUSE='POWER';
      NO_LOAD_CHECK='Both';
      NO_IO_CHECK='Both';
      NO_ASSERT_CHECK='TRUE';
      NO_DIR_CHECK='TRUE';
      ALLOW_CONNECT='TRUE';
    'VDDCR_SOC_BA23':
      PIN_NUMBER='(0,0,0,0,0,0,0,0,0,0,0,0,0,0,0,0,0,0,0,0,0,0,0,0,0,BA23,0,0,0,~
0,0,0,0,0,0,0,0,0,0,0)';
      PINUSE='POWER';
      NO_LOAD_CHECK='Both';
      NO_IO_CHECK='Both';
      NO_ASSERT_CHECK='TRUE';
      NO_DIR_CHECK='TRUE';
      ALLOW_CONNECT='TRUE';
    'VDDCR_SOC_BA25':
      PIN_NUMBER='(0,0,0,0,0,0,0,0,0,0,0,0,0,0,0,0,0,0,0,0,0,0,0,0,0,BA25,0,0,0,~
0,0,0,0,0,0,0,0,0,0,0)';
      PINUSE='POWER';
      NO_LOAD_CHECK='Both';
      NO_IO_CHECK='Both';
      NO_ASSERT_CHECK='TRUE';
      NO_DIR_CHECK='TRUE';
      ALLOW_CONNECT='TRUE';
    'VDDCR_SOC_BA27':
      PIN_NUMBER='(0,0,0,0,0,0,0,0,0,0,0,0,0,0,0,0,0,0,0,0,0,0,0,0,0,BA27,0,0,0,~
0,0,0,0,0,0,0,0,0,0,0)';
      PINUSE='POWER';
      NO_LOAD_CHECK='Both';
      NO_IO_CHECK='Both';
      NO_ASSERT_CHECK='TRUE';
      NO_DIR_CHECK='TRUE';
      ALLOW_CONNECT='TRUE';
    'VDDCR_SOC_BA48':
      PIN_NUMBER='(0,0,0,0,0,0,0,0,0,0,0,0,0,0,0,0,0,0,0,0,0,0,0,0,0,BA48,0,0,0,~
0,0,0,0,0,0,0,0,0,0,0)';
      PINUSE='POWER';
      NO_LOAD_CHECK='Both';
      NO_IO_CHECK='Both';
      NO_ASSERT_CHECK='TRUE';
      NO_DIR_CHECK='TRUE';
      ALLOW_CONNECT='TRUE';
    'VDDCR_SOC_BB22':
      PIN_NUMBER='(0,0,0,0,0,0,0,0,0,0,0,0,0,0,0,0,0,0,0,0,0,0,0,0,0,BB22,0,0,0,~
0,0,0,0,0,0,0,0,0,0,0)';
      PINUSE='POWER';
      NO_LOAD_CHECK='Both';
      NO_IO_CHECK='Both';
      NO_ASSERT_CHECK='TRUE';
      NO_DIR_CHECK='TRUE';
      ALLOW_CONNECT='TRUE';
    'VDDCR_SOC_BB24':
      PIN_NUMBER='(0,0,0,0,0,0,0,0,0,0,0,0,0,0,0,0,0,0,0,0,0,0,0,0,0,BB24,0,0,0,~
0,0,0,0,0,0,0,0,0,0,0)';
      PINUSE='POWER';
      NO_LOAD_CHECK='Both';
      NO_IO_CHECK='Both';
      NO_ASSERT_CHECK='TRUE';
      NO_DIR_CHECK='TRUE';
      ALLOW_CONNECT='TRUE';
    'VDDCR_SOC_BB26':
      PIN_NUMBER='(0,0,0,0,0,0,0,0,0,0,0,0,0,0,0,0,0,0,0,0,0,0,0,0,0,BB26,0,0,0,~
0,0,0,0,0,0,0,0,0,0,0)';
      PINUSE='POWER';
      NO_LOAD_CHECK='Both';
      NO_IO_CHECK='Both';
      NO_ASSERT_CHECK='TRUE';
      NO_DIR_CHECK='TRUE';
      ALLOW_CONNECT='TRUE';
    'VDDCR_SOC_BB28':
      PIN_NUMBER='(0,0,0,0,0,0,0,0,0,0,0,0,0,0,0,0,0,0,0,0,0,0,0,0,0,BB28,0,0,0,~
0,0,0,0,0,0,0,0,0,0,0)';
      PINUSE='POWER';
      NO_LOAD_CHECK='Both';
      NO_IO_CHECK='Both';
      NO_ASSERT_CHECK='TRUE';
      NO_DIR_CHECK='TRUE';
      ALLOW_CONNECT='TRUE';
    'VDDCR_SOC_BB49':
      PIN_NUMBER='(0,0,0,0,0,0,0,0,0,0,0,0,0,0,0,0,0,0,0,0,0,0,0,0,0,BB49,0,0,0,~
0,0,0,0,0,0,0,0,0,0,0)';
      PINUSE='POWER';
      NO_LOAD_CHECK='Both';
      NO_IO_CHECK='Both';
      NO_ASSERT_CHECK='TRUE';
      NO_DIR_CHECK='TRUE';
      ALLOW_CONNECT='TRUE';
    'VDDCR_SOC_BC23':
      PIN_NUMBER='(0,0,0,0,0,0,0,0,0,0,0,0,0,0,0,0,0,0,0,0,0,0,0,0,0,BC23,0,0,0,~
0,0,0,0,0,0,0,0,0,0,0)';
      PINUSE='POWER';
      NO_LOAD_CHECK='Both';
      NO_IO_CHECK='Both';
      NO_ASSERT_CHECK='TRUE';
      NO_DIR_CHECK='TRUE';
      ALLOW_CONNECT='TRUE';
    'VDDCR_SOC_BC25':
      PIN_NUMBER='(0,0,0,0,0,0,0,0,0,0,0,0,0,0,0,0,0,0,0,0,0,0,0,0,0,BC25,0,0,0,~
0,0,0,0,0,0,0,0,0,0,0)';
      PINUSE='POWER';
      NO_LOAD_CHECK='Both';
      NO_IO_CHECK='Both';
      NO_ASSERT_CHECK='TRUE';
      NO_DIR_CHECK='TRUE';
      ALLOW_CONNECT='TRUE';
    'VDDCR_SOC_BC27':
      PIN_NUMBER='(0,0,0,0,0,0,0,0,0,0,0,0,0,0,0,0,0,0,0,0,0,0,0,0,0,BC27,0,0,0,~
0,0,0,0,0,0,0,0,0,0,0)';
      PINUSE='POWER';
      NO_LOAD_CHECK='Both';
      NO_IO_CHECK='Both';
      NO_ASSERT_CHECK='TRUE';
      NO_DIR_CHECK='TRUE';
      ALLOW_CONNECT='TRUE';
    'VDDCR_SOC_BC48':
      PIN_NUMBER='(0,0,0,0,0,0,0,0,0,0,0,0,0,0,0,0,0,0,0,0,0,0,0,0,0,BC48,0,0,0,~
0,0,0,0,0,0,0,0,0,0,0)';
      PINUSE='POWER';
      NO_LOAD_CHECK='Both';
      NO_IO_CHECK='Both';
      NO_ASSERT_CHECK='TRUE';
      NO_DIR_CHECK='TRUE';
      ALLOW_CONNECT='TRUE';
    'VDDCR_SOC_BD5':
      PIN_NUMBER='(0,0,0,0,0,0,0,0,0,0,0,0,0,0,0,0,0,0,0,0,0,0,0,0,0,BD5,0,0,0,0~
,0,0,0,0,0,0,0,0,0,0)';
      PINUSE='POWER';
      NO_LOAD_CHECK='Both';
      NO_IO_CHECK='Both';
      NO_ASSERT_CHECK='TRUE';
      NO_DIR_CHECK='TRUE';
      ALLOW_CONNECT='TRUE';
    'VDDCR_SOC_BD12':
      PIN_NUMBER='(0,0,0,0,0,0,0,0,0,0,0,0,0,0,0,0,0,0,0,0,0,0,0,0,0,BD12,0,0,0,~
0,0,0,0,0,0,0,0,0,0,0)';
      PINUSE='POWER';
      NO_LOAD_CHECK='Both';
      NO_IO_CHECK='Both';
      NO_ASSERT_CHECK='TRUE';
      NO_DIR_CHECK='TRUE';
      ALLOW_CONNECT='TRUE';
    'VDDCR_SOC_BD19':
      PIN_NUMBER='(0,0,0,0,0,0,0,0,0,0,0,0,0,0,0,0,0,0,0,0,0,0,0,0,0,BD19,0,0,0,~
0,0,0,0,0,0,0,0,0,0,0)';
      PINUSE='POWER';
      NO_LOAD_CHECK='Both';
      NO_IO_CHECK='Both';
      NO_ASSERT_CHECK='TRUE';
      NO_DIR_CHECK='TRUE';
      ALLOW_CONNECT='TRUE';
    'VDDCR_SOC_BD22':
      PIN_NUMBER='(0,0,0,0,0,0,0,0,0,0,0,0,0,0,0,0,0,0,0,0,0,0,0,0,0,BD22,0,0,0,~
0,0,0,0,0,0,0,0,0,0,0)';
      PINUSE='POWER';
      NO_LOAD_CHECK='Both';
      NO_IO_CHECK='Both';
      NO_ASSERT_CHECK='TRUE';
      NO_DIR_CHECK='TRUE';
      ALLOW_CONNECT='TRUE';
    'VDDCR_SOC_BD24':
      PIN_NUMBER='(0,0,0,0,0,0,0,0,0,0,0,0,0,0,0,0,0,0,0,0,0,0,0,0,0,BD24,0,0,0,~
0,0,0,0,0,0,0,0,0,0,0)';
      PINUSE='POWER';
      NO_LOAD_CHECK='Both';
      NO_IO_CHECK='Both';
      NO_ASSERT_CHECK='TRUE';
      NO_DIR_CHECK='TRUE';
      ALLOW_CONNECT='TRUE';
    'VDDCR_SOC_BD26':
      PIN_NUMBER='(0,0,0,0,0,0,0,0,0,0,0,0,0,0,0,0,0,0,0,0,0,0,0,0,0,BD26,0,0,0,~
0,0,0,0,0,0,0,0,0,0,0)';
      PINUSE='POWER';
      NO_LOAD_CHECK='Both';
      NO_IO_CHECK='Both';
      NO_ASSERT_CHECK='TRUE';
      NO_DIR_CHECK='TRUE';
      ALLOW_CONNECT='TRUE';
    'VDDCR_SOC_BD28':
      PIN_NUMBER='(0,0,0,0,0,0,0,0,0,0,0,0,0,0,0,0,0,0,0,0,0,0,0,0,0,BD28,0,0,0,~
0,0,0,0,0,0,0,0,0,0,0)';
      PINUSE='POWER';
      NO_LOAD_CHECK='Both';
      NO_IO_CHECK='Both';
      NO_ASSERT_CHECK='TRUE';
      NO_DIR_CHECK='TRUE';
      ALLOW_CONNECT='TRUE';
    'VDDCR_SOC_BD48':
      PIN_NUMBER='(0,0,0,0,0,0,0,0,0,0,0,0,0,0,0,0,0,0,0,0,0,0,0,0,0,BD48,0,0,0,~
0,0,0,0,0,0,0,0,0,0,0)';
      PINUSE='POWER';
      NO_LOAD_CHECK='Both';
      NO_IO_CHECK='Both';
      NO_ASSERT_CHECK='TRUE';
      NO_DIR_CHECK='TRUE';
      ALLOW_CONNECT='TRUE';
    'VDDCR_SOC_BF23':
      PIN_NUMBER='(0,0,0,0,0,0,0,0,0,0,0,0,0,0,0,0,0,0,0,0,0,0,0,0,0,BF23,0,0,0,~
0,0,0,0,0,0,0,0,0,0,0)';
      PINUSE='POWER';
      NO_LOAD_CHECK='Both';
      NO_IO_CHECK='Both';
      NO_ASSERT_CHECK='TRUE';
      NO_DIR_CHECK='TRUE';
      ALLOW_CONNECT='TRUE';
    'VDDCR_SOC_BF25':
      PIN_NUMBER='(0,0,0,0,0,0,0,0,0,0,0,0,0,0,0,0,0,0,0,0,0,0,0,0,0,BF25,0,0,0,~
0,0,0,0,0,0,0,0,0,0,0)';
      PINUSE='POWER';
      NO_LOAD_CHECK='Both';
      NO_IO_CHECK='Both';
      NO_ASSERT_CHECK='TRUE';
      NO_DIR_CHECK='TRUE';
      ALLOW_CONNECT='TRUE';
    'VDDCR_SOC_BF27':
      PIN_NUMBER='(0,0,0,0,0,0,0,0,0,0,0,0,0,0,0,0,0,0,0,0,0,0,0,0,0,BF27,0,0,0,~
0,0,0,0,0,0,0,0,0,0,0)';
      PINUSE='POWER';
      NO_LOAD_CHECK='Both';
      NO_IO_CHECK='Both';
      NO_ASSERT_CHECK='TRUE';
      NO_DIR_CHECK='TRUE';
      ALLOW_CONNECT='TRUE';
    'VDDCR_SOC_BF48':
      PIN_NUMBER='(0,0,0,0,0,0,0,0,0,0,0,0,0,0,0,0,0,0,0,0,0,0,0,0,0,BF48,0,0,0,~
0,0,0,0,0,0,0,0,0,0,0)';
      PINUSE='POWER';
      NO_LOAD_CHECK='Both';
      NO_IO_CHECK='Both';
      NO_ASSERT_CHECK='TRUE';
      NO_DIR_CHECK='TRUE';
      ALLOW_CONNECT='TRUE';
    'VDDCR_SOC_BM5':
      PIN_NUMBER='(0,0,0,0,0,0,0,0,0,0,0,0,0,0,0,0,0,0,0,0,0,0,0,0,0,BM5,0,0,0,0~
,0,0,0,0,0,0,0,0,0,0)';
      PINUSE='POWER';
      NO_LOAD_CHECK='Both';
      NO_IO_CHECK='Both';
      NO_ASSERT_CHECK='TRUE';
      NO_DIR_CHECK='TRUE';
      ALLOW_CONNECT='TRUE';
    'VDDCR_SOC_BJ48':
      PIN_NUMBER='(0,0,0,0,0,0,0,0,0,0,0,0,0,0,0,0,0,0,0,0,0,0,0,0,0,BJ48,0,0,0,~
0,0,0,0,0,0,0,0,0,0,0)';
      PINUSE='POWER';
      NO_LOAD_CHECK='Both';
      NO_IO_CHECK='Both';
      NO_ASSERT_CHECK='TRUE';
      NO_DIR_CHECK='TRUE';
      ALLOW_CONNECT='TRUE';
    'VDDCR_SOC_BJ11':
      PIN_NUMBER='(0,0,0,0,0,0,0,0,0,0,0,0,0,0,0,0,0,0,0,0,0,0,0,0,0,BJ11,0,0,0,~
0,0,0,0,0,0,0,0,0,0,0)';
      PINUSE='POWER';
      NO_LOAD_CHECK='Both';
      NO_IO_CHECK='Both';
      NO_ASSERT_CHECK='TRUE';
      NO_DIR_CHECK='TRUE';
      ALLOW_CONNECT='TRUE';
    'VDDCR_SOC_BJ4':
      PIN_NUMBER='(0,0,0,0,0,0,0,0,0,0,0,0,0,0,0,0,0,0,0,0,0,0,0,0,0,BJ4,0,0,0,0~
,0,0,0,0,0,0,0,0,0,0)';
      PINUSE='POWER';
      NO_LOAD_CHECK='Both';
      NO_IO_CHECK='Both';
      NO_ASSERT_CHECK='TRUE';
      NO_DIR_CHECK='TRUE';
      ALLOW_CONNECT='TRUE';
    'VDDCR_SOC_BH48':
      PIN_NUMBER='(0,0,0,0,0,0,0,0,0,0,0,0,0,0,0,0,0,0,0,0,0,0,0,0,0,BH48,0,0,0,~
0,0,0,0,0,0,0,0,0,0,0)';
      PINUSE='POWER';
      NO_LOAD_CHECK='Both';
      NO_IO_CHECK='Both';
      NO_ASSERT_CHECK='TRUE';
      NO_DIR_CHECK='TRUE';
      ALLOW_CONNECT='TRUE';
    'VDDCR_SOC_BH25':
      PIN_NUMBER='(0,0,0,0,0,0,0,0,0,0,0,0,0,0,0,0,0,0,0,0,0,0,0,0,0,BH25,0,0,0,~
0,0,0,0,0,0,0,0,0,0,0)';
      PINUSE='POWER';
      NO_LOAD_CHECK='Both';
      NO_IO_CHECK='Both';
      NO_ASSERT_CHECK='TRUE';
      NO_DIR_CHECK='TRUE';
      ALLOW_CONNECT='TRUE';
    'VDDCR_SOC_BH23':
      PIN_NUMBER='(0,0,0,0,0,0,0,0,0,0,0,0,0,0,0,0,0,0,0,0,0,0,0,0,0,BH23,0,0,0,~
0,0,0,0,0,0,0,0,0,0,0)';
      PINUSE='POWER';
      NO_LOAD_CHECK='Both';
      NO_IO_CHECK='Both';
      NO_ASSERT_CHECK='TRUE';
      NO_DIR_CHECK='TRUE';
      ALLOW_CONNECT='TRUE';
    'VDDCR_SOC_BG48':
      PIN_NUMBER='(0,0,0,0,0,0,0,0,0,0,0,0,0,0,0,0,0,0,0,0,0,0,0,0,0,BG48,0,0,0,~
0,0,0,0,0,0,0,0,0,0,0)';
      PINUSE='POWER';
      NO_LOAD_CHECK='Both';
      NO_IO_CHECK='Both';
      NO_ASSERT_CHECK='TRUE';
      NO_DIR_CHECK='TRUE';
      ALLOW_CONNECT='TRUE';
    'VDDCR_SOC_BG28':
      PIN_NUMBER='(0,0,0,0,0,0,0,0,0,0,0,0,0,0,0,0,0,0,0,0,0,0,0,0,0,BG28,0,0,0,~
0,0,0,0,0,0,0,0,0,0,0)';
      PINUSE='POWER';
      NO_LOAD_CHECK='Both';
      NO_IO_CHECK='Both';
      NO_ASSERT_CHECK='TRUE';
      NO_DIR_CHECK='TRUE';
      ALLOW_CONNECT='TRUE';
    'VDDCR_SOC_BG26':
      PIN_NUMBER='(0,0,0,0,0,0,0,0,0,0,0,0,0,0,0,0,0,0,0,0,0,0,0,0,0,BG26,0,0,0,~
0,0,0,0,0,0,0,0,0,0,0)';
      PINUSE='POWER';
      NO_LOAD_CHECK='Both';
      NO_IO_CHECK='Both';
      NO_ASSERT_CHECK='TRUE';
      NO_DIR_CHECK='TRUE';
      ALLOW_CONNECT='TRUE';
    'VDDCR_SOC_BG24':
      PIN_NUMBER='(0,0,0,0,0,0,0,0,0,0,0,0,0,0,0,0,0,0,0,0,0,0,0,0,0,BG24,0,0,0,~
0,0,0,0,0,0,0,0,0,0,0)';
      PINUSE='POWER';
      NO_LOAD_CHECK='Both';
      NO_IO_CHECK='Both';
      NO_ASSERT_CHECK='TRUE';
      NO_DIR_CHECK='TRUE';
      ALLOW_CONNECT='TRUE';
    'VDDCR_SOC_BG22':
      PIN_NUMBER='(0,0,0,0,0,0,0,0,0,0,0,0,0,0,0,0,0,0,0,0,0,0,0,0,0,BG22,0,0,0,~
0,0,0,0,0,0,0,0,0,0,0)';
      PINUSE='POWER';
      NO_LOAD_CHECK='Both';
      NO_IO_CHECK='Both';
      NO_ASSERT_CHECK='TRUE';
      NO_DIR_CHECK='TRUE';
      ALLOW_CONNECT='TRUE';
    'VDDIO_H57':
      PIN_NUMBER='(0,0,0,0,0,0,0,0,0,0,0,0,0,0,0,0,0,0,0,0,0,0,0,0,0,0,H57,0,0,0~
,0,0,0,0,0,0,0,0,0,0)';
      PINUSE='POWER';
      NO_LOAD_CHECK='Both';
      NO_IO_CHECK='Both';
      NO_ASSERT_CHECK='TRUE';
      NO_DIR_CHECK='TRUE';
      ALLOW_CONNECT='TRUE';
    'VDDIO_H64':
      PIN_NUMBER='(0,0,0,0,0,0,0,0,0,0,0,0,0,0,0,0,0,0,0,0,0,0,0,0,0,0,H64,0,0,0~
,0,0,0,0,0,0,0,0,0,0)';
      PINUSE='POWER';
      NO_LOAD_CHECK='Both';
      NO_IO_CHECK='Both';
      NO_ASSERT_CHECK='TRUE';
      NO_DIR_CHECK='TRUE';
      ALLOW_CONNECT='TRUE';
    'VDDIO_H71':
      PIN_NUMBER='(0,0,0,0,0,0,0,0,0,0,0,0,0,0,0,0,0,0,0,0,0,0,0,0,0,0,H71,0,0,0~
,0,0,0,0,0,0,0,0,0,0)';
      PINUSE='POWER';
      NO_LOAD_CHECK='Both';
      NO_IO_CHECK='Both';
      NO_ASSERT_CHECK='TRUE';
      NO_DIR_CHECK='TRUE';
      ALLOW_CONNECT='TRUE';
    'VDDIO_K54':
      PIN_NUMBER='(0,0,0,0,0,0,0,0,0,0,0,0,0,0,0,0,0,0,0,0,0,0,0,0,0,0,K54,0,0,0~
,0,0,0,0,0,0,0,0,0,0)';
      PINUSE='POWER';
      NO_LOAD_CHECK='Both';
      NO_IO_CHECK='Both';
      NO_ASSERT_CHECK='TRUE';
      NO_DIR_CHECK='TRUE';
      ALLOW_CONNECT='TRUE';
    'VDDIO_L58':
      PIN_NUMBER='(0,0,0,0,0,0,0,0,0,0,0,0,0,0,0,0,0,0,0,0,0,0,0,0,0,0,L58,0,0,0~
,0,0,0,0,0,0,0,0,0,0)';
      PINUSE='POWER';
      NO_LOAD_CHECK='Both';
      NO_IO_CHECK='Both';
      NO_ASSERT_CHECK='TRUE';
      NO_DIR_CHECK='TRUE';
      ALLOW_CONNECT='TRUE';
    'VDDIO_L65':
      PIN_NUMBER='(0,0,0,0,0,0,0,0,0,0,0,0,0,0,0,0,0,0,0,0,0,0,0,0,0,0,L65,0,0,0~
,0,0,0,0,0,0,0,0,0,0)';
      PINUSE='POWER';
      NO_LOAD_CHECK='Both';
      NO_IO_CHECK='Both';
      NO_ASSERT_CHECK='TRUE';
      NO_DIR_CHECK='TRUE';
      ALLOW_CONNECT='TRUE';
    'VDDIO_L72':
      PIN_NUMBER='(0,0,0,0,0,0,0,0,0,0,0,0,0,0,0,0,0,0,0,0,0,0,0,0,0,0,L72,0,0,0~
,0,0,0,0,0,0,0,0,0,0)';
      PINUSE='POWER';
      NO_LOAD_CHECK='Both';
      NO_IO_CHECK='Both';
      NO_ASSERT_CHECK='TRUE';
      NO_DIR_CHECK='TRUE';
      ALLOW_CONNECT='TRUE';
    'VDDIO_P54':
      PIN_NUMBER='(0,0,0,0,0,0,0,0,0,0,0,0,0,0,0,0,0,0,0,0,0,0,0,0,0,0,P54,0,0,0~
,0,0,0,0,0,0,0,0,0,0)';
      PINUSE='POWER';
      NO_LOAD_CHECK='Both';
      NO_IO_CHECK='Both';
      NO_ASSERT_CHECK='TRUE';
      NO_DIR_CHECK='TRUE';
      ALLOW_CONNECT='TRUE';
    'VDDIO_P57':
      PIN_NUMBER='(0,0,0,0,0,0,0,0,0,0,0,0,0,0,0,0,0,0,0,0,0,0,0,0,0,0,P57,0,0,0~
,0,0,0,0,0,0,0,0,0,0)';
      PINUSE='POWER';
      NO_LOAD_CHECK='Both';
      NO_IO_CHECK='Both';
      NO_ASSERT_CHECK='TRUE';
      NO_DIR_CHECK='TRUE';
      ALLOW_CONNECT='TRUE';
    'VDDIO_P64':
      PIN_NUMBER='(0,0,0,0,0,0,0,0,0,0,0,0,0,0,0,0,0,0,0,0,0,0,0,0,0,0,P64,0,0,0~
,0,0,0,0,0,0,0,0,0,0)';
      PINUSE='POWER';
      NO_LOAD_CHECK='Both';
      NO_IO_CHECK='Both';
      NO_ASSERT_CHECK='TRUE';
      NO_DIR_CHECK='TRUE';
      ALLOW_CONNECT='TRUE';
    'VDDIO_P71':
      PIN_NUMBER='(0,0,0,0,0,0,0,0,0,0,0,0,0,0,0,0,0,0,0,0,0,0,0,0,0,0,P71,0,0,0~
,0,0,0,0,0,0,0,0,0,0)';
      PINUSE='POWER';
      NO_LOAD_CHECK='Both';
      NO_IO_CHECK='Both';
      NO_ASSERT_CHECK='TRUE';
      NO_DIR_CHECK='TRUE';
      ALLOW_CONNECT='TRUE';
    'VDDIO_U58':
      PIN_NUMBER='(0,0,0,0,0,0,0,0,0,0,0,0,0,0,0,0,0,0,0,0,0,0,0,0,0,0,U58,0,0,0~
,0,0,0,0,0,0,0,0,0,0)';
      PINUSE='POWER';
      NO_LOAD_CHECK='Both';
      NO_IO_CHECK='Both';
      NO_ASSERT_CHECK='TRUE';
      NO_DIR_CHECK='TRUE';
      ALLOW_CONNECT='TRUE';
    'VDDIO_U65':
      PIN_NUMBER='(0,0,0,0,0,0,0,0,0,0,0,0,0,0,0,0,0,0,0,0,0,0,0,0,0,0,U65,0,0,0~
,0,0,0,0,0,0,0,0,0,0)';
      PINUSE='POWER';
      NO_LOAD_CHECK='Both';
      NO_IO_CHECK='Both';
      NO_ASSERT_CHECK='TRUE';
      NO_DIR_CHECK='TRUE';
      ALLOW_CONNECT='TRUE';
    'VDDIO_U72':
      PIN_NUMBER='(0,0,0,0,0,0,0,0,0,0,0,0,0,0,0,0,0,0,0,0,0,0,0,0,0,0,U72,0,0,0~
,0,0,0,0,0,0,0,0,0,0)';
      PINUSE='POWER';
      NO_LOAD_CHECK='Both';
      NO_IO_CHECK='Both';
      NO_ASSERT_CHECK='TRUE';
      NO_DIR_CHECK='TRUE';
      ALLOW_CONNECT='TRUE';
    'VDDIO_V54':
      PIN_NUMBER='(0,0,0,0,0,0,0,0,0,0,0,0,0,0,0,0,0,0,0,0,0,0,0,0,0,0,V54,0,0,0~
,0,0,0,0,0,0,0,0,0,0)';
      PINUSE='POWER';
      NO_LOAD_CHECK='Both';
      NO_IO_CHECK='Both';
      NO_ASSERT_CHECK='TRUE';
      NO_DIR_CHECK='TRUE';
      ALLOW_CONNECT='TRUE';
    'VDDIO_Y57':
      PIN_NUMBER='(0,0,0,0,0,0,0,0,0,0,0,0,0,0,0,0,0,0,0,0,0,0,0,0,0,0,Y57,0,0,0~
,0,0,0,0,0,0,0,0,0,0)';
      PINUSE='POWER';
      NO_LOAD_CHECK='Both';
      NO_IO_CHECK='Both';
      NO_ASSERT_CHECK='TRUE';
      NO_DIR_CHECK='TRUE';
      ALLOW_CONNECT='TRUE';
    'VDDIO_Y64':
      PIN_NUMBER='(0,0,0,0,0,0,0,0,0,0,0,0,0,0,0,0,0,0,0,0,0,0,0,0,0,0,Y64,0,0,0~
,0,0,0,0,0,0,0,0,0,0)';
      PINUSE='POWER';
      NO_LOAD_CHECK='Both';
      NO_IO_CHECK='Both';
      NO_ASSERT_CHECK='TRUE';
      NO_DIR_CHECK='TRUE';
      ALLOW_CONNECT='TRUE';
    'VDDIO_Y71':
      PIN_NUMBER='(0,0,0,0,0,0,0,0,0,0,0,0,0,0,0,0,0,0,0,0,0,0,0,0,0,0,Y71,0,0,0~
,0,0,0,0,0,0,0,0,0,0)';
      PINUSE='POWER';
      NO_LOAD_CHECK='Both';
      NO_IO_CHECK='Both';
      NO_ASSERT_CHECK='TRUE';
      NO_DIR_CHECK='TRUE';
      ALLOW_CONNECT='TRUE';
    'VDDIO_AA54':
      PIN_NUMBER='(0,0,0,0,0,0,0,0,0,0,0,0,0,0,0,0,0,0,0,0,0,0,0,0,0,0,AA54,0,0,~
0,0,0,0,0,0,0,0,0,0,0)';
      PINUSE='POWER';
      NO_LOAD_CHECK='Both';
      NO_IO_CHECK='Both';
      NO_ASSERT_CHECK='TRUE';
      NO_DIR_CHECK='TRUE';
      ALLOW_CONNECT='TRUE';
    'VDDIO_AC58':
      PIN_NUMBER='(0,0,0,0,0,0,0,0,0,0,0,0,0,0,0,0,0,0,0,0,0,0,0,0,0,0,AC58,0,0,~
0,0,0,0,0,0,0,0,0,0,0)';
      PINUSE='POWER';
      NO_LOAD_CHECK='Both';
      NO_IO_CHECK='Both';
      NO_ASSERT_CHECK='TRUE';
      NO_DIR_CHECK='TRUE';
      ALLOW_CONNECT='TRUE';
    'VDDIO_AC65':
      PIN_NUMBER='(0,0,0,0,0,0,0,0,0,0,0,0,0,0,0,0,0,0,0,0,0,0,0,0,0,0,AC65,0,0,~
0,0,0,0,0,0,0,0,0,0,0)';
      PINUSE='POWER';
      NO_LOAD_CHECK='Both';
      NO_IO_CHECK='Both';
      NO_ASSERT_CHECK='TRUE';
      NO_DIR_CHECK='TRUE';
      ALLOW_CONNECT='TRUE';
    'VDDIO_AC72':
      PIN_NUMBER='(0,0,0,0,0,0,0,0,0,0,0,0,0,0,0,0,0,0,0,0,0,0,0,0,0,0,AC72,0,0,~
0,0,0,0,0,0,0,0,0,0,0)';
      PINUSE='POWER';
      NO_LOAD_CHECK='Both';
      NO_IO_CHECK='Both';
      NO_ASSERT_CHECK='TRUE';
      NO_DIR_CHECK='TRUE';
      ALLOW_CONNECT='TRUE';
    'VDDIO_AD54':
      PIN_NUMBER='(0,0,0,0,0,0,0,0,0,0,0,0,0,0,0,0,0,0,0,0,0,0,0,0,0,0,AD54,0,0,~
0,0,0,0,0,0,0,0,0,0,0)';
      PINUSE='POWER';
      NO_LOAD_CHECK='Both';
      NO_IO_CHECK='Both';
      NO_ASSERT_CHECK='TRUE';
      NO_DIR_CHECK='TRUE';
      ALLOW_CONNECT='TRUE';
    'VDDIO_AF57':
      PIN_NUMBER='(0,0,0,0,0,0,0,0,0,0,0,0,0,0,0,0,0,0,0,0,0,0,0,0,0,0,AF57,0,0,~
0,0,0,0,0,0,0,0,0,0,0)';
      PINUSE='POWER';
      NO_LOAD_CHECK='Both';
      NO_IO_CHECK='Both';
      NO_ASSERT_CHECK='TRUE';
      NO_DIR_CHECK='TRUE';
      ALLOW_CONNECT='TRUE';
    'VDDIO_AF64':
      PIN_NUMBER='(0,0,0,0,0,0,0,0,0,0,0,0,0,0,0,0,0,0,0,0,0,0,0,0,0,0,AF64,0,0,~
0,0,0,0,0,0,0,0,0,0,0)';
      PINUSE='POWER';
      NO_LOAD_CHECK='Both';
      NO_IO_CHECK='Both';
      NO_ASSERT_CHECK='TRUE';
      NO_DIR_CHECK='TRUE';
      ALLOW_CONNECT='TRUE';
    'VDDIO_AF71':
      PIN_NUMBER='(0,0,0,0,0,0,0,0,0,0,0,0,0,0,0,0,0,0,0,0,0,0,0,0,0,0,AF71,0,0,~
0,0,0,0,0,0,0,0,0,0,0)';
      PINUSE='POWER';
      NO_LOAD_CHECK='Both';
      NO_IO_CHECK='Both';
      NO_ASSERT_CHECK='TRUE';
      NO_DIR_CHECK='TRUE';
      ALLOW_CONNECT='TRUE';
    'VDDIO_AH54':
      PIN_NUMBER='(0,0,0,0,0,0,0,0,0,0,0,0,0,0,0,0,0,0,0,0,0,0,0,0,0,0,AH54,0,0,~
0,0,0,0,0,0,0,0,0,0,0)';
      PINUSE='POWER';
      NO_LOAD_CHECK='Both';
      NO_IO_CHECK='Both';
      NO_ASSERT_CHECK='TRUE';
      NO_DIR_CHECK='TRUE';
      ALLOW_CONNECT='TRUE';
    'VDDIO_AJ58':
      PIN_NUMBER='(0,0,0,0,0,0,0,0,0,0,0,0,0,0,0,0,0,0,0,0,0,0,0,0,0,0,AJ58,0,0,~
0,0,0,0,0,0,0,0,0,0,0)';
      PINUSE='POWER';
      NO_LOAD_CHECK='Both';
      NO_IO_CHECK='Both';
      NO_ASSERT_CHECK='TRUE';
      NO_DIR_CHECK='TRUE';
      ALLOW_CONNECT='TRUE';
    'VDDIO_AJ65':
      PIN_NUMBER='(0,0,0,0,0,0,0,0,0,0,0,0,0,0,0,0,0,0,0,0,0,0,0,0,0,0,AJ65,0,0,~
0,0,0,0,0,0,0,0,0,0,0)';
      PINUSE='POWER';
      NO_LOAD_CHECK='Both';
      NO_IO_CHECK='Both';
      NO_ASSERT_CHECK='TRUE';
      NO_DIR_CHECK='TRUE';
      ALLOW_CONNECT='TRUE';
    'VDDIO_AJ72':
      PIN_NUMBER='(0,0,0,0,0,0,0,0,0,0,0,0,0,0,0,0,0,0,0,0,0,0,0,0,0,0,AJ72,0,0,~
0,0,0,0,0,0,0,0,0,0,0)';
      PINUSE='POWER';
      NO_LOAD_CHECK='Both';
      NO_IO_CHECK='Both';
      NO_ASSERT_CHECK='TRUE';
      NO_DIR_CHECK='TRUE';
      ALLOW_CONNECT='TRUE';
    'VDDIO_AM54':
      PIN_NUMBER='(0,0,0,0,0,0,0,0,0,0,0,0,0,0,0,0,0,0,0,0,0,0,0,0,0,0,AM54,0,0,~
0,0,0,0,0,0,0,0,0,0,0)';
      PINUSE='POWER';
      NO_LOAD_CHECK='Both';
      NO_IO_CHECK='Both';
      NO_ASSERT_CHECK='TRUE';
      NO_DIR_CHECK='TRUE';
      ALLOW_CONNECT='TRUE';
    'VDDIO_AM57':
      PIN_NUMBER='(0,0,0,0,0,0,0,0,0,0,0,0,0,0,0,0,0,0,0,0,0,0,0,0,0,0,AM57,0,0,~
0,0,0,0,0,0,0,0,0,0,0)';
      PINUSE='POWER';
      NO_LOAD_CHECK='Both';
      NO_IO_CHECK='Both';
      NO_ASSERT_CHECK='TRUE';
      NO_DIR_CHECK='TRUE';
      ALLOW_CONNECT='TRUE';
    'VDDIO_AM64':
      PIN_NUMBER='(0,0,0,0,0,0,0,0,0,0,0,0,0,0,0,0,0,0,0,0,0,0,0,0,0,0,AM64,0,0,~
0,0,0,0,0,0,0,0,0,0,0)';
      PINUSE='POWER';
      NO_LOAD_CHECK='Both';
      NO_IO_CHECK='Both';
      NO_ASSERT_CHECK='TRUE';
      NO_DIR_CHECK='TRUE';
      ALLOW_CONNECT='TRUE';
    'VDDIO_AM71':
      PIN_NUMBER='(0,0,0,0,0,0,0,0,0,0,0,0,0,0,0,0,0,0,0,0,0,0,0,0,0,0,AM71,0,0,~
0,0,0,0,0,0,0,0,0,0,0)';
      PINUSE='POWER';
      NO_LOAD_CHECK='Both';
      NO_IO_CHECK='Both';
      NO_ASSERT_CHECK='TRUE';
      NO_DIR_CHECK='TRUE';
      ALLOW_CONNECT='TRUE';
    'VDDIO_AR58':
      PIN_NUMBER='(0,0,0,0,0,0,0,0,0,0,0,0,0,0,0,0,0,0,0,0,0,0,0,0,0,0,AR58,0,0,~
0,0,0,0,0,0,0,0,0,0,0)';
      PINUSE='POWER';
      NO_LOAD_CHECK='Both';
      NO_IO_CHECK='Both';
      NO_ASSERT_CHECK='TRUE';
      NO_DIR_CHECK='TRUE';
      ALLOW_CONNECT='TRUE';
    'VDDIO_AR65':
      PIN_NUMBER='(0,0,0,0,0,0,0,0,0,0,0,0,0,0,0,0,0,0,0,0,0,0,0,0,0,0,AR65,0,0,~
0,0,0,0,0,0,0,0,0,0,0)';
      PINUSE='POWER';
      NO_LOAD_CHECK='Both';
      NO_IO_CHECK='Both';
      NO_ASSERT_CHECK='TRUE';
      NO_DIR_CHECK='TRUE';
      ALLOW_CONNECT='TRUE';
    'VDDIO_AR72':
      PIN_NUMBER='(0,0,0,0,0,0,0,0,0,0,0,0,0,0,0,0,0,0,0,0,0,0,0,0,0,0,AR72,0,0,~
0,0,0,0,0,0,0,0,0,0,0)';
      PINUSE='POWER';
      NO_LOAD_CHECK='Both';
      NO_IO_CHECK='Both';
      NO_ASSERT_CHECK='TRUE';
      NO_DIR_CHECK='TRUE';
      ALLOW_CONNECT='TRUE';
    'VDDIO_AV57':
      PIN_NUMBER='(0,0,0,0,0,0,0,0,0,0,0,0,0,0,0,0,0,0,0,0,0,0,0,0,0,0,AV57,0,0,~
0,0,0,0,0,0,0,0,0,0,0)';
      PINUSE='POWER';
      NO_LOAD_CHECK='Both';
      NO_IO_CHECK='Both';
      NO_ASSERT_CHECK='TRUE';
      NO_DIR_CHECK='TRUE';
      ALLOW_CONNECT='TRUE';
    'VDDIO_AV64':
      PIN_NUMBER='(0,0,0,0,0,0,0,0,0,0,0,0,0,0,0,0,0,0,0,0,0,0,0,0,0,0,AV64,0,0,~
0,0,0,0,0,0,0,0,0,0,0)';
      PINUSE='POWER';
      NO_LOAD_CHECK='Both';
      NO_IO_CHECK='Both';
      NO_ASSERT_CHECK='TRUE';
      NO_DIR_CHECK='TRUE';
      ALLOW_CONNECT='TRUE';
    'VDDIO_AV71':
      PIN_NUMBER='(0,0,0,0,0,0,0,0,0,0,0,0,0,0,0,0,0,0,0,0,0,0,0,0,0,0,AV71,0,0,~
0,0,0,0,0,0,0,0,0,0,0)';
      PINUSE='POWER';
      NO_LOAD_CHECK='Both';
      NO_IO_CHECK='Both';
      NO_ASSERT_CHECK='TRUE';
      NO_DIR_CHECK='TRUE';
      ALLOW_CONNECT='TRUE';
    'VDDIO_BA58':
      PIN_NUMBER='(0,0,0,0,0,0,0,0,0,0,0,0,0,0,0,0,0,0,0,0,0,0,0,0,0,0,BA58,0,0,~
0,0,0,0,0,0,0,0,0,0,0)';
      PINUSE='POWER';
      NO_LOAD_CHECK='Both';
      NO_IO_CHECK='Both';
      NO_ASSERT_CHECK='TRUE';
      NO_DIR_CHECK='TRUE';
      ALLOW_CONNECT='TRUE';
    'VDDIO_BA65':
      PIN_NUMBER='(0,0,0,0,0,0,0,0,0,0,0,0,0,0,0,0,0,0,0,0,0,0,0,0,0,0,BA65,0,0,~
0,0,0,0,0,0,0,0,0,0,0)';
      PINUSE='POWER';
      NO_LOAD_CHECK='Both';
      NO_IO_CHECK='Both';
      NO_ASSERT_CHECK='TRUE';
      NO_DIR_CHECK='TRUE';
      ALLOW_CONNECT='TRUE';
    'VDDIO_BA72':
      PIN_NUMBER='(0,0,0,0,0,0,0,0,0,0,0,0,0,0,0,0,0,0,0,0,0,0,0,0,0,0,BA72,0,0,~
0,0,0,0,0,0,0,0,0,0,0)';
      PINUSE='POWER';
      NO_LOAD_CHECK='Both';
      NO_IO_CHECK='Both';
      NO_ASSERT_CHECK='TRUE';
      NO_DIR_CHECK='TRUE';
      ALLOW_CONNECT='TRUE';
    'VDDIO_BD50':
      PIN_NUMBER='(0,0,0,0,0,0,0,0,0,0,0,0,0,0,0,0,0,0,0,0,0,0,0,0,0,0,BD50,0,0,~
0,0,0,0,0,0,0,0,0,0,0)';
      PINUSE='POWER';
      NO_LOAD_CHECK='Both';
      NO_IO_CHECK='Both';
      NO_ASSERT_CHECK='TRUE';
      NO_DIR_CHECK='TRUE';
      ALLOW_CONNECT='TRUE';
    'VDDIO_BD52':
      PIN_NUMBER='(0,0,0,0,0,0,0,0,0,0,0,0,0,0,0,0,0,0,0,0,0,0,0,0,0,0,BD52,0,0,~
0,0,0,0,0,0,0,0,0,0,0)';
      PINUSE='POWER';
      NO_LOAD_CHECK='Both';
      NO_IO_CHECK='Both';
      NO_ASSERT_CHECK='TRUE';
      NO_DIR_CHECK='TRUE';
      ALLOW_CONNECT='TRUE';
    'VDDIO_BD54':
      PIN_NUMBER='(0,0,0,0,0,0,0,0,0,0,0,0,0,0,0,0,0,0,0,0,0,0,0,0,0,0,BD54,0,0,~
0,0,0,0,0,0,0,0,0,0,0)';
      PINUSE='POWER';
      NO_LOAD_CHECK='Both';
      NO_IO_CHECK='Both';
      NO_ASSERT_CHECK='TRUE';
      NO_DIR_CHECK='TRUE';
      ALLOW_CONNECT='TRUE';
    'VDDIO_BF51':
      PIN_NUMBER='(0,0,0,0,0,0,0,0,0,0,0,0,0,0,0,0,0,0,0,0,0,0,0,0,0,0,BF51,0,0,~
0,0,0,0,0,0,0,0,0,0,0)';
      PINUSE='POWER';
      NO_LOAD_CHECK='Both';
      NO_IO_CHECK='Both';
      NO_ASSERT_CHECK='TRUE';
      NO_DIR_CHECK='TRUE';
      ALLOW_CONNECT='TRUE';
    'VDDIO_BF53':
      PIN_NUMBER='(0,0,0,0,0,0,0,0,0,0,0,0,0,0,0,0,0,0,0,0,0,0,0,0,0,0,BF53,0,0,~
0,0,0,0,0,0,0,0,0,0,0)';
      PINUSE='POWER';
      NO_LOAD_CHECK='Both';
      NO_IO_CHECK='Both';
      NO_ASSERT_CHECK='TRUE';
      NO_DIR_CHECK='TRUE';
      ALLOW_CONNECT='TRUE';
    'VDDIO_BF57':
      PIN_NUMBER='(0,0,0,0,0,0,0,0,0,0,0,0,0,0,0,0,0,0,0,0,0,0,0,0,0,0,BF57,0,0,~
0,0,0,0,0,0,0,0,0,0,0)';
      PINUSE='POWER';
      NO_LOAD_CHECK='Both';
      NO_IO_CHECK='Both';
      NO_ASSERT_CHECK='TRUE';
      NO_DIR_CHECK='TRUE';
      ALLOW_CONNECT='TRUE';
    'VDDIO_BF64':
      PIN_NUMBER='(0,0,0,0,0,0,0,0,0,0,0,0,0,0,0,0,0,0,0,0,0,0,0,0,0,0,BF64,0,0,~
0,0,0,0,0,0,0,0,0,0,0)';
      PINUSE='POWER';
      NO_LOAD_CHECK='Both';
      NO_IO_CHECK='Both';
      NO_ASSERT_CHECK='TRUE';
      NO_DIR_CHECK='TRUE';
      ALLOW_CONNECT='TRUE';
    'VDDIO_BF71':
      PIN_NUMBER='(0,0,0,0,0,0,0,0,0,0,0,0,0,0,0,0,0,0,0,0,0,0,0,0,0,0,BF71,0,0,~
0,0,0,0,0,0,0,0,0,0,0)';
      PINUSE='POWER';
      NO_LOAD_CHECK='Both';
      NO_IO_CHECK='Both';
      NO_ASSERT_CHECK='TRUE';
      NO_DIR_CHECK='TRUE';
      ALLOW_CONNECT='TRUE';
    'VDDIO_BG50':
      PIN_NUMBER='(0,0,0,0,0,0,0,0,0,0,0,0,0,0,0,0,0,0,0,0,0,0,0,0,0,0,BG50,0,0,~
0,0,0,0,0,0,0,0,0,0,0)';
      PINUSE='POWER';
      NO_LOAD_CHECK='Both';
      NO_IO_CHECK='Both';
      NO_ASSERT_CHECK='TRUE';
      NO_DIR_CHECK='TRUE';
      ALLOW_CONNECT='TRUE';
    'VDDIO_BG52':
      PIN_NUMBER='(0,0,0,0,0,0,0,0,0,0,0,0,0,0,0,0,0,0,0,0,0,0,0,0,0,0,BG52,0,0,~
0,0,0,0,0,0,0,0,0,0,0)';
      PINUSE='POWER';
      NO_LOAD_CHECK='Both';
      NO_IO_CHECK='Both';
      NO_ASSERT_CHECK='TRUE';
      NO_DIR_CHECK='TRUE';
      ALLOW_CONNECT='TRUE';
    'VDDIO_BG54':
      PIN_NUMBER='(0,0,0,0,0,0,0,0,0,0,0,0,0,0,0,0,0,0,0,0,0,0,0,0,0,0,BG54,0,0,~
0,0,0,0,0,0,0,0,0,0,0)';
      PINUSE='POWER';
      NO_LOAD_CHECK='Both';
      NO_IO_CHECK='Both';
      NO_ASSERT_CHECK='TRUE';
      NO_DIR_CHECK='TRUE';
      ALLOW_CONNECT='TRUE';
    'VDDIO_BH51':
      PIN_NUMBER='(0,0,0,0,0,0,0,0,0,0,0,0,0,0,0,0,0,0,0,0,0,0,0,0,0,0,BH51,0,0,~
0,0,0,0,0,0,0,0,0,0,0)';
      PINUSE='POWER';
      NO_LOAD_CHECK='Both';
      NO_IO_CHECK='Both';
      NO_ASSERT_CHECK='TRUE';
      NO_DIR_CHECK='TRUE';
      ALLOW_CONNECT='TRUE';
    'VDDIO_BH53':
      PIN_NUMBER='(0,0,0,0,0,0,0,0,0,0,0,0,0,0,0,0,0,0,0,0,0,0,0,0,0,0,BH53,0,0,~
0,0,0,0,0,0,0,0,0,0,0)';
      PINUSE='POWER';
      NO_LOAD_CHECK='Both';
      NO_IO_CHECK='Both';
      NO_ASSERT_CHECK='TRUE';
      NO_DIR_CHECK='TRUE';
      ALLOW_CONNECT='TRUE';
    'VDDIO_BJ50':
      PIN_NUMBER='(0,0,0,0,0,0,0,0,0,0,0,0,0,0,0,0,0,0,0,0,0,0,0,0,0,0,BJ50,0,0,~
0,0,0,0,0,0,0,0,0,0,0)';
      PINUSE='POWER';
      NO_LOAD_CHECK='Both';
      NO_IO_CHECK='Both';
      NO_ASSERT_CHECK='TRUE';
      NO_DIR_CHECK='TRUE';
      ALLOW_CONNECT='TRUE';
    'VDDIO_BJ52':
      PIN_NUMBER='(0,0,0,0,0,0,0,0,0,0,0,0,0,0,0,0,0,0,0,0,0,0,0,0,0,0,BJ52,0,0,~
0,0,0,0,0,0,0,0,0,0,0)';
      PINUSE='POWER';
      NO_LOAD_CHECK='Both';
      NO_IO_CHECK='Both';
      NO_ASSERT_CHECK='TRUE';
      NO_DIR_CHECK='TRUE';
      ALLOW_CONNECT='TRUE';
    'VDDIO_BJ54':
      PIN_NUMBER='(0,0,0,0,0,0,0,0,0,0,0,0,0,0,0,0,0,0,0,0,0,0,0,0,0,0,BJ54,0,0,~
0,0,0,0,0,0,0,0,0,0,0)';
      PINUSE='POWER';
      NO_LOAD_CHECK='Both';
      NO_IO_CHECK='Both';
      NO_ASSERT_CHECK='TRUE';
      NO_DIR_CHECK='TRUE';
      ALLOW_CONNECT='TRUE';
    'VDDIO_BJ58':
      PIN_NUMBER='(0,0,0,0,0,0,0,0,0,0,0,0,0,0,0,0,0,0,0,0,0,0,0,0,0,0,BJ58,0,0,~
0,0,0,0,0,0,0,0,0,0,0)';
      PINUSE='POWER';
      NO_LOAD_CHECK='Both';
      NO_IO_CHECK='Both';
      NO_ASSERT_CHECK='TRUE';
      NO_DIR_CHECK='TRUE';
      ALLOW_CONNECT='TRUE';
    'VDDIO_BJ65':
      PIN_NUMBER='(0,0,0,0,0,0,0,0,0,0,0,0,0,0,0,0,0,0,0,0,0,0,0,0,0,0,BJ65,0,0,~
0,0,0,0,0,0,0,0,0,0,0)';
      PINUSE='POWER';
      NO_LOAD_CHECK='Both';
      NO_IO_CHECK='Both';
      NO_ASSERT_CHECK='TRUE';
      NO_DIR_CHECK='TRUE';
      ALLOW_CONNECT='TRUE';
    'VDDIO_BJ72':
      PIN_NUMBER='(0,0,0,0,0,0,0,0,0,0,0,0,0,0,0,0,0,0,0,0,0,0,0,0,0,0,BJ72,0,0,~
0,0,0,0,0,0,0,0,0,0,0)';
      PINUSE='POWER';
      NO_LOAD_CHECK='Both';
      NO_IO_CHECK='Both';
      NO_ASSERT_CHECK='TRUE';
      NO_DIR_CHECK='TRUE';
      ALLOW_CONNECT='TRUE';
    'VDDIO_BK51':
      PIN_NUMBER='(0,0,0,0,0,0,0,0,0,0,0,0,0,0,0,0,0,0,0,0,0,0,0,0,0,0,BK51,0,0,~
0,0,0,0,0,0,0,0,0,0,0)';
      PINUSE='POWER';
      NO_LOAD_CHECK='Both';
      NO_IO_CHECK='Both';
      NO_ASSERT_CHECK='TRUE';
      NO_DIR_CHECK='TRUE';
      ALLOW_CONNECT='TRUE';
    'VDDIO_BK53':
      PIN_NUMBER='(0,0,0,0,0,0,0,0,0,0,0,0,0,0,0,0,0,0,0,0,0,0,0,0,0,0,BK53,0,0,~
0,0,0,0,0,0,0,0,0,0,0)';
      PINUSE='POWER';
      NO_LOAD_CHECK='Both';
      NO_IO_CHECK='Both';
      NO_ASSERT_CHECK='TRUE';
      NO_DIR_CHECK='TRUE';
      ALLOW_CONNECT='TRUE';
    'VDDIO_BL50':
      PIN_NUMBER='(0,0,0,0,0,0,0,0,0,0,0,0,0,0,0,0,0,0,0,0,0,0,0,0,0,0,BL50,0,0,~
0,0,0,0,0,0,0,0,0,0,0)';
      PINUSE='POWER';
      NO_LOAD_CHECK='Both';
      NO_IO_CHECK='Both';
      NO_ASSERT_CHECK='TRUE';
      NO_DIR_CHECK='TRUE';
      ALLOW_CONNECT='TRUE';
    'VDDIO_BL52':
      PIN_NUMBER='(0,0,0,0,0,0,0,0,0,0,0,0,0,0,0,0,0,0,0,0,0,0,0,0,0,0,BL52,0,0,~
0,0,0,0,0,0,0,0,0,0,0)';
      PINUSE='POWER';
      NO_LOAD_CHECK='Both';
      NO_IO_CHECK='Both';
      NO_ASSERT_CHECK='TRUE';
      NO_DIR_CHECK='TRUE';
      ALLOW_CONNECT='TRUE';
    'VDDIO_BL54':
      PIN_NUMBER='(0,0,0,0,0,0,0,0,0,0,0,0,0,0,0,0,0,0,0,0,0,0,0,0,0,0,BL54,0,0,~
0,0,0,0,0,0,0,0,0,0,0)';
      PINUSE='POWER';
      NO_LOAD_CHECK='Both';
      NO_IO_CHECK='Both';
      NO_ASSERT_CHECK='TRUE';
      NO_DIR_CHECK='TRUE';
      ALLOW_CONNECT='TRUE';
    'VDDIO_BM51':
      PIN_NUMBER='(0,0,0,0,0,0,0,0,0,0,0,0,0,0,0,0,0,0,0,0,0,0,0,0,0,0,BM51,0,0,~
0,0,0,0,0,0,0,0,0,0,0)';
      PINUSE='POWER';
      NO_LOAD_CHECK='Both';
      NO_IO_CHECK='Both';
      NO_ASSERT_CHECK='TRUE';
      NO_DIR_CHECK='TRUE';
      ALLOW_CONNECT='TRUE';
    'VDDIO_BM53':
      PIN_NUMBER='(0,0,0,0,0,0,0,0,0,0,0,0,0,0,0,0,0,0,0,0,0,0,0,0,0,0,BM53,0,0,~
0,0,0,0,0,0,0,0,0,0,0)';
      PINUSE='POWER';
      NO_LOAD_CHECK='Both';
      NO_IO_CHECK='Both';
      NO_ASSERT_CHECK='TRUE';
      NO_DIR_CHECK='TRUE';
      ALLOW_CONNECT='TRUE';
    'VDDIO_BM57':
      PIN_NUMBER='(0,0,0,0,0,0,0,0,0,0,0,0,0,0,0,0,0,0,0,0,0,0,0,0,0,0,BM57,0,0,~
0,0,0,0,0,0,0,0,0,0,0)';
      PINUSE='POWER';
      NO_LOAD_CHECK='Both';
      NO_IO_CHECK='Both';
      NO_ASSERT_CHECK='TRUE';
      NO_DIR_CHECK='TRUE';
      ALLOW_CONNECT='TRUE';
    'VDDIO_BM64':
      PIN_NUMBER='(0,0,0,0,0,0,0,0,0,0,0,0,0,0,0,0,0,0,0,0,0,0,0,0,0,0,BM64,0,0,~
0,0,0,0,0,0,0,0,0,0,0)';
      PINUSE='POWER';
      NO_LOAD_CHECK='Both';
      NO_IO_CHECK='Both';
      NO_ASSERT_CHECK='TRUE';
      NO_DIR_CHECK='TRUE';
      ALLOW_CONNECT='TRUE';
    'VDDIO_BM71':
      PIN_NUMBER='(0,0,0,0,0,0,0,0,0,0,0,0,0,0,0,0,0,0,0,0,0,0,0,0,0,0,BM71,0,0,~
0,0,0,0,0,0,0,0,0,0,0)';
      PINUSE='POWER';
      NO_LOAD_CHECK='Both';
      NO_IO_CHECK='Both';
      NO_ASSERT_CHECK='TRUE';
      NO_DIR_CHECK='TRUE';
      ALLOW_CONNECT='TRUE';
    'VDDIO_BN54':
      PIN_NUMBER='(0,0,0,0,0,0,0,0,0,0,0,0,0,0,0,0,0,0,0,0,0,0,0,0,0,0,BN54,0,0,~
0,0,0,0,0,0,0,0,0,0,0)';
      PINUSE='POWER';
      NO_LOAD_CHECK='Both';
      NO_IO_CHECK='Both';
      NO_ASSERT_CHECK='TRUE';
      NO_DIR_CHECK='TRUE';
      ALLOW_CONNECT='TRUE';
    'VDDIO_BR58':
      PIN_NUMBER='(0,0,0,0,0,0,0,0,0,0,0,0,0,0,0,0,0,0,0,0,0,0,0,0,0,0,BR58,0,0,~
0,0,0,0,0,0,0,0,0,0,0)';
      PINUSE='POWER';
      NO_LOAD_CHECK='Both';
      NO_IO_CHECK='Both';
      NO_ASSERT_CHECK='TRUE';
      NO_DIR_CHECK='TRUE';
      ALLOW_CONNECT='TRUE';
    'VDDIO_BR65':
      PIN_NUMBER='(0,0,0,0,0,0,0,0,0,0,0,0,0,0,0,0,0,0,0,0,0,0,0,0,0,0,BR65,0,0,~
0,0,0,0,0,0,0,0,0,0,0)';
      PINUSE='POWER';
      NO_LOAD_CHECK='Both';
      NO_IO_CHECK='Both';
      NO_ASSERT_CHECK='TRUE';
      NO_DIR_CHECK='TRUE';
      ALLOW_CONNECT='TRUE';
    'VDDIO_BR72':
      PIN_NUMBER='(0,0,0,0,0,0,0,0,0,0,0,0,0,0,0,0,0,0,0,0,0,0,0,0,0,0,BR72,0,0,~
0,0,0,0,0,0,0,0,0,0,0)';
      PINUSE='POWER';
      NO_LOAD_CHECK='Both';
      NO_IO_CHECK='Both';
      NO_ASSERT_CHECK='TRUE';
      NO_DIR_CHECK='TRUE';
      ALLOW_CONNECT='TRUE';
    'VDDIO_BV54':
      PIN_NUMBER='(0,0,0,0,0,0,0,0,0,0,0,0,0,0,0,0,0,0,0,0,0,0,0,0,0,0,BV54,0,0,~
0,0,0,0,0,0,0,0,0,0,0)';
      PINUSE='POWER';
      NO_LOAD_CHECK='Both';
      NO_IO_CHECK='Both';
      NO_ASSERT_CHECK='TRUE';
      NO_DIR_CHECK='TRUE';
      ALLOW_CONNECT='TRUE';
    'VDDIO_BV57':
      PIN_NUMBER='(0,0,0,0,0,0,0,0,0,0,0,0,0,0,0,0,0,0,0,0,0,0,0,0,0,0,BV57,0,0,~
0,0,0,0,0,0,0,0,0,0,0)';
      PINUSE='POWER';
      NO_LOAD_CHECK='Both';
      NO_IO_CHECK='Both';
      NO_ASSERT_CHECK='TRUE';
      NO_DIR_CHECK='TRUE';
      ALLOW_CONNECT='TRUE';
    'VDDIO_BV64':
      PIN_NUMBER='(0,0,0,0,0,0,0,0,0,0,0,0,0,0,0,0,0,0,0,0,0,0,0,0,0,0,BV64,0,0,~
0,0,0,0,0,0,0,0,0,0,0)';
      PINUSE='POWER';
      NO_LOAD_CHECK='Both';
      NO_IO_CHECK='Both';
      NO_ASSERT_CHECK='TRUE';
      NO_DIR_CHECK='TRUE';
      ALLOW_CONNECT='TRUE';
    'VDDIO_BV71':
      PIN_NUMBER='(0,0,0,0,0,0,0,0,0,0,0,0,0,0,0,0,0,0,0,0,0,0,0,0,0,0,BV71,0,0,~
0,0,0,0,0,0,0,0,0,0,0)';
      PINUSE='POWER';
      NO_LOAD_CHECK='Both';
      NO_IO_CHECK='Both';
      NO_ASSERT_CHECK='TRUE';
      NO_DIR_CHECK='TRUE';
      ALLOW_CONNECT='TRUE';
    'VDDIO_CA58':
      PIN_NUMBER='(0,0,0,0,0,0,0,0,0,0,0,0,0,0,0,0,0,0,0,0,0,0,0,0,0,0,CA58,0,0,~
0,0,0,0,0,0,0,0,0,0,0)';
      PINUSE='POWER';
      NO_LOAD_CHECK='Both';
      NO_IO_CHECK='Both';
      NO_ASSERT_CHECK='TRUE';
      NO_DIR_CHECK='TRUE';
      ALLOW_CONNECT='TRUE';
    'VDDIO_CA65':
      PIN_NUMBER='(0,0,0,0,0,0,0,0,0,0,0,0,0,0,0,0,0,0,0,0,0,0,0,0,0,0,CA65,0,0,~
0,0,0,0,0,0,0,0,0,0,0)';
      PINUSE='POWER';
      NO_LOAD_CHECK='Both';
      NO_IO_CHECK='Both';
      NO_ASSERT_CHECK='TRUE';
      NO_DIR_CHECK='TRUE';
      ALLOW_CONNECT='TRUE';
    'VDDIO_CA72':
      PIN_NUMBER='(0,0,0,0,0,0,0,0,0,0,0,0,0,0,0,0,0,0,0,0,0,0,0,0,0,0,CA72,0,0,~
0,0,0,0,0,0,0,0,0,0,0)';
      PINUSE='POWER';
      NO_LOAD_CHECK='Both';
      NO_IO_CHECK='Both';
      NO_ASSERT_CHECK='TRUE';
      NO_DIR_CHECK='TRUE';
      ALLOW_CONNECT='TRUE';
    'VDDIO_CB54':
      PIN_NUMBER='(0,0,0,0,0,0,0,0,0,0,0,0,0,0,0,0,0,0,0,0,0,0,0,0,0,0,CB54,0,0,~
0,0,0,0,0,0,0,0,0,0,0)';
      PINUSE='POWER';
      NO_LOAD_CHECK='Both';
      NO_IO_CHECK='Both';
      NO_ASSERT_CHECK='TRUE';
      NO_DIR_CHECK='TRUE';
      ALLOW_CONNECT='TRUE';
    'VDDIO_CD57':
      PIN_NUMBER='(0,0,0,0,0,0,0,0,0,0,0,0,0,0,0,0,0,0,0,0,0,0,0,0,0,0,CD57,0,0,~
0,0,0,0,0,0,0,0,0,0,0)';
      PINUSE='POWER';
      NO_LOAD_CHECK='Both';
      NO_IO_CHECK='Both';
      NO_ASSERT_CHECK='TRUE';
      NO_DIR_CHECK='TRUE';
      ALLOW_CONNECT='TRUE';
    'VDDIO_CD64':
      PIN_NUMBER='(0,0,0,0,0,0,0,0,0,0,0,0,0,0,0,0,0,0,0,0,0,0,0,0,0,0,CD64,0,0,~
0,0,0,0,0,0,0,0,0,0,0)';
      PINUSE='POWER';
      NO_LOAD_CHECK='Both';
      NO_IO_CHECK='Both';
      NO_ASSERT_CHECK='TRUE';
      NO_DIR_CHECK='TRUE';
      ALLOW_CONNECT='TRUE';
    'VDDIO_CD71':
      PIN_NUMBER='(0,0,0,0,0,0,0,0,0,0,0,0,0,0,0,0,0,0,0,0,0,0,0,0,0,0,CD71,0,0,~
0,0,0,0,0,0,0,0,0,0,0)';
      PINUSE='POWER';
      NO_LOAD_CHECK='Both';
      NO_IO_CHECK='Both';
      NO_ASSERT_CHECK='TRUE';
      NO_DIR_CHECK='TRUE';
      ALLOW_CONNECT='TRUE';
    'VDDIO_CF54':
      PIN_NUMBER='(0,0,0,0,0,0,0,0,0,0,0,0,0,0,0,0,0,0,0,0,0,0,0,0,0,0,CF54,0,0,~
0,0,0,0,0,0,0,0,0,0,0)';
      PINUSE='POWER';
      NO_LOAD_CHECK='Both';
      NO_IO_CHECK='Both';
      NO_ASSERT_CHECK='TRUE';
      NO_DIR_CHECK='TRUE';
      ALLOW_CONNECT='TRUE';
    'VDDIO_CG58':
      PIN_NUMBER='(0,0,0,0,0,0,0,0,0,0,0,0,0,0,0,0,0,0,0,0,0,0,0,0,0,0,CG58,0,0,~
0,0,0,0,0,0,0,0,0,0,0)';
      PINUSE='POWER';
      NO_LOAD_CHECK='Both';
      NO_IO_CHECK='Both';
      NO_ASSERT_CHECK='TRUE';
      NO_DIR_CHECK='TRUE';
      ALLOW_CONNECT='TRUE';
    'VDDIO_CG65':
      PIN_NUMBER='(0,0,0,0,0,0,0,0,0,0,0,0,0,0,0,0,0,0,0,0,0,0,0,0,0,0,CG65,0,0,~
0,0,0,0,0,0,0,0,0,0,0)';
      PINUSE='POWER';
      NO_LOAD_CHECK='Both';
      NO_IO_CHECK='Both';
      NO_ASSERT_CHECK='TRUE';
      NO_DIR_CHECK='TRUE';
      ALLOW_CONNECT='TRUE';
    'VDDIO_CG72':
      PIN_NUMBER='(0,0,0,0,0,0,0,0,0,0,0,0,0,0,0,0,0,0,0,0,0,0,0,0,0,0,CG72,0,0,~
0,0,0,0,0,0,0,0,0,0,0)';
      PINUSE='POWER';
      NO_LOAD_CHECK='Both';
      NO_IO_CHECK='Both';
      NO_ASSERT_CHECK='TRUE';
      NO_DIR_CHECK='TRUE';
      ALLOW_CONNECT='TRUE';
    'VDDIO_CJ54':
      PIN_NUMBER='(0,0,0,0,0,0,0,0,0,0,0,0,0,0,0,0,0,0,0,0,0,0,0,0,0,0,CJ54,0,0,~
0,0,0,0,0,0,0,0,0,0,0)';
      PINUSE='POWER';
      NO_LOAD_CHECK='Both';
      NO_IO_CHECK='Both';
      NO_ASSERT_CHECK='TRUE';
      NO_DIR_CHECK='TRUE';
      ALLOW_CONNECT='TRUE';
    'VDDIO_CK57':
      PIN_NUMBER='(0,0,0,0,0,0,0,0,0,0,0,0,0,0,0,0,0,0,0,0,0,0,0,0,0,0,CK57,0,0,~
0,0,0,0,0,0,0,0,0,0,0)';
      PINUSE='POWER';
      NO_LOAD_CHECK='Both';
      NO_IO_CHECK='Both';
      NO_ASSERT_CHECK='TRUE';
      NO_DIR_CHECK='TRUE';
      ALLOW_CONNECT='TRUE';
    'VDDIO_CK64':
      PIN_NUMBER='(0,0,0,0,0,0,0,0,0,0,0,0,0,0,0,0,0,0,0,0,0,0,0,0,0,0,CK64,0,0,~
0,0,0,0,0,0,0,0,0,0,0)';
      PINUSE='POWER';
      NO_LOAD_CHECK='Both';
      NO_IO_CHECK='Both';
      NO_ASSERT_CHECK='TRUE';
      NO_DIR_CHECK='TRUE';
      ALLOW_CONNECT='TRUE';
    'VDDIO_CK71':
      PIN_NUMBER='(0,0,0,0,0,0,0,0,0,0,0,0,0,0,0,0,0,0,0,0,0,0,0,0,0,0,CK71,0,0,~
0,0,0,0,0,0,0,0,0,0,0)';
      PINUSE='POWER';
      NO_LOAD_CHECK='Both';
      NO_IO_CHECK='Both';
      NO_ASSERT_CHECK='TRUE';
      NO_DIR_CHECK='TRUE';
      ALLOW_CONNECT='TRUE';
    'VDDIO_CM54':
      PIN_NUMBER='(0,0,0,0,0,0,0,0,0,0,0,0,0,0,0,0,0,0,0,0,0,0,0,0,0,0,CM54,0,0,~
0,0,0,0,0,0,0,0,0,0,0)';
      PINUSE='POWER';
      NO_LOAD_CHECK='Both';
      NO_IO_CHECK='Both';
      NO_ASSERT_CHECK='TRUE';
      NO_DIR_CHECK='TRUE';
      ALLOW_CONNECT='TRUE';
    'VDDIO_CN58':
      PIN_NUMBER='(0,0,0,0,0,0,0,0,0,0,0,0,0,0,0,0,0,0,0,0,0,0,0,0,0,0,CN58,0,0,~
0,0,0,0,0,0,0,0,0,0,0)';
      PINUSE='POWER';
      NO_LOAD_CHECK='Both';
      NO_IO_CHECK='Both';
      NO_ASSERT_CHECK='TRUE';
      NO_DIR_CHECK='TRUE';
      ALLOW_CONNECT='TRUE';
    'VDDIO_CN65':
      PIN_NUMBER='(0,0,0,0,0,0,0,0,0,0,0,0,0,0,0,0,0,0,0,0,0,0,0,0,0,0,CN65,0,0,~
0,0,0,0,0,0,0,0,0,0,0)';
      PINUSE='POWER';
      NO_LOAD_CHECK='Both';
      NO_IO_CHECK='Both';
      NO_ASSERT_CHECK='TRUE';
      NO_DIR_CHECK='TRUE';
      ALLOW_CONNECT='TRUE';
    'VDDIO_CN72':
      PIN_NUMBER='(0,0,0,0,0,0,0,0,0,0,0,0,0,0,0,0,0,0,0,0,0,0,0,0,0,0,CN72,0,0,~
0,0,0,0,0,0,0,0,0,0,0)';
      PINUSE='POWER';
      NO_LOAD_CHECK='Both';
      NO_IO_CHECK='Both';
      NO_ASSERT_CHECK='TRUE';
      NO_DIR_CHECK='TRUE';
      ALLOW_CONNECT='TRUE';
    'VDDIO_CT54':
      PIN_NUMBER='(0,0,0,0,0,0,0,0,0,0,0,0,0,0,0,0,0,0,0,0,0,0,0,0,0,0,CT54,0,0,~
0,0,0,0,0,0,0,0,0,0,0)';
      PINUSE='POWER';
      NO_LOAD_CHECK='Both';
      NO_IO_CHECK='Both';
      NO_ASSERT_CHECK='TRUE';
      NO_DIR_CHECK='TRUE';
      ALLOW_CONNECT='TRUE';
    'VDDIO_CT57':
      PIN_NUMBER='(0,0,0,0,0,0,0,0,0,0,0,0,0,0,0,0,0,0,0,0,0,0,0,0,0,0,CT57,0,0,~
0,0,0,0,0,0,0,0,0,0,0)';
      PINUSE='POWER';
      NO_LOAD_CHECK='Both';
      NO_IO_CHECK='Both';
      NO_ASSERT_CHECK='TRUE';
      NO_DIR_CHECK='TRUE';
      ALLOW_CONNECT='TRUE';
    'VDD_11_S3_BJ18':
      PIN_NUMBER='(0,0,0,0,0,0,0,0,0,0,0,0,0,0,0,0,0,0,0,0,0,0,0,0,0,0,BJ18,0,0,~
0,0,0,0,0,0,0,0,0,0,0)';
      PINUSE='POWER';
      NO_LOAD_CHECK='Both';
      NO_IO_CHECK='Both';
      NO_ASSERT_CHECK='TRUE';
      NO_DIR_CHECK='TRUE';
      ALLOW_CONNECT='TRUE';
    'VDD_11_S3_BJ23':
      PIN_NUMBER='(0,0,0,0,0,0,0,0,0,0,0,0,0,0,0,0,0,0,0,0,0,0,0,0,0,0,BJ23,0,0,~
0,0,0,0,0,0,0,0,0,0,0)';
      PINUSE='POWER';
      NO_LOAD_CHECK='Both';
      NO_IO_CHECK='Both';
      NO_ASSERT_CHECK='TRUE';
      NO_DIR_CHECK='TRUE';
      ALLOW_CONNECT='TRUE';
    'VDD_11_S3_BJ25':
      PIN_NUMBER='(0,0,0,0,0,0,0,0,0,0,0,0,0,0,0,0,0,0,0,0,0,0,0,0,0,0,BJ25,0,0,~
0,0,0,0,0,0,0,0,0,0,0)';
      PINUSE='POWER';
      NO_LOAD_CHECK='Both';
      NO_IO_CHECK='Both';
      NO_ASSERT_CHECK='TRUE';
      NO_DIR_CHECK='TRUE';
      ALLOW_CONNECT='TRUE';
    'VDD_11_S3_BJ27':
      PIN_NUMBER='(0,0,0,0,0,0,0,0,0,0,0,0,0,0,0,0,0,0,0,0,0,0,0,0,0,0,BJ27,0,0,~
0,0,0,0,0,0,0,0,0,0,0)';
      PINUSE='POWER';
      NO_LOAD_CHECK='Both';
      NO_IO_CHECK='Both';
      NO_ASSERT_CHECK='TRUE';
      NO_DIR_CHECK='TRUE';
      ALLOW_CONNECT='TRUE';
    'VDD_11_S3_BK22':
      PIN_NUMBER='(0,0,0,0,0,0,0,0,0,0,0,0,0,0,0,0,0,0,0,0,0,0,0,0,0,0,BK22,0,0,~
0,0,0,0,0,0,0,0,0,0,0)';
      PINUSE='POWER';
      NO_LOAD_CHECK='Both';
      NO_IO_CHECK='Both';
      NO_ASSERT_CHECK='TRUE';
      NO_DIR_CHECK='TRUE';
      ALLOW_CONNECT='TRUE';
    'VDD_11_S3_BK24':
      PIN_NUMBER='(0,0,0,0,0,0,0,0,0,0,0,0,0,0,0,0,0,0,0,0,0,0,0,0,0,0,BK24,0,0,~
0,0,0,0,0,0,0,0,0,0,0)';
      PINUSE='POWER';
      NO_LOAD_CHECK='Both';
      NO_IO_CHECK='Both';
      NO_ASSERT_CHECK='TRUE';
      NO_DIR_CHECK='TRUE';
      ALLOW_CONNECT='TRUE';
    'VDD_11_S3_BK26':
      PIN_NUMBER='(0,0,0,0,0,0,0,0,0,0,0,0,0,0,0,0,0,0,0,0,0,0,0,0,0,0,BK26,0,0,~
0,0,0,0,0,0,0,0,0,0,0)';
      PINUSE='POWER';
      NO_LOAD_CHECK='Both';
      NO_IO_CHECK='Both';
      NO_ASSERT_CHECK='TRUE';
      NO_DIR_CHECK='TRUE';
      ALLOW_CONNECT='TRUE';
    'VDD_11_S3_BK28':
      PIN_NUMBER='(0,0,0,0,0,0,0,0,0,0,0,0,0,0,0,0,0,0,0,0,0,0,0,0,0,0,BK28,0,0,~
0,0,0,0,0,0,0,0,0,0,0)';
      PINUSE='POWER';
      NO_LOAD_CHECK='Both';
      NO_IO_CHECK='Both';
      NO_ASSERT_CHECK='TRUE';
      NO_DIR_CHECK='TRUE';
      ALLOW_CONNECT='TRUE';
    'VDD_11_S3_BK49':
      PIN_NUMBER='(0,0,0,0,0,0,0,0,0,0,0,0,0,0,0,0,0,0,0,0,0,0,0,0,0,0,BK49,0,0,~
0,0,0,0,0,0,0,0,0,0,0)';
      PINUSE='POWER';
      NO_LOAD_CHECK='Both';
      NO_IO_CHECK='Both';
      NO_ASSERT_CHECK='TRUE';
      NO_DIR_CHECK='TRUE';
      ALLOW_CONNECT='TRUE';
    'VDD_11_S3_BL23':
      PIN_NUMBER='(0,0,0,0,0,0,0,0,0,0,0,0,0,0,0,0,0,0,0,0,0,0,0,0,0,0,BL23,0,0,~
0,0,0,0,0,0,0,0,0,0,0)';
      PINUSE='POWER';
      NO_LOAD_CHECK='Both';
      NO_IO_CHECK='Both';
      NO_ASSERT_CHECK='TRUE';
      NO_DIR_CHECK='TRUE';
      ALLOW_CONNECT='TRUE';
    'VDD_11_S3_BL25':
      PIN_NUMBER='(0,0,0,0,0,0,0,0,0,0,0,0,0,0,0,0,0,0,0,0,0,0,0,0,0,0,BL25,0,0,~
0,0,0,0,0,0,0,0,0,0,0)';
      PINUSE='POWER';
      NO_LOAD_CHECK='Both';
      NO_IO_CHECK='Both';
      NO_ASSERT_CHECK='TRUE';
      NO_DIR_CHECK='TRUE';
      ALLOW_CONNECT='TRUE';
    'VDD_11_S3_BL27':
      PIN_NUMBER='(0,0,0,0,0,0,0,0,0,0,0,0,0,0,0,0,0,0,0,0,0,0,0,0,0,0,BL27,0,0,~
0,0,0,0,0,0,0,0,0,0,0)';
      PINUSE='POWER';
      NO_LOAD_CHECK='Both';
      NO_IO_CHECK='Both';
      NO_ASSERT_CHECK='TRUE';
      NO_DIR_CHECK='TRUE';
      ALLOW_CONNECT='TRUE';
    'VDD_11_S3_BL48':
      PIN_NUMBER='(0,0,0,0,0,0,0,0,0,0,0,0,0,0,0,0,0,0,0,0,0,0,0,0,0,0,BL48,0,0,~
0,0,0,0,0,0,0,0,0,0,0)';
      PINUSE='POWER';
      NO_LOAD_CHECK='Both';
      NO_IO_CHECK='Both';
      NO_ASSERT_CHECK='TRUE';
      NO_DIR_CHECK='TRUE';
      ALLOW_CONNECT='TRUE';
    'VDD_11_S3_BM12':
      PIN_NUMBER='(0,0,0,0,0,0,0,0,0,0,0,0,0,0,0,0,0,0,0,0,0,0,0,0,0,0,BM12,0,0,~
0,0,0,0,0,0,0,0,0,0,0)';
      PINUSE='POWER';
      NO_LOAD_CHECK='Both';
      NO_IO_CHECK='Both';
      NO_ASSERT_CHECK='TRUE';
      NO_DIR_CHECK='TRUE';
      ALLOW_CONNECT='TRUE';
    'VDD_11_S3_BM19':
      PIN_NUMBER='(0,0,0,0,0,0,0,0,0,0,0,0,0,0,0,0,0,0,0,0,0,0,0,0,0,0,BM19,0,0,~
0,0,0,0,0,0,0,0,0,0,0)';
      PINUSE='POWER';
      NO_LOAD_CHECK='Both';
      NO_IO_CHECK='Both';
      NO_ASSERT_CHECK='TRUE';
      NO_DIR_CHECK='TRUE';
      ALLOW_CONNECT='TRUE';
    'VDD_11_S3_BM22':
      PIN_NUMBER='(0,0,0,0,0,0,0,0,0,0,0,0,0,0,0,0,0,0,0,0,0,0,0,0,0,0,BM22,0,0,~
0,0,0,0,0,0,0,0,0,0,0)';
      PINUSE='POWER';
      NO_LOAD_CHECK='Both';
      NO_IO_CHECK='Both';
      NO_ASSERT_CHECK='TRUE';
      NO_DIR_CHECK='TRUE';
      ALLOW_CONNECT='TRUE';
    'VDD_11_S3_BM24':
      PIN_NUMBER='(0,0,0,0,0,0,0,0,0,0,0,0,0,0,0,0,0,0,0,0,0,0,0,0,0,0,BM24,0,0,~
0,0,0,0,0,0,0,0,0,0,0)';
      PINUSE='POWER';
      NO_LOAD_CHECK='Both';
      NO_IO_CHECK='Both';
      NO_ASSERT_CHECK='TRUE';
      NO_DIR_CHECK='TRUE';
      ALLOW_CONNECT='TRUE';
    'VDD_11_S3_BM26':
      PIN_NUMBER='(0,0,0,0,0,0,0,0,0,0,0,0,0,0,0,0,0,0,0,0,0,0,0,0,0,0,BM26,0,0,~
0,0,0,0,0,0,0,0,0,0,0)';
      PINUSE='POWER';
      NO_LOAD_CHECK='Both';
      NO_IO_CHECK='Both';
      NO_ASSERT_CHECK='TRUE';
      NO_DIR_CHECK='TRUE';
      ALLOW_CONNECT='TRUE';
    'VDD_11_S3_BM28':
      PIN_NUMBER='(0,0,0,0,0,0,0,0,0,0,0,0,0,0,0,0,0,0,0,0,0,0,0,0,0,0,BM28,0,0,~
0,0,0,0,0,0,0,0,0,0,0)';
      PINUSE='POWER';
      NO_LOAD_CHECK='Both';
      NO_IO_CHECK='Both';
      NO_ASSERT_CHECK='TRUE';
      NO_DIR_CHECK='TRUE';
      ALLOW_CONNECT='TRUE';
    'VDD_11_S3_BM30':
      PIN_NUMBER='(0,0,0,0,0,0,0,0,0,0,0,0,0,0,0,0,0,0,0,0,0,0,0,0,0,0,BM30,0,0,~
0,0,0,0,0,0,0,0,0,0,0)';
      PINUSE='POWER';
      NO_LOAD_CHECK='Both';
      NO_IO_CHECK='Both';
      NO_ASSERT_CHECK='TRUE';
      NO_DIR_CHECK='TRUE';
      ALLOW_CONNECT='TRUE';
    'VDD_11_S3_BM32':
      PIN_NUMBER='(0,0,0,0,0,0,0,0,0,0,0,0,0,0,0,0,0,0,0,0,0,0,0,0,0,0,BM32,0,0,~
0,0,0,0,0,0,0,0,0,0,0)';
      PINUSE='POWER';
      NO_LOAD_CHECK='Both';
      NO_IO_CHECK='Both';
      NO_ASSERT_CHECK='TRUE';
      NO_DIR_CHECK='TRUE';
      ALLOW_CONNECT='TRUE';
    'VDD_11_S3_BM34':
      PIN_NUMBER='(0,0,0,0,0,0,0,0,0,0,0,0,0,0,0,0,0,0,0,0,0,0,0,0,0,0,BM34,0,0,~
0,0,0,0,0,0,0,0,0,0,0)';
      PINUSE='POWER';
      NO_LOAD_CHECK='Both';
      NO_IO_CHECK='Both';
      NO_ASSERT_CHECK='TRUE';
      NO_DIR_CHECK='TRUE';
      ALLOW_CONNECT='TRUE';
    'VDD_11_S3_BM36':
      PIN_NUMBER='(0,0,0,0,0,0,0,0,0,0,0,0,0,0,0,0,0,0,0,0,0,0,0,0,0,0,BM36,0,0,~
0,0,0,0,0,0,0,0,0,0,0)';
      PINUSE='POWER';
      NO_LOAD_CHECK='Both';
      NO_IO_CHECK='Both';
      NO_ASSERT_CHECK='TRUE';
      NO_DIR_CHECK='TRUE';
      ALLOW_CONNECT='TRUE';
    'VDD_11_S3_BM39':
      PIN_NUMBER='(0,0,0,0,0,0,0,0,0,0,0,0,0,0,0,0,0,0,0,0,0,0,0,0,0,0,BM39,0,0,~
0,0,0,0,0,0,0,0,0,0,0)';
      PINUSE='POWER';
      NO_LOAD_CHECK='Both';
      NO_IO_CHECK='Both';
      NO_ASSERT_CHECK='TRUE';
      NO_DIR_CHECK='TRUE';
      ALLOW_CONNECT='TRUE';
    'VDD_11_S3_BM41':
      PIN_NUMBER='(0,0,0,0,0,0,0,0,0,0,0,0,0,0,0,0,0,0,0,0,0,0,0,0,0,0,BM41,0,0,~
0,0,0,0,0,0,0,0,0,0,0)';
      PINUSE='POWER';
      NO_LOAD_CHECK='Both';
      NO_IO_CHECK='Both';
      NO_ASSERT_CHECK='TRUE';
      NO_DIR_CHECK='TRUE';
      ALLOW_CONNECT='TRUE';
    'VDD_11_S3_BM43':
      PIN_NUMBER='(0,0,0,0,0,0,0,0,0,0,0,0,0,0,0,0,0,0,0,0,0,0,0,0,0,0,BM43,0,0,~
0,0,0,0,0,0,0,0,0,0,0)';
      PINUSE='POWER';
      NO_LOAD_CHECK='Both';
      NO_IO_CHECK='Both';
      NO_ASSERT_CHECK='TRUE';
      NO_DIR_CHECK='TRUE';
      ALLOW_CONNECT='TRUE';
    'VDD_11_S3_BM45':
      PIN_NUMBER='(0,0,0,0,0,0,0,0,0,0,0,0,0,0,0,0,0,0,0,0,0,0,0,0,0,0,BM45,0,0,~
0,0,0,0,0,0,0,0,0,0,0)';
      PINUSE='POWER';
      NO_LOAD_CHECK='Both';
      NO_IO_CHECK='Both';
      NO_ASSERT_CHECK='TRUE';
      NO_DIR_CHECK='TRUE';
      ALLOW_CONNECT='TRUE';
    'VDD_11_S3_BM47':
      PIN_NUMBER='(0,0,0,0,0,0,0,0,0,0,0,0,0,0,0,0,0,0,0,0,0,0,0,0,0,0,BM47,0,0,~
0,0,0,0,0,0,0,0,0,0,0)';
      PINUSE='POWER';
      NO_LOAD_CHECK='Both';
      NO_IO_CHECK='Both';
      NO_ASSERT_CHECK='TRUE';
      NO_DIR_CHECK='TRUE';
      ALLOW_CONNECT='TRUE';
    'VDD_11_S3_BM49':
      PIN_NUMBER='(0,0,0,0,0,0,0,0,0,0,0,0,0,0,0,0,0,0,0,0,0,0,0,0,0,0,BM49,0,0,~
0,0,0,0,0,0,0,0,0,0,0)';
      PINUSE='POWER';
      NO_LOAD_CHECK='Both';
      NO_IO_CHECK='Both';
      NO_ASSERT_CHECK='TRUE';
      NO_DIR_CHECK='TRUE';
      ALLOW_CONNECT='TRUE';
    'VDD_11_S3_BN25':
      PIN_NUMBER='(0,0,0,0,0,0,0,0,0,0,0,0,0,0,0,0,0,0,0,0,0,0,0,0,0,0,BN25,0,0,~
0,0,0,0,0,0,0,0,0,0,0)';
      PINUSE='POWER';
      NO_LOAD_CHECK='Both';
      NO_IO_CHECK='Both';
      NO_ASSERT_CHECK='TRUE';
      NO_DIR_CHECK='TRUE';
      ALLOW_CONNECT='TRUE';
    'VDD_11_S3_BN29':
      PIN_NUMBER='(0,0,0,0,0,0,0,0,0,0,0,0,0,0,0,0,0,0,0,0,0,0,0,0,0,0,BN29,0,0,~
0,0,0,0,0,0,0,0,0,0,0)';
      PINUSE='POWER';
      NO_LOAD_CHECK='Both';
      NO_IO_CHECK='Both';
      NO_ASSERT_CHECK='TRUE';
      NO_DIR_CHECK='TRUE';
      ALLOW_CONNECT='TRUE';
    'VDD_11_S3_BN33':
      PIN_NUMBER='(0,0,0,0,0,0,0,0,0,0,0,0,0,0,0,0,0,0,0,0,0,0,0,0,0,0,BN33,0,0,~
0,0,0,0,0,0,0,0,0,0,0)';
      PINUSE='POWER';
      NO_LOAD_CHECK='Both';
      NO_IO_CHECK='Both';
      NO_ASSERT_CHECK='TRUE';
      NO_DIR_CHECK='TRUE';
      ALLOW_CONNECT='TRUE';
    'VDD_11_S3_BN40':
      PIN_NUMBER='(0,0,0,0,0,0,0,0,0,0,0,0,0,0,0,0,0,0,0,0,0,0,0,0,0,0,BN40,0,0,~
0,0,0,0,0,0,0,0,0,0,0)';
      PINUSE='POWER';
      NO_LOAD_CHECK='Both';
      NO_IO_CHECK='Both';
      NO_ASSERT_CHECK='TRUE';
      NO_DIR_CHECK='TRUE';
      ALLOW_CONNECT='TRUE';
    'VDD_11_S3_BN44':
      PIN_NUMBER='(0,0,0,0,0,0,0,0,0,0,0,0,0,0,0,0,0,0,0,0,0,0,0,0,0,0,BN44,0,0,~
0,0,0,0,0,0,0,0,0,0,0)';
      PINUSE='POWER';
      NO_LOAD_CHECK='Both';
      NO_IO_CHECK='Both';
      NO_ASSERT_CHECK='TRUE';
      NO_DIR_CHECK='TRUE';
      ALLOW_CONNECT='TRUE';
    'VDD_11_S3_BN48':
      PIN_NUMBER='(0,0,0,0,0,0,0,0,0,0,0,0,0,0,0,0,0,0,0,0,0,0,0,0,0,0,BN48,0,0,~
0,0,0,0,0,0,0,0,0,0,0)';
      PINUSE='POWER';
      NO_LOAD_CHECK='Both';
      NO_IO_CHECK='Both';
      NO_ASSERT_CHECK='TRUE';
      NO_DIR_CHECK='TRUE';
      ALLOW_CONNECT='TRUE';
    'VDD_11_S3_BP22':
      PIN_NUMBER='(0,0,0,0,0,0,0,0,0,0,0,0,0,0,0,0,0,0,0,0,0,0,0,0,0,0,BP22,0,0,~
0,0,0,0,0,0,0,0,0,0,0)';
      PINUSE='POWER';
      NO_LOAD_CHECK='Both';
      NO_IO_CHECK='Both';
      NO_ASSERT_CHECK='TRUE';
      NO_DIR_CHECK='TRUE';
      ALLOW_CONNECT='TRUE';
    'VDD_11_S3_BR4':
      PIN_NUMBER='(0,0,0,0,0,0,0,0,0,0,0,0,0,0,0,0,0,0,0,0,0,0,0,0,0,0,BR4,0,0,0~
,0,0,0,0,0,0,0,0,0,0)';
      PINUSE='POWER';
      NO_LOAD_CHECK='Both';
      NO_IO_CHECK='Both';
      NO_ASSERT_CHECK='TRUE';
      NO_DIR_CHECK='TRUE';
      ALLOW_CONNECT='TRUE';
    'VDD_11_S3_BR11':
      PIN_NUMBER='(0,0,0,0,0,0,0,0,0,0,0,0,0,0,0,0,0,0,0,0,0,0,0,0,0,0,BR11,0,0,~
0,0,0,0,0,0,0,0,0,0,0)';
      PINUSE='POWER';
      NO_LOAD_CHECK='Both';
      NO_IO_CHECK='Both';
      NO_ASSERT_CHECK='TRUE';
      NO_DIR_CHECK='TRUE';
      ALLOW_CONNECT='TRUE';
    'VDD_11_S3_BR18':
      PIN_NUMBER='(0,0,0,0,0,0,0,0,0,0,0,0,0,0,0,0,0,0,0,0,0,0,0,0,0,0,BR18,0,0,~
0,0,0,0,0,0,0,0,0,0,0)';
      PINUSE='POWER';
      NO_LOAD_CHECK='Both';
      NO_IO_CHECK='Both';
      NO_ASSERT_CHECK='TRUE';
      NO_DIR_CHECK='TRUE';
      ALLOW_CONNECT='TRUE';
    'VDD_11_S3_BV5':
      PIN_NUMBER='(0,0,0,0,0,0,0,0,0,0,0,0,0,0,0,0,0,0,0,0,0,0,0,0,0,0,BV5,0,0,0~
,0,0,0,0,0,0,0,0,0,0)';
      PINUSE='POWER';
      NO_LOAD_CHECK='Both';
      NO_IO_CHECK='Both';
      NO_ASSERT_CHECK='TRUE';
      NO_DIR_CHECK='TRUE';
      ALLOW_CONNECT='TRUE';
    'VDD_11_S3_BV12':
      PIN_NUMBER='(0,0,0,0,0,0,0,0,0,0,0,0,0,0,0,0,0,0,0,0,0,0,0,0,0,0,BV12,0,0,~
0,0,0,0,0,0,0,0,0,0,0)';
      PINUSE='POWER';
      NO_LOAD_CHECK='Both';
      NO_IO_CHECK='Both';
      NO_ASSERT_CHECK='TRUE';
      NO_DIR_CHECK='TRUE';
      ALLOW_CONNECT='TRUE';
    'VDD_11_S3_BV19':
      PIN_NUMBER='(0,0,0,0,0,0,0,0,0,0,0,0,0,0,0,0,0,0,0,0,0,0,0,0,0,0,BV19,0,0,~
0,0,0,0,0,0,0,0,0,0,0)';
      PINUSE='POWER';
      NO_LOAD_CHECK='Both';
      NO_IO_CHECK='Both';
      NO_ASSERT_CHECK='TRUE';
      NO_DIR_CHECK='TRUE';
      ALLOW_CONNECT='TRUE';
    'VDD_11_S3_BV22':
      PIN_NUMBER='(0,0,0,0,0,0,0,0,0,0,0,0,0,0,0,0,0,0,0,0,0,0,0,0,0,0,BV22,0,0,~
0,0,0,0,0,0,0,0,0,0,0)';
      PINUSE='POWER';
      NO_LOAD_CHECK='Both';
      NO_IO_CHECK='Both';
      NO_ASSERT_CHECK='TRUE';
      NO_DIR_CHECK='TRUE';
      ALLOW_CONNECT='TRUE';
    'VDD_11_S3_CA4':
      PIN_NUMBER='(0,0,0,0,0,0,0,0,0,0,0,0,0,0,0,0,0,0,0,0,0,0,0,0,0,0,CA4,0,0,0~
,0,0,0,0,0,0,0,0,0,0)';
      PINUSE='POWER';
      NO_LOAD_CHECK='Both';
      NO_IO_CHECK='Both';
      NO_ASSERT_CHECK='TRUE';
      NO_DIR_CHECK='TRUE';
      ALLOW_CONNECT='TRUE';
    'VDD_11_S3_CA11':
      PIN_NUMBER='(0,0,0,0,0,0,0,0,0,0,0,0,0,0,0,0,0,0,0,0,0,0,0,0,0,0,CA11,0,0,~
0,0,0,0,0,0,0,0,0,0,0)';
      PINUSE='POWER';
      NO_LOAD_CHECK='Both';
      NO_IO_CHECK='Both';
      NO_ASSERT_CHECK='TRUE';
      NO_DIR_CHECK='TRUE';
      ALLOW_CONNECT='TRUE';
    'VDD_11_S3_CA18':
      PIN_NUMBER='(0,0,0,0,0,0,0,0,0,0,0,0,0,0,0,0,0,0,0,0,0,0,0,0,0,0,CA18,0,0,~
0,0,0,0,0,0,0,0,0,0,0)';
      PINUSE='POWER';
      NO_LOAD_CHECK='Both';
      NO_IO_CHECK='Both';
      NO_ASSERT_CHECK='TRUE';
      NO_DIR_CHECK='TRUE';
      ALLOW_CONNECT='TRUE';
    'VDD_11_S3_CB22':
      PIN_NUMBER='(0,0,0,0,0,0,0,0,0,0,0,0,0,0,0,0,0,0,0,0,0,0,0,0,0,0,CB22,0,0,~
0,0,0,0,0,0,0,0,0,0,0)';
      PINUSE='POWER';
      NO_LOAD_CHECK='Both';
      NO_IO_CHECK='Both';
      NO_ASSERT_CHECK='TRUE';
      NO_DIR_CHECK='TRUE';
      ALLOW_CONNECT='TRUE';
    'VDD_11_S3_CD5':
      PIN_NUMBER='(0,0,0,0,0,0,0,0,0,0,0,0,0,0,0,0,0,0,0,0,0,0,0,0,0,0,CD5,0,0,0~
,0,0,0,0,0,0,0,0,0,0)';
      PINUSE='POWER';
      NO_LOAD_CHECK='Both';
      NO_IO_CHECK='Both';
      NO_ASSERT_CHECK='TRUE';
      NO_DIR_CHECK='TRUE';
      ALLOW_CONNECT='TRUE';
    'VDD_11_S3_CD12':
      PIN_NUMBER='(0,0,0,0,0,0,0,0,0,0,0,0,0,0,0,0,0,0,0,0,0,0,0,0,0,0,CD12,0,0,~
0,0,0,0,0,0,0,0,0,0,0)';
      PINUSE='POWER';
      NO_LOAD_CHECK='Both';
      NO_IO_CHECK='Both';
      NO_ASSERT_CHECK='TRUE';
      NO_DIR_CHECK='TRUE';
      ALLOW_CONNECT='TRUE';
    'VDD_11_S3_CD19':
      PIN_NUMBER='(0,0,0,0,0,0,0,0,0,0,0,0,0,0,0,0,0,0,0,0,0,0,0,0,0,0,CD19,0,0,~
0,0,0,0,0,0,0,0,0,0,0)';
      PINUSE='POWER';
      NO_LOAD_CHECK='Both';
      NO_IO_CHECK='Both';
      NO_ASSERT_CHECK='TRUE';
      NO_DIR_CHECK='TRUE';
      ALLOW_CONNECT='TRUE';
    'VDD_11_S3_CF22':
      PIN_NUMBER='(0,0,0,0,0,0,0,0,0,0,0,0,0,0,0,0,0,0,0,0,0,0,0,0,0,0,CF22,0,0,~
0,0,0,0,0,0,0,0,0,0,0)';
      PINUSE='POWER';
      NO_LOAD_CHECK='Both';
      NO_IO_CHECK='Both';
      NO_ASSERT_CHECK='TRUE';
      NO_DIR_CHECK='TRUE';
      ALLOW_CONNECT='TRUE';
    'VDD_11_S3_CG4':
      PIN_NUMBER='(0,0,0,0,0,0,0,0,0,0,0,0,0,0,0,0,0,0,0,0,0,0,0,0,0,0,CG4,0,0,0~
,0,0,0,0,0,0,0,0,0,0)';
      PINUSE='POWER';
      NO_LOAD_CHECK='Both';
      NO_IO_CHECK='Both';
      NO_ASSERT_CHECK='TRUE';
      NO_DIR_CHECK='TRUE';
      ALLOW_CONNECT='TRUE';
    'VDD_11_S3_CG11':
      PIN_NUMBER='(0,0,0,0,0,0,0,0,0,0,0,0,0,0,0,0,0,0,0,0,0,0,0,0,0,0,CG11,0,0,~
0,0,0,0,0,0,0,0,0,0,0)';
      PINUSE='POWER';
      NO_LOAD_CHECK='Both';
      NO_IO_CHECK='Both';
      NO_ASSERT_CHECK='TRUE';
      NO_DIR_CHECK='TRUE';
      ALLOW_CONNECT='TRUE';
    'VDD_11_S3_CG18':
      PIN_NUMBER='(0,0,0,0,0,0,0,0,0,0,0,0,0,0,0,0,0,0,0,0,0,0,0,0,0,0,CG18,0,0,~
0,0,0,0,0,0,0,0,0,0,0)';
      PINUSE='POWER';
      NO_LOAD_CHECK='Both';
      NO_IO_CHECK='Both';
      NO_ASSERT_CHECK='TRUE';
      NO_DIR_CHECK='TRUE';
      ALLOW_CONNECT='TRUE';
    'VDD_11_S3_CJ22':
      PIN_NUMBER='(0,0,0,0,0,0,0,0,0,0,0,0,0,0,0,0,0,0,0,0,0,0,0,0,0,0,CJ22,0,0,~
0,0,0,0,0,0,0,0,0,0,0)';
      PINUSE='POWER';
      NO_LOAD_CHECK='Both';
      NO_IO_CHECK='Both';
      NO_ASSERT_CHECK='TRUE';
      NO_DIR_CHECK='TRUE';
      ALLOW_CONNECT='TRUE';
    'VDD_11_S3_CK5':
      PIN_NUMBER='(0,0,0,0,0,0,0,0,0,0,0,0,0,0,0,0,0,0,0,0,0,0,0,0,0,0,CK5,0,0,0~
,0,0,0,0,0,0,0,0,0,0)';
      PINUSE='POWER';
      NO_LOAD_CHECK='Both';
      NO_IO_CHECK='Both';
      NO_ASSERT_CHECK='TRUE';
      NO_DIR_CHECK='TRUE';
      ALLOW_CONNECT='TRUE';
    'VDD_11_S3_CK12':
      PIN_NUMBER='(0,0,0,0,0,0,0,0,0,0,0,0,0,0,0,0,0,0,0,0,0,0,0,0,0,0,CK12,0,0,~
0,0,0,0,0,0,0,0,0,0,0)';
      PINUSE='POWER';
      NO_LOAD_CHECK='Both';
      NO_IO_CHECK='Both';
      NO_ASSERT_CHECK='TRUE';
      NO_DIR_CHECK='TRUE';
      ALLOW_CONNECT='TRUE';
    'VDD_11_S3_CK19':
      PIN_NUMBER='(0,0,0,0,0,0,0,0,0,0,0,0,0,0,0,0,0,0,0,0,0,0,0,0,0,0,CK19,0,0,~
0,0,0,0,0,0,0,0,0,0,0)';
      PINUSE='POWER';
      NO_LOAD_CHECK='Both';
      NO_IO_CHECK='Both';
      NO_ASSERT_CHECK='TRUE';
      NO_DIR_CHECK='TRUE';
      ALLOW_CONNECT='TRUE';
    'VDD_11_S3_CM22':
      PIN_NUMBER='(0,0,0,0,0,0,0,0,0,0,0,0,0,0,0,0,0,0,0,0,0,0,0,0,0,0,CM22,0,0,~
0,0,0,0,0,0,0,0,0,0,0)';
      PINUSE='POWER';
      NO_LOAD_CHECK='Both';
      NO_IO_CHECK='Both';
      NO_ASSERT_CHECK='TRUE';
      NO_DIR_CHECK='TRUE';
      ALLOW_CONNECT='TRUE';
    'VDD_11_S3_CN4':
      PIN_NUMBER='(0,0,0,0,0,0,0,0,0,0,0,0,0,0,0,0,0,0,0,0,0,0,0,0,0,0,CN4,0,0,0~
,0,0,0,0,0,0,0,0,0,0)';
      PINUSE='POWER';
      NO_LOAD_CHECK='Both';
      NO_IO_CHECK='Both';
      NO_ASSERT_CHECK='TRUE';
      NO_DIR_CHECK='TRUE';
      ALLOW_CONNECT='TRUE';
    'VDD_11_S3_CN11':
      PIN_NUMBER='(0,0,0,0,0,0,0,0,0,0,0,0,0,0,0,0,0,0,0,0,0,0,0,0,0,0,CN11,0,0,~
0,0,0,0,0,0,0,0,0,0,0)';
      PINUSE='POWER';
      NO_LOAD_CHECK='Both';
      NO_IO_CHECK='Both';
      NO_ASSERT_CHECK='TRUE';
      NO_DIR_CHECK='TRUE';
      ALLOW_CONNECT='TRUE';
    'VDD_11_S3_CN18':
      PIN_NUMBER='(0,0,0,0,0,0,0,0,0,0,0,0,0,0,0,0,0,0,0,0,0,0,0,0,0,0,CN18,0,0,~
0,0,0,0,0,0,0,0,0,0,0)';
      PINUSE='POWER';
      NO_LOAD_CHECK='Both';
      NO_IO_CHECK='Both';
      NO_ASSERT_CHECK='TRUE';
      NO_DIR_CHECK='TRUE';
      ALLOW_CONNECT='TRUE';
    'VDD_11_S3_CT5':
      PIN_NUMBER='(0,0,0,0,0,0,0,0,0,0,0,0,0,0,0,0,0,0,0,0,0,0,0,0,0,0,CT5,0,0,0~
,0,0,0,0,0,0,0,0,0,0)';
      PINUSE='POWER';
      NO_LOAD_CHECK='Both';
      NO_IO_CHECK='Both';
      NO_ASSERT_CHECK='TRUE';
      NO_DIR_CHECK='TRUE';
      ALLOW_CONNECT='TRUE';
    'VDD_18_S5_AU54':
      PIN_NUMBER='(0,0,0,0,0,0,0,0,0,0,0,0,0,0,0,0,0,0,0,0,0,0,0,0,0,0,AU54,0,0,~
0,0,0,0,0,0,0,0,0,0,0)';
      PINUSE='POWER';
      NO_LOAD_CHECK='Both';
      NO_IO_CHECK='Both';
      NO_ASSERT_CHECK='TRUE';
      NO_DIR_CHECK='TRUE';
      ALLOW_CONNECT='TRUE';
    'VDD_18_S5_AR52':
      PIN_NUMBER='(0,0,0,0,0,0,0,0,0,0,0,0,0,0,0,0,0,0,0,0,0,0,0,0,0,0,AR52,0,0,~
0,0,0,0,0,0,0,0,0,0,0)';
      PINUSE='POWER';
      NO_LOAD_CHECK='Both';
      NO_IO_CHECK='Both';
      NO_ASSERT_CHECK='TRUE';
      NO_DIR_CHECK='TRUE';
      ALLOW_CONNECT='TRUE';
    'VDD_18_S5_AR54':
      PIN_NUMBER='(0,0,0,0,0,0,0,0,0,0,0,0,0,0,0,0,0,0,0,0,0,0,0,0,0,0,AR54,0,0,~
0,0,0,0,0,0,0,0,0,0,0)';
      PINUSE='POWER';
      NO_LOAD_CHECK='Both';
      NO_IO_CHECK='Both';
      NO_ASSERT_CHECK='TRUE';
      NO_DIR_CHECK='TRUE';
      ALLOW_CONNECT='TRUE';
    'VDD_18_S5_AT51':
      PIN_NUMBER='(0,0,0,0,0,0,0,0,0,0,0,0,0,0,0,0,0,0,0,0,0,0,0,0,0,0,AT51,0,0,~
0,0,0,0,0,0,0,0,0,0,0)';
      PINUSE='POWER';
      NO_LOAD_CHECK='Both';
      NO_IO_CHECK='Both';
      NO_ASSERT_CHECK='TRUE';
      NO_DIR_CHECK='TRUE';
      ALLOW_CONNECT='TRUE';
    'VDD_18_S5_AT53':
      PIN_NUMBER='(0,0,0,0,0,0,0,0,0,0,0,0,0,0,0,0,0,0,0,0,0,0,0,0,0,0,AT53,0,0,~
0,0,0,0,0,0,0,0,0,0,0)';
      PINUSE='POWER';
      NO_LOAD_CHECK='Both';
      NO_IO_CHECK='Both';
      NO_ASSERT_CHECK='TRUE';
      NO_DIR_CHECK='TRUE';
      ALLOW_CONNECT='TRUE';
    'VDD_18_S5_AU50':
      PIN_NUMBER='(0,0,0,0,0,0,0,0,0,0,0,0,0,0,0,0,0,0,0,0,0,0,0,0,0,0,AU50,0,0,~
0,0,0,0,0,0,0,0,0,0,0)';
      PINUSE='POWER';
      NO_LOAD_CHECK='Both';
      NO_IO_CHECK='Both';
      NO_ASSERT_CHECK='TRUE';
      NO_DIR_CHECK='TRUE';
      ALLOW_CONNECT='TRUE';
    'VDD_18_S5_AU52':
      PIN_NUMBER='(0,0,0,0,0,0,0,0,0,0,0,0,0,0,0,0,0,0,0,0,0,0,0,0,0,0,AU52,0,0,~
0,0,0,0,0,0,0,0,0,0,0)';
      PINUSE='POWER';
      NO_LOAD_CHECK='Both';
      NO_IO_CHECK='Both';
      NO_ASSERT_CHECK='TRUE';
      NO_DIR_CHECK='TRUE';
      ALLOW_CONNECT='TRUE';
    'VDD_18_S5_AV49':
      PIN_NUMBER='(0,0,0,0,0,0,0,0,0,0,0,0,0,0,0,0,0,0,0,0,0,0,0,0,0,0,AV49,0,0,~
0,0,0,0,0,0,0,0,0,0,0)';
      PINUSE='POWER';
      NO_LOAD_CHECK='Both';
      NO_IO_CHECK='Both';
      NO_ASSERT_CHECK='TRUE';
      NO_DIR_CHECK='TRUE';
      ALLOW_CONNECT='TRUE';
    'VDD_18_S5_AV51':
      PIN_NUMBER='(0,0,0,0,0,0,0,0,0,0,0,0,0,0,0,0,0,0,0,0,0,0,0,0,0,0,AV51,0,0,~
0,0,0,0,0,0,0,0,0,0,0)';
      PINUSE='POWER';
      NO_LOAD_CHECK='Both';
      NO_IO_CHECK='Both';
      NO_ASSERT_CHECK='TRUE';
      NO_DIR_CHECK='TRUE';
      ALLOW_CONNECT='TRUE';
    'VDD_18_S5_AV53':
      PIN_NUMBER='(0,0,0,0,0,0,0,0,0,0,0,0,0,0,0,0,0,0,0,0,0,0,0,0,0,0,AV53,0,0,~
0,0,0,0,0,0,0,0,0,0,0)';
      PINUSE='POWER';
      NO_LOAD_CHECK='Both';
      NO_IO_CHECK='Both';
      NO_ASSERT_CHECK='TRUE';
      NO_DIR_CHECK='TRUE';
      ALLOW_CONNECT='TRUE';
    'VDD_18_S5_AW50':
      PIN_NUMBER='(0,0,0,0,0,0,0,0,0,0,0,0,0,0,0,0,0,0,0,0,0,0,0,0,0,0,AW50,0,0,~
0,0,0,0,0,0,0,0,0,0,0)';
      PINUSE='POWER';
      NO_LOAD_CHECK='Both';
      NO_IO_CHECK='Both';
      NO_ASSERT_CHECK='TRUE';
      NO_DIR_CHECK='TRUE';
      ALLOW_CONNECT='TRUE';
    'VDD_18_S5_BC52':
      PIN_NUMBER='(0,0,0,0,0,0,0,0,0,0,0,0,0,0,0,0,0,0,0,0,0,0,0,0,0,0,BC52,0,0,~
0,0,0,0,0,0,0,0,0,0,0)';
      PINUSE='POWER';
      NO_LOAD_CHECK='Both';
      NO_IO_CHECK='Both';
      NO_ASSERT_CHECK='TRUE';
      NO_DIR_CHECK='TRUE';
      ALLOW_CONNECT='TRUE';
    'VDD_18_S5_BC54':
      PIN_NUMBER='(0,0,0,0,0,0,0,0,0,0,0,0,0,0,0,0,0,0,0,0,0,0,0,0,0,0,BC54,0,0,~
0,0,0,0,0,0,0,0,0,0,0)';
      PINUSE='POWER';
      NO_LOAD_CHECK='Both';
      NO_IO_CHECK='Both';
      NO_ASSERT_CHECK='TRUE';
      NO_DIR_CHECK='TRUE';
      ALLOW_CONNECT='TRUE';
    'VDD_18_S5_AW52':
      PIN_NUMBER='(0,0,0,0,0,0,0,0,0,0,0,0,0,0,0,0,0,0,0,0,0,0,0,0,0,0,AW52,0,0,~
0,0,0,0,0,0,0,0,0,0,0)';
      PINUSE='POWER';
      NO_LOAD_CHECK='Both';
      NO_IO_CHECK='Both';
      NO_ASSERT_CHECK='TRUE';
      NO_DIR_CHECK='TRUE';
      ALLOW_CONNECT='TRUE';
    'VDD_18_S5_AW54':
      PIN_NUMBER='(0,0,0,0,0,0,0,0,0,0,0,0,0,0,0,0,0,0,0,0,0,0,0,0,0,0,AW54,0,0,~
0,0,0,0,0,0,0,0,0,0,0)';
      PINUSE='POWER';
      NO_LOAD_CHECK='Both';
      NO_IO_CHECK='Both';
      NO_ASSERT_CHECK='TRUE';
      NO_DIR_CHECK='TRUE';
      ALLOW_CONNECT='TRUE';
    'VDD_18_S5_AY51':
      PIN_NUMBER='(0,0,0,0,0,0,0,0,0,0,0,0,0,0,0,0,0,0,0,0,0,0,0,0,0,0,AY51,0,0,~
0,0,0,0,0,0,0,0,0,0,0)';
      PINUSE='POWER';
      NO_LOAD_CHECK='Both';
      NO_IO_CHECK='Both';
      NO_ASSERT_CHECK='TRUE';
      NO_DIR_CHECK='TRUE';
      ALLOW_CONNECT='TRUE';
    'VDD_18_S5_AY53':
      PIN_NUMBER='(0,0,0,0,0,0,0,0,0,0,0,0,0,0,0,0,0,0,0,0,0,0,0,0,0,0,AY53,0,0,~
0,0,0,0,0,0,0,0,0,0,0)';
      PINUSE='POWER';
      NO_LOAD_CHECK='Both';
      NO_IO_CHECK='Both';
      NO_ASSERT_CHECK='TRUE';
      NO_DIR_CHECK='TRUE';
      ALLOW_CONNECT='TRUE';
    'VDD_18_S5_BA50':
      PIN_NUMBER='(0,0,0,0,0,0,0,0,0,0,0,0,0,0,0,0,0,0,0,0,0,0,0,0,0,0,BA50,0,0,~
0,0,0,0,0,0,0,0,0,0,0)';
      PINUSE='POWER';
      NO_LOAD_CHECK='Both';
      NO_IO_CHECK='Both';
      NO_ASSERT_CHECK='TRUE';
      NO_DIR_CHECK='TRUE';
      ALLOW_CONNECT='TRUE';
    'VDD_18_S5_BA52':
      PIN_NUMBER='(0,0,0,0,0,0,0,0,0,0,0,0,0,0,0,0,0,0,0,0,0,0,0,0,0,0,BA52,0,0,~
0,0,0,0,0,0,0,0,0,0,0)';
      PINUSE='POWER';
      NO_LOAD_CHECK='Both';
      NO_IO_CHECK='Both';
      NO_ASSERT_CHECK='TRUE';
      NO_DIR_CHECK='TRUE';
      ALLOW_CONNECT='TRUE';
    'VDD_18_S5_BA54':
      PIN_NUMBER='(0,0,0,0,0,0,0,0,0,0,0,0,0,0,0,0,0,0,0,0,0,0,0,0,0,0,BA54,0,0,~
0,0,0,0,0,0,0,0,0,0,0)';
      PINUSE='POWER';
      NO_LOAD_CHECK='Both';
      NO_IO_CHECK='Both';
      NO_ASSERT_CHECK='TRUE';
      NO_DIR_CHECK='TRUE';
      ALLOW_CONNECT='TRUE';
    'VDD_18_S5_BB51':
      PIN_NUMBER='(0,0,0,0,0,0,0,0,0,0,0,0,0,0,0,0,0,0,0,0,0,0,0,0,0,0,BB51,0,0,~
0,0,0,0,0,0,0,0,0,0,0)';
      PINUSE='POWER';
      NO_LOAD_CHECK='Both';
      NO_IO_CHECK='Both';
      NO_ASSERT_CHECK='TRUE';
      NO_DIR_CHECK='TRUE';
      ALLOW_CONNECT='TRUE';
    'VDD_18_S5_BB53':
      PIN_NUMBER='(0,0,0,0,0,0,0,0,0,0,0,0,0,0,0,0,0,0,0,0,0,0,0,0,0,0,BB53,0,0,~
0,0,0,0,0,0,0,0,0,0,0)';
      PINUSE='POWER';
      NO_LOAD_CHECK='Both';
      NO_IO_CHECK='Both';
      NO_ASSERT_CHECK='TRUE';
      NO_DIR_CHECK='TRUE';
      ALLOW_CONNECT='TRUE';
    'VDD_11_S3_CT12':
      PIN_NUMBER='(0,0,0,0,0,0,0,0,0,0,0,0,0,0,0,0,0,0,0,0,0,0,0,0,0,0,CT12,0,0,~
0,0,0,0,0,0,0,0,0,0,0)';
      PINUSE='POWER';
      NO_LOAD_CHECK='Both';
      NO_IO_CHECK='Both';
      NO_ASSERT_CHECK='TRUE';
      NO_DIR_CHECK='TRUE';
      ALLOW_CONNECT='TRUE';
    'VDD_33_S5_BN52':
      PIN_NUMBER='(0,0,0,0,0,0,0,0,0,0,0,0,0,0,0,0,0,0,0,0,0,0,0,0,0,0,BN52,0,0,~
0,0,0,0,0,0,0,0,0,0,0)';
      PINUSE='POWER';
      NO_LOAD_CHECK='Both';
      NO_IO_CHECK='Both';
      NO_ASSERT_CHECK='TRUE';
      NO_DIR_CHECK='TRUE';
      ALLOW_CONNECT='TRUE';
    'VDD_33_S5_BP51':
      PIN_NUMBER='(0,0,0,0,0,0,0,0,0,0,0,0,0,0,0,0,0,0,0,0,0,0,0,0,0,0,BP51,0,0,~
0,0,0,0,0,0,0,0,0,0,0)';
      PINUSE='POWER';
      NO_LOAD_CHECK='Both';
      NO_IO_CHECK='Both';
      NO_ASSERT_CHECK='TRUE';
      NO_DIR_CHECK='TRUE';
      ALLOW_CONNECT='TRUE';
    'VDDIO_AUDIO':
      PIN_NUMBER='(0,0,0,0,0,0,0,0,0,0,0,0,0,0,0,0,0,0,0,0,0,0,0,0,0,0,BH27,0,0,~
0,0,0,0,0,0,0,0,0,0,0)';
      PINUSE='POWER';
      NO_LOAD_CHECK='Both';
      NO_IO_CHECK='Both';
      NO_ASSERT_CHECK='TRUE';
      NO_DIR_CHECK='TRUE';
      ALLOW_CONNECT='TRUE';
    'VDDBT_RTC_G':
      PIN_NUMBER='(0,0,0,0,0,0,0,0,0,0,0,0,0,0,0,0,0,0,0,0,0,0,0,0,0,0,BN23,0,0,~
0,0,0,0,0,0,0,0,0,0,0)';
      PINUSE='POWER';
      NO_LOAD_CHECK='Both';
      NO_IO_CHECK='Both';
      NO_ASSERT_CHECK='TRUE';
      NO_DIR_CHECK='TRUE';
      ALLOW_CONNECT='TRUE';
    'VDDIO_DG71':
      PIN_NUMBER='(0,0,0,0,0,0,0,0,0,0,0,0,0,0,0,0,0,0,0,0,0,0,0,0,0,0,DG71,0,0,~
0,0,0,0,0,0,0,0,0,0,0)';
      PINUSE='POWER';
      NO_LOAD_CHECK='Both';
      NO_IO_CHECK='Both';
      NO_ASSERT_CHECK='TRUE';
      NO_DIR_CHECK='TRUE';
      ALLOW_CONNECT='TRUE';
    'VDDIO_DG64':
      PIN_NUMBER='(0,0,0,0,0,0,0,0,0,0,0,0,0,0,0,0,0,0,0,0,0,0,0,0,0,0,DG64,0,0,~
0,0,0,0,0,0,0,0,0,0,0)';
      PINUSE='POWER';
      NO_LOAD_CHECK='Both';
      NO_IO_CHECK='Both';
      NO_ASSERT_CHECK='TRUE';
      NO_DIR_CHECK='TRUE';
      ALLOW_CONNECT='TRUE';
    'VDDIO_DE72':
      PIN_NUMBER='(0,0,0,0,0,0,0,0,0,0,0,0,0,0,0,0,0,0,0,0,0,0,0,0,0,0,DE72,0,0,~
0,0,0,0,0,0,0,0,0,0,0)';
      PINUSE='POWER';
      NO_LOAD_CHECK='Both';
      NO_IO_CHECK='Both';
      NO_ASSERT_CHECK='TRUE';
      NO_DIR_CHECK='TRUE';
      ALLOW_CONNECT='TRUE';
    'VDDIO_DE65':
      PIN_NUMBER='(0,0,0,0,0,0,0,0,0,0,0,0,0,0,0,0,0,0,0,0,0,0,0,0,0,0,DE65,0,0,~
0,0,0,0,0,0,0,0,0,0,0)';
      PINUSE='POWER';
      NO_LOAD_CHECK='Both';
      NO_IO_CHECK='Both';
      NO_ASSERT_CHECK='TRUE';
      NO_DIR_CHECK='TRUE';
      ALLOW_CONNECT='TRUE';
    'VDDIO_DE58':
      PIN_NUMBER='(0,0,0,0,0,0,0,0,0,0,0,0,0,0,0,0,0,0,0,0,0,0,0,0,0,0,DE58,0,0,~
0,0,0,0,0,0,0,0,0,0,0)';
      PINUSE='POWER';
      NO_LOAD_CHECK='Both';
      NO_IO_CHECK='Both';
      NO_ASSERT_CHECK='TRUE';
      NO_DIR_CHECK='TRUE';
      ALLOW_CONNECT='TRUE';
    'VDDIO_DB71':
      PIN_NUMBER='(0,0,0,0,0,0,0,0,0,0,0,0,0,0,0,0,0,0,0,0,0,0,0,0,0,0,DB71,0,0,~
0,0,0,0,0,0,0,0,0,0,0)';
      PINUSE='POWER';
      NO_LOAD_CHECK='Both';
      NO_IO_CHECK='Both';
      NO_ASSERT_CHECK='TRUE';
      NO_DIR_CHECK='TRUE';
      ALLOW_CONNECT='TRUE';
    'VDDIO_DB64':
      PIN_NUMBER='(0,0,0,0,0,0,0,0,0,0,0,0,0,0,0,0,0,0,0,0,0,0,0,0,0,0,DB64,0,0,~
0,0,0,0,0,0,0,0,0,0,0)';
      PINUSE='POWER';
      NO_LOAD_CHECK='Both';
      NO_IO_CHECK='Both';
      NO_ASSERT_CHECK='TRUE';
      NO_DIR_CHECK='TRUE';
      ALLOW_CONNECT='TRUE';
    'VDDIO_DB57':
      PIN_NUMBER='(0,0,0,0,0,0,0,0,0,0,0,0,0,0,0,0,0,0,0,0,0,0,0,0,0,0,DB57,0,0,~
0,0,0,0,0,0,0,0,0,0,0)';
      PINUSE='POWER';
      NO_LOAD_CHECK='Both';
      NO_IO_CHECK='Both';
      NO_ASSERT_CHECK='TRUE';
      NO_DIR_CHECK='TRUE';
      ALLOW_CONNECT='TRUE';
    'VDDIO_CY54':
      PIN_NUMBER='(0,0,0,0,0,0,0,0,0,0,0,0,0,0,0,0,0,0,0,0,0,0,0,0,0,0,CY54,0,0,~
0,0,0,0,0,0,0,0,0,0,0)';
      PINUSE='POWER';
      NO_LOAD_CHECK='Both';
      NO_IO_CHECK='Both';
      NO_ASSERT_CHECK='TRUE';
      NO_DIR_CHECK='TRUE';
      ALLOW_CONNECT='TRUE';
    'VDDIO_CW72':
      PIN_NUMBER='(0,0,0,0,0,0,0,0,0,0,0,0,0,0,0,0,0,0,0,0,0,0,0,0,0,0,CW72,0,0,~
0,0,0,0,0,0,0,0,0,0,0)';
      PINUSE='POWER';
      NO_LOAD_CHECK='Both';
      NO_IO_CHECK='Both';
      NO_ASSERT_CHECK='TRUE';
      NO_DIR_CHECK='TRUE';
      ALLOW_CONNECT='TRUE';
    'VDDIO_CW65':
      PIN_NUMBER='(0,0,0,0,0,0,0,0,0,0,0,0,0,0,0,0,0,0,0,0,0,0,0,0,0,0,CW65,0,0,~
0,0,0,0,0,0,0,0,0,0,0)';
      PINUSE='POWER';
      NO_LOAD_CHECK='Both';
      NO_IO_CHECK='Both';
      NO_ASSERT_CHECK='TRUE';
      NO_DIR_CHECK='TRUE';
      ALLOW_CONNECT='TRUE';
    'VDDIO_CW58':
      PIN_NUMBER='(0,0,0,0,0,0,0,0,0,0,0,0,0,0,0,0,0,0,0,0,0,0,0,0,0,0,CW58,0,0,~
0,0,0,0,0,0,0,0,0,0,0)';
      PINUSE='POWER';
      NO_LOAD_CHECK='Both';
      NO_IO_CHECK='Both';
      NO_ASSERT_CHECK='TRUE';
      NO_DIR_CHECK='TRUE';
      ALLOW_CONNECT='TRUE';
    'VDDIO_CT71':
      PIN_NUMBER='(0,0,0,0,0,0,0,0,0,0,0,0,0,0,0,0,0,0,0,0,0,0,0,0,0,0,CT71,0,0,~
0,0,0,0,0,0,0,0,0,0,0)';
      PINUSE='POWER';
      NO_LOAD_CHECK='Both';
      NO_IO_CHECK='Both';
      NO_ASSERT_CHECK='TRUE';
      NO_DIR_CHECK='TRUE';
      ALLOW_CONNECT='TRUE';
    'VDDIO_CT64':
      PIN_NUMBER='(0,0,0,0,0,0,0,0,0,0,0,0,0,0,0,0,0,0,0,0,0,0,0,0,0,0,CT64,0,0,~
0,0,0,0,0,0,0,0,0,0,0)';
      PINUSE='POWER';
      NO_LOAD_CHECK='Both';
      NO_IO_CHECK='Both';
      NO_ASSERT_CHECK='TRUE';
      NO_DIR_CHECK='TRUE';
      ALLOW_CONNECT='TRUE';
    'VDD_11_S3_DG5':
      PIN_NUMBER='(0,0,0,0,0,0,0,0,0,0,0,0,0,0,0,0,0,0,0,0,0,0,0,0,0,0,DG5,0,0,0~
,0,0,0,0,0,0,0,0,0,0)';
      PINUSE='POWER';
      NO_LOAD_CHECK='Both';
      NO_IO_CHECK='Both';
      NO_ASSERT_CHECK='TRUE';
      NO_DIR_CHECK='TRUE';
      ALLOW_CONNECT='TRUE';
    'VDD_11_S3_DE18':
      PIN_NUMBER='(0,0,0,0,0,0,0,0,0,0,0,0,0,0,0,0,0,0,0,0,0,0,0,0,0,0,DE18,0,0,~
0,0,0,0,0,0,0,0,0,0,0)';
      PINUSE='POWER';
      NO_LOAD_CHECK='Both';
      NO_IO_CHECK='Both';
      NO_ASSERT_CHECK='TRUE';
      NO_DIR_CHECK='TRUE';
      ALLOW_CONNECT='TRUE';
    'VDD_11_S3_DE11':
      PIN_NUMBER='(0,0,0,0,0,0,0,0,0,0,0,0,0,0,0,0,0,0,0,0,0,0,0,0,0,0,DE11,0,0,~
0,0,0,0,0,0,0,0,0,0,0)';
      PINUSE='POWER';
      NO_LOAD_CHECK='Both';
      NO_IO_CHECK='Both';
      NO_ASSERT_CHECK='TRUE';
      NO_DIR_CHECK='TRUE';
      ALLOW_CONNECT='TRUE';
    'VDD_11_S3_DE4':
      PIN_NUMBER='(0,0,0,0,0,0,0,0,0,0,0,0,0,0,0,0,0,0,0,0,0,0,0,0,0,0,DE4,0,0,0~
,0,0,0,0,0,0,0,0,0,0)';
      PINUSE='POWER';
      NO_LOAD_CHECK='Both';
      NO_IO_CHECK='Both';
      NO_ASSERT_CHECK='TRUE';
      NO_DIR_CHECK='TRUE';
      ALLOW_CONNECT='TRUE';
    'VDD_11_S3_DB19':
      PIN_NUMBER='(0,0,0,0,0,0,0,0,0,0,0,0,0,0,0,0,0,0,0,0,0,0,0,0,0,0,DB19,0,0,~
0,0,0,0,0,0,0,0,0,0,0)';
      PINUSE='POWER';
      NO_LOAD_CHECK='Both';
      NO_IO_CHECK='Both';
      NO_ASSERT_CHECK='TRUE';
      NO_DIR_CHECK='TRUE';
      ALLOW_CONNECT='TRUE';
    'VDD_11_S3_DB12':
      PIN_NUMBER='(0,0,0,0,0,0,0,0,0,0,0,0,0,0,0,0,0,0,0,0,0,0,0,0,0,0,DB12,0,0,~
0,0,0,0,0,0,0,0,0,0,0)';
      PINUSE='POWER';
      NO_LOAD_CHECK='Both';
      NO_IO_CHECK='Both';
      NO_ASSERT_CHECK='TRUE';
      NO_DIR_CHECK='TRUE';
      ALLOW_CONNECT='TRUE';
    'VDD_11_S3_DB5':
      PIN_NUMBER='(0,0,0,0,0,0,0,0,0,0,0,0,0,0,0,0,0,0,0,0,0,0,0,0,0,0,DB5,0,0,0~
,0,0,0,0,0,0,0,0,0,0)';
      PINUSE='POWER';
      NO_LOAD_CHECK='Both';
      NO_IO_CHECK='Both';
      NO_ASSERT_CHECK='TRUE';
      NO_DIR_CHECK='TRUE';
      ALLOW_CONNECT='TRUE';
    'VDD_11_S3_CY22':
      PIN_NUMBER='(0,0,0,0,0,0,0,0,0,0,0,0,0,0,0,0,0,0,0,0,0,0,0,0,0,0,CY22,0,0,~
0,0,0,0,0,0,0,0,0,0,0)';
      PINUSE='POWER';
      NO_LOAD_CHECK='Both';
      NO_IO_CHECK='Both';
      NO_ASSERT_CHECK='TRUE';
      NO_DIR_CHECK='TRUE';
      ALLOW_CONNECT='TRUE';
    'VDD_11_S3_CW18':
      PIN_NUMBER='(0,0,0,0,0,0,0,0,0,0,0,0,0,0,0,0,0,0,0,0,0,0,0,0,0,0,CW18,0,0,~
0,0,0,0,0,0,0,0,0,0,0)';
      PINUSE='POWER';
      NO_LOAD_CHECK='Both';
      NO_IO_CHECK='Both';
      NO_ASSERT_CHECK='TRUE';
      NO_DIR_CHECK='TRUE';
      ALLOW_CONNECT='TRUE';
    'VDD_11_S3_CW11':
      PIN_NUMBER='(0,0,0,0,0,0,0,0,0,0,0,0,0,0,0,0,0,0,0,0,0,0,0,0,0,0,CW11,0,0,~
0,0,0,0,0,0,0,0,0,0,0)';
      PINUSE='POWER';
      NO_LOAD_CHECK='Both';
      NO_IO_CHECK='Both';
      NO_ASSERT_CHECK='TRUE';
      NO_DIR_CHECK='TRUE';
      ALLOW_CONNECT='TRUE';
    'VDD_11_S3_CW4':
      PIN_NUMBER='(0,0,0,0,0,0,0,0,0,0,0,0,0,0,0,0,0,0,0,0,0,0,0,0,0,0,CW4,0,0,0~
,0,0,0,0,0,0,0,0,0,0)';
      PINUSE='POWER';
      NO_LOAD_CHECK='Both';
      NO_IO_CHECK='Both';
      NO_ASSERT_CHECK='TRUE';
      NO_DIR_CHECK='TRUE';
      ALLOW_CONNECT='TRUE';
    'VDD_11_S3_CT22':
      PIN_NUMBER='(0,0,0,0,0,0,0,0,0,0,0,0,0,0,0,0,0,0,0,0,0,0,0,0,0,0,CT22,0,0,~
0,0,0,0,0,0,0,0,0,0,0)';
      PINUSE='POWER';
      NO_LOAD_CHECK='Both';
      NO_IO_CHECK='Both';
      NO_ASSERT_CHECK='TRUE';
      NO_DIR_CHECK='TRUE';
      ALLOW_CONNECT='TRUE';
    'VDD_11_S3_CT19':
      PIN_NUMBER='(0,0,0,0,0,0,0,0,0,0,0,0,0,0,0,0,0,0,0,0,0,0,0,0,0,0,CT19,0,0,~
0,0,0,0,0,0,0,0,0,0,0)';
      PINUSE='POWER';
      NO_LOAD_CHECK='Both';
      NO_IO_CHECK='Both';
      NO_ASSERT_CHECK='TRUE';
      NO_DIR_CHECK='TRUE';
      ALLOW_CONNECT='TRUE';
    'VSS_H37':
      PIN_NUMBER='(0,0,0,0,0,0,0,0,0,0,0,0,0,0,0,0,0,0,0,0,0,0,0,0,0,0,0,H37,0,0~
,0,0,0,0,0,0,0,0,0,0)';
      PINUSE='POWER';
      NO_LOAD_CHECK='Both';
      NO_IO_CHECK='Both';
      NO_ASSERT_CHECK='TRUE';
      NO_DIR_CHECK='TRUE';
      ALLOW_CONNECT='TRUE';
    'VSS_H39':
      PIN_NUMBER='(0,0,0,0,0,0,0,0,0,0,0,0,0,0,0,0,0,0,0,0,0,0,0,0,0,0,0,H39,0,0~
,0,0,0,0,0,0,0,0,0,0)';
      PINUSE='POWER';
      NO_LOAD_CHECK='Both';
      NO_IO_CHECK='Both';
      NO_ASSERT_CHECK='TRUE';
      NO_DIR_CHECK='TRUE';
      ALLOW_CONNECT='TRUE';
    'VSS_H42':
      PIN_NUMBER='(0,0,0,0,0,0,0,0,0,0,0,0,0,0,0,0,0,0,0,0,0,0,0,0,0,0,0,H42,0,0~
,0,0,0,0,0,0,0,0,0,0)';
      PINUSE='POWER';
      NO_LOAD_CHECK='Both';
      NO_IO_CHECK='Both';
      NO_ASSERT_CHECK='TRUE';
      NO_DIR_CHECK='TRUE';
      ALLOW_CONNECT='TRUE';
    'VSS_H45':
      PIN_NUMBER='(0,0,0,0,0,0,0,0,0,0,0,0,0,0,0,0,0,0,0,0,0,0,0,0,0,0,0,H45,0,0~
,0,0,0,0,0,0,0,0,0,0)';
      PINUSE='POWER';
      NO_LOAD_CHECK='Both';
      NO_IO_CHECK='Both';
      NO_ASSERT_CHECK='TRUE';
      NO_DIR_CHECK='TRUE';
      ALLOW_CONNECT='TRUE';
    'VSS_H48':
      PIN_NUMBER='(0,0,0,0,0,0,0,0,0,0,0,0,0,0,0,0,0,0,0,0,0,0,0,0,0,0,0,H48,0,0~
,0,0,0,0,0,0,0,0,0,0)';
      PINUSE='POWER';
      NO_LOAD_CHECK='Both';
      NO_IO_CHECK='Both';
      NO_ASSERT_CHECK='TRUE';
      NO_DIR_CHECK='TRUE';
      ALLOW_CONNECT='TRUE';
    'VSS_H51':
      PIN_NUMBER='(0,0,0,0,0,0,0,0,0,0,0,0,0,0,0,0,0,0,0,0,0,0,0,0,0,0,0,H51,0,0~
,0,0,0,0,0,0,0,0,0,0)';
      PINUSE='POWER';
      NO_LOAD_CHECK='Both';
      NO_IO_CHECK='Both';
      NO_ASSERT_CHECK='TRUE';
      NO_DIR_CHECK='TRUE';
      ALLOW_CONNECT='TRUE';
    'VSS_H54':
      PIN_NUMBER='(0,0,0,0,0,0,0,0,0,0,0,0,0,0,0,0,0,0,0,0,0,0,0,0,0,0,0,H54,0,0~
,0,0,0,0,0,0,0,0,0,0)';
      PINUSE='POWER';
      NO_LOAD_CHECK='Both';
      NO_IO_CHECK='Both';
      NO_ASSERT_CHECK='TRUE';
      NO_DIR_CHECK='TRUE';
      ALLOW_CONNECT='TRUE';
    'VSS_H59':
      PIN_NUMBER='(0,0,0,0,0,0,0,0,0,0,0,0,0,0,0,0,0,0,0,0,0,0,0,0,0,0,0,H59,0,0~
,0,0,0,0,0,0,0,0,0,0)';
      PINUSE='POWER';
      NO_LOAD_CHECK='Both';
      NO_IO_CHECK='Both';
      NO_ASSERT_CHECK='TRUE';
      NO_DIR_CHECK='TRUE';
      ALLOW_CONNECT='TRUE';
    'VSS_H61':
      PIN_NUMBER='(0,0,0,0,0,0,0,0,0,0,0,0,0,0,0,0,0,0,0,0,0,0,0,0,0,0,0,H61,0,0~
,0,0,0,0,0,0,0,0,0,0)';
      PINUSE='POWER';
      NO_LOAD_CHECK='Both';
      NO_IO_CHECK='Both';
      NO_ASSERT_CHECK='TRUE';
      NO_DIR_CHECK='TRUE';
      ALLOW_CONNECT='TRUE';
    'VSS_H66':
      PIN_NUMBER='(0,0,0,0,0,0,0,0,0,0,0,0,0,0,0,0,0,0,0,0,0,0,0,0,0,0,0,H66,0,0~
,0,0,0,0,0,0,0,0,0,0)';
      PINUSE='POWER';
      NO_LOAD_CHECK='Both';
      NO_IO_CHECK='Both';
      NO_ASSERT_CHECK='TRUE';
      NO_DIR_CHECK='TRUE';
      ALLOW_CONNECT='TRUE';
    'VSS_H68':
      PIN_NUMBER='(0,0,0,0,0,0,0,0,0,0,0,0,0,0,0,0,0,0,0,0,0,0,0,0,0,0,0,H68,0,0~
,0,0,0,0,0,0,0,0,0,0)';
      PINUSE='POWER';
      NO_LOAD_CHECK='Both';
      NO_IO_CHECK='Both';
      NO_ASSERT_CHECK='TRUE';
      NO_DIR_CHECK='TRUE';
      ALLOW_CONNECT='TRUE';
    'VSS_H73':
      PIN_NUMBER='(0,0,0,0,0,0,0,0,0,0,0,0,0,0,0,0,0,0,0,0,0,0,0,0,0,0,0,H73,0,0~
,0,0,0,0,0,0,0,0,0,0)';
      PINUSE='POWER';
      NO_LOAD_CHECK='Both';
      NO_IO_CHECK='Both';
      NO_ASSERT_CHECK='TRUE';
      NO_DIR_CHECK='TRUE';
      ALLOW_CONNECT='TRUE';
    'VSS_J1':
      PIN_NUMBER='(0,0,0,0,0,0,0,0,0,0,0,0,0,0,0,0,0,0,0,0,0,0,0,0,0,0,0,J1,0,0,~
0,0,0,0,0,0,0,0,0,0)';
      PINUSE='POWER';
      NO_LOAD_CHECK='Both';
      NO_IO_CHECK='Both';
      NO_ASSERT_CHECK='TRUE';
      NO_DIR_CHECK='TRUE';
      ALLOW_CONNECT='TRUE';
    'VSS_J4':
      PIN_NUMBER='(0,0,0,0,0,0,0,0,0,0,0,0,0,0,0,0,0,0,0,0,0,0,0,0,0,0,0,J4,0,0,~
0,0,0,0,0,0,0,0,0,0)';
      PINUSE='POWER';
      NO_LOAD_CHECK='Both';
      NO_IO_CHECK='Both';
      NO_ASSERT_CHECK='TRUE';
      NO_DIR_CHECK='TRUE';
      ALLOW_CONNECT='TRUE';
    'VSS_J6':
      PIN_NUMBER='(0,0,0,0,0,0,0,0,0,0,0,0,0,0,0,0,0,0,0,0,0,0,0,0,0,0,0,J6,0,0,~
0,0,0,0,0,0,0,0,0,0)';
      PINUSE='POWER';
      NO_LOAD_CHECK='Both';
      NO_IO_CHECK='Both';
      NO_ASSERT_CHECK='TRUE';
      NO_DIR_CHECK='TRUE';
      ALLOW_CONNECT='TRUE';
    'VSS_J8':
      PIN_NUMBER='(0,0,0,0,0,0,0,0,0,0,0,0,0,0,0,0,0,0,0,0,0,0,0,0,0,0,0,J8,0,0,~
0,0,0,0,0,0,0,0,0,0)';
      PINUSE='POWER';
      NO_LOAD_CHECK='Both';
      NO_IO_CHECK='Both';
      NO_ASSERT_CHECK='TRUE';
      NO_DIR_CHECK='TRUE';
      ALLOW_CONNECT='TRUE';
    'VSS_J11':
      PIN_NUMBER='(0,0,0,0,0,0,0,0,0,0,0,0,0,0,0,0,0,0,0,0,0,0,0,0,0,0,0,J11,0,0~
,0,0,0,0,0,0,0,0,0,0)';
      PINUSE='POWER';
      NO_LOAD_CHECK='Both';
      NO_IO_CHECK='Both';
      NO_ASSERT_CHECK='TRUE';
      NO_DIR_CHECK='TRUE';
      ALLOW_CONNECT='TRUE';
    'VSS_J13':
      PIN_NUMBER='(0,0,0,0,0,0,0,0,0,0,0,0,0,0,0,0,0,0,0,0,0,0,0,0,0,0,0,J13,0,0~
,0,0,0,0,0,0,0,0,0,0)';
      PINUSE='POWER';
      NO_LOAD_CHECK='Both';
      NO_IO_CHECK='Both';
      NO_ASSERT_CHECK='TRUE';
      NO_DIR_CHECK='TRUE';
      ALLOW_CONNECT='TRUE';
    'VSS_A3':
      PIN_NUMBER='(0,0,0,0,0,0,0,0,0,0,0,0,0,0,0,0,0,0,0,0,0,0,0,0,0,0,0,A3,0,0,~
0,0,0,0,0,0,0,0,0,0)';
      PINUSE='POWER';
      NO_LOAD_CHECK='Both';
      NO_IO_CHECK='Both';
      NO_ASSERT_CHECK='TRUE';
      NO_DIR_CHECK='TRUE';
      ALLOW_CONNECT='TRUE';
    'VSS_A9':
      PIN_NUMBER='(0,0,0,0,0,0,0,0,0,0,0,0,0,0,0,0,0,0,0,0,0,0,0,0,0,0,0,A9,0,0,~
0,0,0,0,0,0,0,0,0,0)';
      PINUSE='POWER';
      NO_LOAD_CHECK='Both';
      NO_IO_CHECK='Both';
      NO_ASSERT_CHECK='TRUE';
      NO_DIR_CHECK='TRUE';
      ALLOW_CONNECT='TRUE';
    'VSS_A15':
      PIN_NUMBER='(0,0,0,0,0,0,0,0,0,0,0,0,0,0,0,0,0,0,0,0,0,0,0,0,0,0,0,A15,0,0~
,0,0,0,0,0,0,0,0,0,0)';
      PINUSE='POWER';
      NO_LOAD_CHECK='Both';
      NO_IO_CHECK='Both';
      NO_ASSERT_CHECK='TRUE';
      NO_DIR_CHECK='TRUE';
      ALLOW_CONNECT='TRUE';
    'VSS_A21':
      PIN_NUMBER='(0,0,0,0,0,0,0,0,0,0,0,0,0,0,0,0,0,0,0,0,0,0,0,0,0,0,0,A21,0,0~
,0,0,0,0,0,0,0,0,0,0)';
      PINUSE='POWER';
      NO_LOAD_CHECK='Both';
      NO_IO_CHECK='Both';
      NO_ASSERT_CHECK='TRUE';
      NO_DIR_CHECK='TRUE';
      ALLOW_CONNECT='TRUE';
    'VSS_A27':
      PIN_NUMBER='(0,0,0,0,0,0,0,0,0,0,0,0,0,0,0,0,0,0,0,0,0,0,0,0,0,0,0,A27,0,0~
,0,0,0,0,0,0,0,0,0,0)';
      PINUSE='POWER';
      NO_LOAD_CHECK='Both';
      NO_IO_CHECK='Both';
      NO_ASSERT_CHECK='TRUE';
      NO_DIR_CHECK='TRUE';
      ALLOW_CONNECT='TRUE';
    'VSS_A43':
      PIN_NUMBER='(0,0,0,0,0,0,0,0,0,0,0,0,0,0,0,0,0,0,0,0,0,0,0,0,0,0,0,A43,0,0~
,0,0,0,0,0,0,0,0,0,0)';
      PINUSE='POWER';
      NO_LOAD_CHECK='Both';
      NO_IO_CHECK='Both';
      NO_ASSERT_CHECK='TRUE';
      NO_DIR_CHECK='TRUE';
      ALLOW_CONNECT='TRUE';
    'VSS_A44':
      PIN_NUMBER='(0,0,0,0,0,0,0,0,0,0,0,0,0,0,0,0,0,0,0,0,0,0,0,0,0,0,0,A44,0,0~
,0,0,0,0,0,0,0,0,0,0)';
      PINUSE='POWER';
      NO_LOAD_CHECK='Both';
      NO_IO_CHECK='Both';
      NO_ASSERT_CHECK='TRUE';
      NO_DIR_CHECK='TRUE';
      ALLOW_CONNECT='TRUE';
    'VSS_A47':
      PIN_NUMBER='(0,0,0,0,0,0,0,0,0,0,0,0,0,0,0,0,0,0,0,0,0,0,0,0,0,0,0,A47,0,0~
,0,0,0,0,0,0,0,0,0,0)';
      PINUSE='POWER';
      NO_LOAD_CHECK='Both';
      NO_IO_CHECK='Both';
      NO_ASSERT_CHECK='TRUE';
      NO_DIR_CHECK='TRUE';
      ALLOW_CONNECT='TRUE';
    'VSS_A49':
      PIN_NUMBER='(0,0,0,0,0,0,0,0,0,0,0,0,0,0,0,0,0,0,0,0,0,0,0,0,0,0,0,A49,0,0~
,0,0,0,0,0,0,0,0,0,0)';
      PINUSE='POWER';
      NO_LOAD_CHECK='Both';
      NO_IO_CHECK='Both';
      NO_ASSERT_CHECK='TRUE';
      NO_DIR_CHECK='TRUE';
      ALLOW_CONNECT='TRUE';
    'VSS_A53':
      PIN_NUMBER='(0,0,0,0,0,0,0,0,0,0,0,0,0,0,0,0,0,0,0,0,0,0,0,0,0,0,0,A53,0,0~
,0,0,0,0,0,0,0,0,0,0)';
      PINUSE='POWER';
      NO_LOAD_CHECK='Both';
      NO_IO_CHECK='Both';
      NO_ASSERT_CHECK='TRUE';
      NO_DIR_CHECK='TRUE';
      ALLOW_CONNECT='TRUE';
    'VSS_A61':
      PIN_NUMBER='(0,0,0,0,0,0,0,0,0,0,0,0,0,0,0,0,0,0,0,0,0,0,0,0,0,0,0,A61,0,0~
,0,0,0,0,0,0,0,0,0,0)';
      PINUSE='POWER';
      NO_LOAD_CHECK='Both';
      NO_IO_CHECK='Both';
      NO_ASSERT_CHECK='TRUE';
      NO_DIR_CHECK='TRUE';
      ALLOW_CONNECT='TRUE';
    'VSS_A67':
      PIN_NUMBER='(0,0,0,0,0,0,0,0,0,0,0,0,0,0,0,0,0,0,0,0,0,0,0,0,0,0,0,A67,0,0~
,0,0,0,0,0,0,0,0,0,0)';
      PINUSE='POWER';
      NO_LOAD_CHECK='Both';
      NO_IO_CHECK='Both';
      NO_ASSERT_CHECK='TRUE';
      NO_DIR_CHECK='TRUE';
      ALLOW_CONNECT='TRUE';
    'VSS_A72':
      PIN_NUMBER='(0,0,0,0,0,0,0,0,0,0,0,0,0,0,0,0,0,0,0,0,0,0,0,0,0,0,0,A72,0,0~
,0,0,0,0,0,0,0,0,0,0)';
      PINUSE='POWER';
      NO_LOAD_CHECK='Both';
      NO_IO_CHECK='Both';
      NO_ASSERT_CHECK='TRUE';
      NO_DIR_CHECK='TRUE';
      ALLOW_CONNECT='TRUE';
    'VSS_A73':
      PIN_NUMBER='(0,0,0,0,0,0,0,0,0,0,0,0,0,0,0,0,0,0,0,0,0,0,0,0,0,0,0,A73,0,0~
,0,0,0,0,0,0,0,0,0,0)';
      PINUSE='POWER';
      NO_LOAD_CHECK='Both';
      NO_IO_CHECK='Both';
      NO_ASSERT_CHECK='TRUE';
      NO_DIR_CHECK='TRUE';
      ALLOW_CONNECT='TRUE';
    'VSS_B7':
      PIN_NUMBER='(0,0,0,0,0,0,0,0,0,0,0,0,0,0,0,0,0,0,0,0,0,0,0,0,0,0,0,B7,0,0,~
0,0,0,0,0,0,0,0,0,0)';
      PINUSE='POWER';
      NO_LOAD_CHECK='Both';
      NO_IO_CHECK='Both';
      NO_ASSERT_CHECK='TRUE';
      NO_DIR_CHECK='TRUE';
      ALLOW_CONNECT='TRUE';
    'VSS_B8':
      PIN_NUMBER='(0,0,0,0,0,0,0,0,0,0,0,0,0,0,0,0,0,0,0,0,0,0,0,0,0,0,0,B8,0,0,~
0,0,0,0,0,0,0,0,0,0)';
      PINUSE='POWER';
      NO_LOAD_CHECK='Both';
      NO_IO_CHECK='Both';
      NO_ASSERT_CHECK='TRUE';
      NO_DIR_CHECK='TRUE';
      ALLOW_CONNECT='TRUE';
    'VSS_B10':
      PIN_NUMBER='(0,0,0,0,0,0,0,0,0,0,0,0,0,0,0,0,0,0,0,0,0,0,0,0,0,0,0,B10,0,0~
,0,0,0,0,0,0,0,0,0,0)';
      PINUSE='POWER';
      NO_LOAD_CHECK='Both';
      NO_IO_CHECK='Both';
      NO_ASSERT_CHECK='TRUE';
      NO_DIR_CHECK='TRUE';
      ALLOW_CONNECT='TRUE';
    'VSS_B11':
      PIN_NUMBER='(0,0,0,0,0,0,0,0,0,0,0,0,0,0,0,0,0,0,0,0,0,0,0,0,0,0,0,B11,0,0~
,0,0,0,0,0,0,0,0,0,0)';
      PINUSE='POWER';
      NO_LOAD_CHECK='Both';
      NO_IO_CHECK='Both';
      NO_ASSERT_CHECK='TRUE';
      NO_DIR_CHECK='TRUE';
      ALLOW_CONNECT='TRUE';
    'VSS_B13':
      PIN_NUMBER='(0,0,0,0,0,0,0,0,0,0,0,0,0,0,0,0,0,0,0,0,0,0,0,0,0,0,0,B13,0,0~
,0,0,0,0,0,0,0,0,0,0)';
      PINUSE='POWER';
      NO_LOAD_CHECK='Both';
      NO_IO_CHECK='Both';
      NO_ASSERT_CHECK='TRUE';
      NO_DIR_CHECK='TRUE';
      ALLOW_CONNECT='TRUE';
    'VSS_B18':
      PIN_NUMBER='(0,0,0,0,0,0,0,0,0,0,0,0,0,0,0,0,0,0,0,0,0,0,0,0,0,0,0,B18,0,0~
,0,0,0,0,0,0,0,0,0,0)';
      PINUSE='POWER';
      NO_LOAD_CHECK='Both';
      NO_IO_CHECK='Both';
      NO_ASSERT_CHECK='TRUE';
      NO_DIR_CHECK='TRUE';
      ALLOW_CONNECT='TRUE';
    'VSS_B24':
      PIN_NUMBER='(0,0,0,0,0,0,0,0,0,0,0,0,0,0,0,0,0,0,0,0,0,0,0,0,0,0,0,B24,0,0~
,0,0,0,0,0,0,0,0,0,0)';
      PINUSE='POWER';
      NO_LOAD_CHECK='Both';
      NO_IO_CHECK='Both';
      NO_ASSERT_CHECK='TRUE';
      NO_DIR_CHECK='TRUE';
      ALLOW_CONNECT='TRUE';
    'VSS_B27':
      PIN_NUMBER='(0,0,0,0,0,0,0,0,0,0,0,0,0,0,0,0,0,0,0,0,0,0,0,0,0,0,0,B27,0,0~
,0,0,0,0,0,0,0,0,0,0)';
      PINUSE='POWER';
      NO_LOAD_CHECK='Both';
      NO_IO_CHECK='Both';
      NO_ASSERT_CHECK='TRUE';
      NO_DIR_CHECK='TRUE';
      ALLOW_CONNECT='TRUE';
    'VSS_B30':
      PIN_NUMBER='(0,0,0,0,0,0,0,0,0,0,0,0,0,0,0,0,0,0,0,0,0,0,0,0,0,0,0,B30,0,0~
,0,0,0,0,0,0,0,0,0,0)';
      PINUSE='POWER';
      NO_LOAD_CHECK='Both';
      NO_IO_CHECK='Both';
      NO_ASSERT_CHECK='TRUE';
      NO_DIR_CHECK='TRUE';
      ALLOW_CONNECT='TRUE';
    'VSS_B33':
      PIN_NUMBER='(0,0,0,0,0,0,0,0,0,0,0,0,0,0,0,0,0,0,0,0,0,0,0,0,0,0,0,B33,0,0~
,0,0,0,0,0,0,0,0,0,0)';
      PINUSE='POWER';
      NO_LOAD_CHECK='Both';
      NO_IO_CHECK='Both';
      NO_ASSERT_CHECK='TRUE';
      NO_DIR_CHECK='TRUE';
      ALLOW_CONNECT='TRUE';
    'VSS_B37':
      PIN_NUMBER='(0,0,0,0,0,0,0,0,0,0,0,0,0,0,0,0,0,0,0,0,0,0,0,0,0,0,0,B37,0,0~
,0,0,0,0,0,0,0,0,0,0)';
      PINUSE='POWER';
      NO_LOAD_CHECK='Both';
      NO_IO_CHECK='Both';
      NO_ASSERT_CHECK='TRUE';
      NO_DIR_CHECK='TRUE';
      ALLOW_CONNECT='TRUE';
    'VSS_B39':
      PIN_NUMBER='(0,0,0,0,0,0,0,0,0,0,0,0,0,0,0,0,0,0,0,0,0,0,0,0,0,0,0,B39,0,0~
,0,0,0,0,0,0,0,0,0,0)';
      PINUSE='POWER';
      NO_LOAD_CHECK='Both';
      NO_IO_CHECK='Both';
      NO_ASSERT_CHECK='TRUE';
      NO_DIR_CHECK='TRUE';
      ALLOW_CONNECT='TRUE';
    'VSS_B43':
      PIN_NUMBER='(0,0,0,0,0,0,0,0,0,0,0,0,0,0,0,0,0,0,0,0,0,0,0,0,0,0,0,B43,0,0~
,0,0,0,0,0,0,0,0,0,0)';
      PINUSE='POWER';
      NO_LOAD_CHECK='Both';
      NO_IO_CHECK='Both';
      NO_ASSERT_CHECK='TRUE';
      NO_DIR_CHECK='TRUE';
      ALLOW_CONNECT='TRUE';
    'VSS_B46':
      PIN_NUMBER='(0,0,0,0,0,0,0,0,0,0,0,0,0,0,0,0,0,0,0,0,0,0,0,0,0,0,0,B46,0,0~
,0,0,0,0,0,0,0,0,0,0)';
      PINUSE='POWER';
      NO_LOAD_CHECK='Both';
      NO_IO_CHECK='Both';
      NO_ASSERT_CHECK='TRUE';
      NO_DIR_CHECK='TRUE';
      ALLOW_CONNECT='TRUE';
    'VSS_B49':
      PIN_NUMBER='(0,0,0,0,0,0,0,0,0,0,0,0,0,0,0,0,0,0,0,0,0,0,0,0,0,0,0,B49,0,0~
,0,0,0,0,0,0,0,0,0,0)';
      PINUSE='POWER';
      NO_LOAD_CHECK='Both';
      NO_IO_CHECK='Both';
      NO_ASSERT_CHECK='TRUE';
      NO_DIR_CHECK='TRUE';
      ALLOW_CONNECT='TRUE';
    'VSS_B52':
      PIN_NUMBER='(0,0,0,0,0,0,0,0,0,0,0,0,0,0,0,0,0,0,0,0,0,0,0,0,0,0,0,B52,0,0~
,0,0,0,0,0,0,0,0,0,0)';
      PINUSE='POWER';
      NO_LOAD_CHECK='Both';
      NO_IO_CHECK='Both';
      NO_ASSERT_CHECK='TRUE';
      NO_DIR_CHECK='TRUE';
      ALLOW_CONNECT='TRUE';
    'VSS_B55':
      PIN_NUMBER='(0,0,0,0,0,0,0,0,0,0,0,0,0,0,0,0,0,0,0,0,0,0,0,0,0,0,0,B55,0,0~
,0,0,0,0,0,0,0,0,0,0)';
      PINUSE='POWER';
      NO_LOAD_CHECK='Both';
      NO_IO_CHECK='Both';
      NO_ASSERT_CHECK='TRUE';
      NO_DIR_CHECK='TRUE';
      ALLOW_CONNECT='TRUE';
    'VSS_B59':
      PIN_NUMBER='(0,0,0,0,0,0,0,0,0,0,0,0,0,0,0,0,0,0,0,0,0,0,0,0,0,0,0,B59,0,0~
,0,0,0,0,0,0,0,0,0,0)';
      PINUSE='POWER';
      NO_LOAD_CHECK='Both';
      NO_IO_CHECK='Both';
      NO_ASSERT_CHECK='TRUE';
      NO_DIR_CHECK='TRUE';
      ALLOW_CONNECT='TRUE';
    'VSS_B62':
      PIN_NUMBER='(0,0,0,0,0,0,0,0,0,0,0,0,0,0,0,0,0,0,0,0,0,0,0,0,0,0,0,B62,0,0~
,0,0,0,0,0,0,0,0,0,0)';
      PINUSE='POWER';
      NO_LOAD_CHECK='Both';
      NO_IO_CHECK='Both';
      NO_ASSERT_CHECK='TRUE';
      NO_DIR_CHECK='TRUE';
      ALLOW_CONNECT='TRUE';
    'VSS_B65':
      PIN_NUMBER='(0,0,0,0,0,0,0,0,0,0,0,0,0,0,0,0,0,0,0,0,0,0,0,0,0,0,0,B65,0,0~
,0,0,0,0,0,0,0,0,0,0)';
      PINUSE='POWER';
      NO_LOAD_CHECK='Both';
      NO_IO_CHECK='Both';
      NO_ASSERT_CHECK='TRUE';
      NO_DIR_CHECK='TRUE';
      ALLOW_CONNECT='TRUE';
    'VSS_B68':
      PIN_NUMBER='(0,0,0,0,0,0,0,0,0,0,0,0,0,0,0,0,0,0,0,0,0,0,0,0,0,0,0,B68,0,0~
,0,0,0,0,0,0,0,0,0,0)';
      PINUSE='POWER';
      NO_LOAD_CHECK='Both';
      NO_IO_CHECK='Both';
      NO_ASSERT_CHECK='TRUE';
      NO_DIR_CHECK='TRUE';
      ALLOW_CONNECT='TRUE';
    'VSS_B70':
      PIN_NUMBER='(0,0,0,0,0,0,0,0,0,0,0,0,0,0,0,0,0,0,0,0,0,0,0,0,0,0,0,B70,0,0~
,0,0,0,0,0,0,0,0,0,0)';
      PINUSE='POWER';
      NO_LOAD_CHECK='Both';
      NO_IO_CHECK='Both';
      NO_ASSERT_CHECK='TRUE';
      NO_DIR_CHECK='TRUE';
      ALLOW_CONNECT='TRUE';
    'VSS_C1':
      PIN_NUMBER='(0,0,0,0,0,0,0,0,0,0,0,0,0,0,0,0,0,0,0,0,0,0,0,0,0,0,0,C1,0,0,~
0,0,0,0,0,0,0,0,0,0)';
      PINUSE='POWER';
      NO_LOAD_CHECK='Both';
      NO_IO_CHECK='Both';
      NO_ASSERT_CHECK='TRUE';
      NO_DIR_CHECK='TRUE';
      ALLOW_CONNECT='TRUE';
    'VSS_C5':
      PIN_NUMBER='(0,0,0,0,0,0,0,0,0,0,0,0,0,0,0,0,0,0,0,0,0,0,0,0,0,0,0,C5,0,0,~
0,0,0,0,0,0,0,0,0,0)';
      PINUSE='POWER';
      NO_LOAD_CHECK='Both';
      NO_IO_CHECK='Both';
      NO_ASSERT_CHECK='TRUE';
      NO_DIR_CHECK='TRUE';
      ALLOW_CONNECT='TRUE';
    'VSS_C8':
      PIN_NUMBER='(0,0,0,0,0,0,0,0,0,0,0,0,0,0,0,0,0,0,0,0,0,0,0,0,0,0,0,C8,0,0,~
0,0,0,0,0,0,0,0,0,0)';
      PINUSE='POWER';
      NO_LOAD_CHECK='Both';
      NO_IO_CHECK='Both';
      NO_ASSERT_CHECK='TRUE';
      NO_DIR_CHECK='TRUE';
      ALLOW_CONNECT='TRUE';
    'VSS_C10':
      PIN_NUMBER='(0,0,0,0,0,0,0,0,0,0,0,0,0,0,0,0,0,0,0,0,0,0,0,0,0,0,0,C10,0,0~
,0,0,0,0,0,0,0,0,0,0)';
      PINUSE='POWER';
      NO_LOAD_CHECK='Both';
      NO_IO_CHECK='Both';
      NO_ASSERT_CHECK='TRUE';
      NO_DIR_CHECK='TRUE';
      ALLOW_CONNECT='TRUE';
    'VSS_C11':
      PIN_NUMBER='(0,0,0,0,0,0,0,0,0,0,0,0,0,0,0,0,0,0,0,0,0,0,0,0,0,0,0,C11,0,0~
,0,0,0,0,0,0,0,0,0,0)';
      PINUSE='POWER';
      NO_LOAD_CHECK='Both';
      NO_IO_CHECK='Both';
      NO_ASSERT_CHECK='TRUE';
      NO_DIR_CHECK='TRUE';
      ALLOW_CONNECT='TRUE';
    'VSS_C13':
      PIN_NUMBER='(0,0,0,0,0,0,0,0,0,0,0,0,0,0,0,0,0,0,0,0,0,0,0,0,0,0,0,C13,0,0~
,0,0,0,0,0,0,0,0,0,0)';
      PINUSE='POWER';
      NO_LOAD_CHECK='Both';
      NO_IO_CHECK='Both';
      NO_ASSERT_CHECK='TRUE';
      NO_DIR_CHECK='TRUE';
      ALLOW_CONNECT='TRUE';
    'VSS_C15':
      PIN_NUMBER='(0,0,0,0,0,0,0,0,0,0,0,0,0,0,0,0,0,0,0,0,0,0,0,0,0,0,0,C15,0,0~
,0,0,0,0,0,0,0,0,0,0)';
      PINUSE='POWER';
      NO_LOAD_CHECK='Both';
      NO_IO_CHECK='Both';
      NO_ASSERT_CHECK='TRUE';
      NO_DIR_CHECK='TRUE';
      ALLOW_CONNECT='TRUE';
    'VSS_C21':
      PIN_NUMBER='(0,0,0,0,0,0,0,0,0,0,0,0,0,0,0,0,0,0,0,0,0,0,0,0,0,0,0,C21,0,0~
,0,0,0,0,0,0,0,0,0,0)';
      PINUSE='POWER';
      NO_LOAD_CHECK='Both';
      NO_IO_CHECK='Both';
      NO_ASSERT_CHECK='TRUE';
      NO_DIR_CHECK='TRUE';
      ALLOW_CONNECT='TRUE';
    'VSS_C24':
      PIN_NUMBER='(0,0,0,0,0,0,0,0,0,0,0,0,0,0,0,0,0,0,0,0,0,0,0,0,0,0,0,C24,0,0~
,0,0,0,0,0,0,0,0,0,0)';
      PINUSE='POWER';
      NO_LOAD_CHECK='Both';
      NO_IO_CHECK='Both';
      NO_ASSERT_CHECK='TRUE';
      NO_DIR_CHECK='TRUE';
      ALLOW_CONNECT='TRUE';
    'VSS_C27':
      PIN_NUMBER='(0,0,0,0,0,0,0,0,0,0,0,0,0,0,0,0,0,0,0,0,0,0,0,0,0,0,0,C27,0,0~
,0,0,0,0,0,0,0,0,0,0)';
      PINUSE='POWER';
      NO_LOAD_CHECK='Both';
      NO_IO_CHECK='Both';
      NO_ASSERT_CHECK='TRUE';
      NO_DIR_CHECK='TRUE';
      ALLOW_CONNECT='TRUE';
    'VSS_C30':
      PIN_NUMBER='(0,0,0,0,0,0,0,0,0,0,0,0,0,0,0,0,0,0,0,0,0,0,0,0,0,0,0,C30,0,0~
,0,0,0,0,0,0,0,0,0,0)';
      PINUSE='POWER';
      NO_LOAD_CHECK='Both';
      NO_IO_CHECK='Both';
      NO_ASSERT_CHECK='TRUE';
      NO_DIR_CHECK='TRUE';
      ALLOW_CONNECT='TRUE';
    'VSS_C36':
      PIN_NUMBER='(0,0,0,0,0,0,0,0,0,0,0,0,0,0,0,0,0,0,0,0,0,0,0,0,0,0,0,C36,0,0~
,0,0,0,0,0,0,0,0,0,0)';
      PINUSE='POWER';
      NO_LOAD_CHECK='Both';
      NO_IO_CHECK='Both';
      NO_ASSERT_CHECK='TRUE';
      NO_DIR_CHECK='TRUE';
      ALLOW_CONNECT='TRUE';
    'VSS_C40':
      PIN_NUMBER='(0,0,0,0,0,0,0,0,0,0,0,0,0,0,0,0,0,0,0,0,0,0,0,0,0,0,0,C40,0,0~
,0,0,0,0,0,0,0,0,0,0)';
      PINUSE='POWER';
      NO_LOAD_CHECK='Both';
      NO_IO_CHECK='Both';
      NO_ASSERT_CHECK='TRUE';
      NO_DIR_CHECK='TRUE';
      ALLOW_CONNECT='TRUE';
    'VSS_C43':
      PIN_NUMBER='(0,0,0,0,0,0,0,0,0,0,0,0,0,0,0,0,0,0,0,0,0,0,0,0,0,0,0,C43,0,0~
,0,0,0,0,0,0,0,0,0,0)';
      PINUSE='POWER';
      NO_LOAD_CHECK='Both';
      NO_IO_CHECK='Both';
      NO_ASSERT_CHECK='TRUE';
      NO_DIR_CHECK='TRUE';
      ALLOW_CONNECT='TRUE';
    'VSS_C46':
      PIN_NUMBER='(0,0,0,0,0,0,0,0,0,0,0,0,0,0,0,0,0,0,0,0,0,0,0,0,0,0,0,C46,0,0~
,0,0,0,0,0,0,0,0,0,0)';
      PINUSE='POWER';
      NO_LOAD_CHECK='Both';
      NO_IO_CHECK='Both';
      NO_ASSERT_CHECK='TRUE';
      NO_DIR_CHECK='TRUE';
      ALLOW_CONNECT='TRUE';
    'VSS_C49':
      PIN_NUMBER='(0,0,0,0,0,0,0,0,0,0,0,0,0,0,0,0,0,0,0,0,0,0,0,0,0,0,0,C49,0,0~
,0,0,0,0,0,0,0,0,0,0)';
      PINUSE='POWER';
      NO_LOAD_CHECK='Both';
      NO_IO_CHECK='Both';
      NO_ASSERT_CHECK='TRUE';
      NO_DIR_CHECK='TRUE';
      ALLOW_CONNECT='TRUE';
    'VSS_C52':
      PIN_NUMBER='(0,0,0,0,0,0,0,0,0,0,0,0,0,0,0,0,0,0,0,0,0,0,0,0,0,0,0,C52,0,0~
,0,0,0,0,0,0,0,0,0,0)';
      PINUSE='POWER';
      NO_LOAD_CHECK='Both';
      NO_IO_CHECK='Both';
      NO_ASSERT_CHECK='TRUE';
      NO_DIR_CHECK='TRUE';
      ALLOW_CONNECT='TRUE';
    'VSS_C55':
      PIN_NUMBER='(0,0,0,0,0,0,0,0,0,0,0,0,0,0,0,0,0,0,0,0,0,0,0,0,0,0,0,C55,0,0~
,0,0,0,0,0,0,0,0,0,0)';
      PINUSE='POWER';
      NO_LOAD_CHECK='Both';
      NO_IO_CHECK='Both';
      NO_ASSERT_CHECK='TRUE';
      NO_DIR_CHECK='TRUE';
      ALLOW_CONNECT='TRUE';
    'VSS_C56':
      PIN_NUMBER='(0,0,0,0,0,0,0,0,0,0,0,0,0,0,0,0,0,0,0,0,0,0,0,0,0,0,0,C56,0,0~
,0,0,0,0,0,0,0,0,0,0)';
      PINUSE='POWER';
      NO_LOAD_CHECK='Both';
      NO_IO_CHECK='Both';
      NO_ASSERT_CHECK='TRUE';
      NO_DIR_CHECK='TRUE';
      ALLOW_CONNECT='TRUE';
    'VSS_C57':
      PIN_NUMBER='(0,0,0,0,0,0,0,0,0,0,0,0,0,0,0,0,0,0,0,0,0,0,0,0,0,0,0,C57,0,0~
,0,0,0,0,0,0,0,0,0,0)';
      PINUSE='POWER';
      NO_LOAD_CHECK='Both';
      NO_IO_CHECK='Both';
      NO_ASSERT_CHECK='TRUE';
      NO_DIR_CHECK='TRUE';
      ALLOW_CONNECT='TRUE';
    'VSS_C61':
      PIN_NUMBER='(0,0,0,0,0,0,0,0,0,0,0,0,0,0,0,0,0,0,0,0,0,0,0,0,0,0,0,C61,0,0~
,0,0,0,0,0,0,0,0,0,0)';
      PINUSE='POWER';
      NO_LOAD_CHECK='Both';
      NO_IO_CHECK='Both';
      NO_ASSERT_CHECK='TRUE';
      NO_DIR_CHECK='TRUE';
      ALLOW_CONNECT='TRUE';
    'VSS_C64':
      PIN_NUMBER='(0,0,0,0,0,0,0,0,0,0,0,0,0,0,0,0,0,0,0,0,0,0,0,0,0,0,0,C64,0,0~
,0,0,0,0,0,0,0,0,0,0)';
      PINUSE='POWER';
      NO_LOAD_CHECK='Both';
      NO_IO_CHECK='Both';
      NO_ASSERT_CHECK='TRUE';
      NO_DIR_CHECK='TRUE';
      ALLOW_CONNECT='TRUE';
    'VSS_C67':
      PIN_NUMBER='(0,0,0,0,0,0,0,0,0,0,0,0,0,0,0,0,0,0,0,0,0,0,0,0,0,0,0,C67,0,0~
,0,0,0,0,0,0,0,0,0,0)';
      PINUSE='POWER';
      NO_LOAD_CHECK='Both';
      NO_IO_CHECK='Both';
      NO_ASSERT_CHECK='TRUE';
      NO_DIR_CHECK='TRUE';
      ALLOW_CONNECT='TRUE';
    'VSS_C69':
      PIN_NUMBER='(0,0,0,0,0,0,0,0,0,0,0,0,0,0,0,0,0,0,0,0,0,0,0,0,0,0,0,C69,0,0~
,0,0,0,0,0,0,0,0,0,0)';
      PINUSE='POWER';
      NO_LOAD_CHECK='Both';
      NO_IO_CHECK='Both';
      NO_ASSERT_CHECK='TRUE';
      NO_DIR_CHECK='TRUE';
      ALLOW_CONNECT='TRUE';
    'VSS_C71':
      PIN_NUMBER='(0,0,0,0,0,0,0,0,0,0,0,0,0,0,0,0,0,0,0,0,0,0,0,0,0,0,0,C71,0,0~
,0,0,0,0,0,0,0,0,0,0)';
      PINUSE='POWER';
      NO_LOAD_CHECK='Both';
      NO_IO_CHECK='Both';
      NO_ASSERT_CHECK='TRUE';
      NO_DIR_CHECK='TRUE';
      ALLOW_CONNECT='TRUE';
    'VSS_C73':
      PIN_NUMBER='(0,0,0,0,0,0,0,0,0,0,0,0,0,0,0,0,0,0,0,0,0,0,0,0,0,0,0,C73,0,0~
,0,0,0,0,0,0,0,0,0,0)';
      PINUSE='POWER';
      NO_LOAD_CHECK='Both';
      NO_IO_CHECK='Both';
      NO_ASSERT_CHECK='TRUE';
      NO_DIR_CHECK='TRUE';
      ALLOW_CONNECT='TRUE';
    'VSS_C75':
      PIN_NUMBER='(0,0,0,0,0,0,0,0,0,0,0,0,0,0,0,0,0,0,0,0,0,0,0,0,0,0,0,C75,0,0~
,0,0,0,0,0,0,0,0,0,0)';
      PINUSE='POWER';
      NO_LOAD_CHECK='Both';
      NO_IO_CHECK='Both';
      NO_ASSERT_CHECK='TRUE';
      NO_DIR_CHECK='TRUE';
      ALLOW_CONNECT='TRUE';
    'VSS_D2':
      PIN_NUMBER='(0,0,0,0,0,0,0,0,0,0,0,0,0,0,0,0,0,0,0,0,0,0,0,0,0,0,0,D2,0,0,~
0,0,0,0,0,0,0,0,0,0)';
      PINUSE='POWER';
      NO_LOAD_CHECK='Both';
      NO_IO_CHECK='Both';
      NO_ASSERT_CHECK='TRUE';
      NO_DIR_CHECK='TRUE';
      ALLOW_CONNECT='TRUE';
    'VSS_D3':
      PIN_NUMBER='(0,0,0,0,0,0,0,0,0,0,0,0,0,0,0,0,0,0,0,0,0,0,0,0,0,0,0,D3,0,0,~
0,0,0,0,0,0,0,0,0,0)';
      PINUSE='POWER';
      NO_LOAD_CHECK='Both';
      NO_IO_CHECK='Both';
      NO_ASSERT_CHECK='TRUE';
      NO_DIR_CHECK='TRUE';
      ALLOW_CONNECT='TRUE';
    'VSS_D5':
      PIN_NUMBER='(0,0,0,0,0,0,0,0,0,0,0,0,0,0,0,0,0,0,0,0,0,0,0,0,0,0,0,D5,0,0,~
0,0,0,0,0,0,0,0,0,0)';
      PINUSE='POWER';
      NO_LOAD_CHECK='Both';
      NO_IO_CHECK='Both';
      NO_ASSERT_CHECK='TRUE';
      NO_DIR_CHECK='TRUE';
      ALLOW_CONNECT='TRUE';
    'VSS_D6':
      PIN_NUMBER='(0,0,0,0,0,0,0,0,0,0,0,0,0,0,0,0,0,0,0,0,0,0,0,0,0,0,0,D6,0,0,~
0,0,0,0,0,0,0,0,0,0)';
      PINUSE='POWER';
      NO_LOAD_CHECK='Both';
      NO_IO_CHECK='Both';
      NO_ASSERT_CHECK='TRUE';
      NO_DIR_CHECK='TRUE';
      ALLOW_CONNECT='TRUE';
    'VSS_D9':
      PIN_NUMBER='(0,0,0,0,0,0,0,0,0,0,0,0,0,0,0,0,0,0,0,0,0,0,0,0,0,0,0,D9,0,0,~
0,0,0,0,0,0,0,0,0,0)';
      PINUSE='POWER';
      NO_LOAD_CHECK='Both';
      NO_IO_CHECK='Both';
      NO_ASSERT_CHECK='TRUE';
      NO_DIR_CHECK='TRUE';
      ALLOW_CONNECT='TRUE';
    'VSS_D10':
      PIN_NUMBER='(0,0,0,0,0,0,0,0,0,0,0,0,0,0,0,0,0,0,0,0,0,0,0,0,0,0,0,D10,0,0~
,0,0,0,0,0,0,0,0,0,0)';
      PINUSE='POWER';
      NO_LOAD_CHECK='Both';
      NO_IO_CHECK='Both';
      NO_ASSERT_CHECK='TRUE';
      NO_DIR_CHECK='TRUE';
      ALLOW_CONNECT='TRUE';
    'VSS_D12':
      PIN_NUMBER='(0,0,0,0,0,0,0,0,0,0,0,0,0,0,0,0,0,0,0,0,0,0,0,0,0,0,0,D12,0,0~
,0,0,0,0,0,0,0,0,0,0)';
      PINUSE='POWER';
      NO_LOAD_CHECK='Both';
      NO_IO_CHECK='Both';
      NO_ASSERT_CHECK='TRUE';
      NO_DIR_CHECK='TRUE';
      ALLOW_CONNECT='TRUE';
    'VSS_D13':
      PIN_NUMBER='(0,0,0,0,0,0,0,0,0,0,0,0,0,0,0,0,0,0,0,0,0,0,0,0,0,0,0,D13,0,0~
,0,0,0,0,0,0,0,0,0,0)';
      PINUSE='POWER';
      NO_LOAD_CHECK='Both';
      NO_IO_CHECK='Both';
      NO_ASSERT_CHECK='TRUE';
      NO_DIR_CHECK='TRUE';
      ALLOW_CONNECT='TRUE';
    'VSS_D16':
      PIN_NUMBER='(0,0,0,0,0,0,0,0,0,0,0,0,0,0,0,0,0,0,0,0,0,0,0,0,0,0,0,D16,0,0~
,0,0,0,0,0,0,0,0,0,0)';
      PINUSE='POWER';
      NO_LOAD_CHECK='Both';
      NO_IO_CHECK='Both';
      NO_ASSERT_CHECK='TRUE';
      NO_DIR_CHECK='TRUE';
      ALLOW_CONNECT='TRUE';
    'VSS_D17':
      PIN_NUMBER='(0,0,0,0,0,0,0,0,0,0,0,0,0,0,0,0,0,0,0,0,0,0,0,0,0,0,0,D17,0,0~
,0,0,0,0,0,0,0,0,0,0)';
      PINUSE='POWER';
      NO_LOAD_CHECK='Both';
      NO_IO_CHECK='Both';
      NO_ASSERT_CHECK='TRUE';
      NO_DIR_CHECK='TRUE';
      ALLOW_CONNECT='TRUE';
    'VSS_D19':
      PIN_NUMBER='(0,0,0,0,0,0,0,0,0,0,0,0,0,0,0,0,0,0,0,0,0,0,0,0,0,0,0,D19,0,0~
,0,0,0,0,0,0,0,0,0,0)';
      PINUSE='POWER';
      NO_LOAD_CHECK='Both';
      NO_IO_CHECK='Both';
      NO_ASSERT_CHECK='TRUE';
      NO_DIR_CHECK='TRUE';
      ALLOW_CONNECT='TRUE';
    'VSS_D20':
      PIN_NUMBER='(0,0,0,0,0,0,0,0,0,0,0,0,0,0,0,0,0,0,0,0,0,0,0,0,0,0,0,D20,0,0~
,0,0,0,0,0,0,0,0,0,0)';
      PINUSE='POWER';
      NO_LOAD_CHECK='Both';
      NO_IO_CHECK='Both';
      NO_ASSERT_CHECK='TRUE';
      NO_DIR_CHECK='TRUE';
      ALLOW_CONNECT='TRUE';
    'VSS_D21':
      PIN_NUMBER='(0,0,0,0,0,0,0,0,0,0,0,0,0,0,0,0,0,0,0,0,0,0,0,0,0,0,0,D21,0,0~
,0,0,0,0,0,0,0,0,0,0)';
      PINUSE='POWER';
      NO_LOAD_CHECK='Both';
      NO_IO_CHECK='Both';
      NO_ASSERT_CHECK='TRUE';
      NO_DIR_CHECK='TRUE';
      ALLOW_CONNECT='TRUE';
    'VSS_D24':
      PIN_NUMBER='(0,0,0,0,0,0,0,0,0,0,0,0,0,0,0,0,0,0,0,0,0,0,0,0,0,0,0,D24,0,0~
,0,0,0,0,0,0,0,0,0,0)';
      PINUSE='POWER';
      NO_LOAD_CHECK='Both';
      NO_IO_CHECK='Both';
      NO_ASSERT_CHECK='TRUE';
      NO_DIR_CHECK='TRUE';
      ALLOW_CONNECT='TRUE';
    'VSS_D25':
      PIN_NUMBER='(0,0,0,0,0,0,0,0,0,0,0,0,0,0,0,0,0,0,0,0,0,0,0,0,0,0,0,D25,0,0~
,0,0,0,0,0,0,0,0,0,0)';
      PINUSE='POWER';
      NO_LOAD_CHECK='Both';
      NO_IO_CHECK='Both';
      NO_ASSERT_CHECK='TRUE';
      NO_DIR_CHECK='TRUE';
      ALLOW_CONNECT='TRUE';
    'VSS_D26':
      PIN_NUMBER='(0,0,0,0,0,0,0,0,0,0,0,0,0,0,0,0,0,0,0,0,0,0,0,0,0,0,0,D26,0,0~
,0,0,0,0,0,0,0,0,0,0)';
      PINUSE='POWER';
      NO_LOAD_CHECK='Both';
      NO_IO_CHECK='Both';
      NO_ASSERT_CHECK='TRUE';
      NO_DIR_CHECK='TRUE';
      ALLOW_CONNECT='TRUE';
    'VSS_D27':
      PIN_NUMBER='(0,0,0,0,0,0,0,0,0,0,0,0,0,0,0,0,0,0,0,0,0,0,0,0,0,0,0,D27,0,0~
,0,0,0,0,0,0,0,0,0,0)';
      PINUSE='POWER';
      NO_LOAD_CHECK='Both';
      NO_IO_CHECK='Both';
      NO_ASSERT_CHECK='TRUE';
      NO_DIR_CHECK='TRUE';
      ALLOW_CONNECT='TRUE';
    'VSS_D28':
      PIN_NUMBER='(0,0,0,0,0,0,0,0,0,0,0,0,0,0,0,0,0,0,0,0,0,0,0,0,0,0,0,D28,0,0~
,0,0,0,0,0,0,0,0,0,0)';
      PINUSE='POWER';
      NO_LOAD_CHECK='Both';
      NO_IO_CHECK='Both';
      NO_ASSERT_CHECK='TRUE';
      NO_DIR_CHECK='TRUE';
      ALLOW_CONNECT='TRUE';
    'VSS_D29':
      PIN_NUMBER='(0,0,0,0,0,0,0,0,0,0,0,0,0,0,0,0,0,0,0,0,0,0,0,0,0,0,0,D29,0,0~
,0,0,0,0,0,0,0,0,0,0)';
      PINUSE='POWER';
      NO_LOAD_CHECK='Both';
      NO_IO_CHECK='Both';
      NO_ASSERT_CHECK='TRUE';
      NO_DIR_CHECK='TRUE';
      ALLOW_CONNECT='TRUE';
    'VSS_D30':
      PIN_NUMBER='(0,0,0,0,0,0,0,0,0,0,0,0,0,0,0,0,0,0,0,0,0,0,0,0,0,0,0,D30,0,0~
,0,0,0,0,0,0,0,0,0,0)';
      PINUSE='POWER';
      NO_LOAD_CHECK='Both';
      NO_IO_CHECK='Both';
      NO_ASSERT_CHECK='TRUE';
      NO_DIR_CHECK='TRUE';
      ALLOW_CONNECT='TRUE';
    'VSS_D31':
      PIN_NUMBER='(0,0,0,0,0,0,0,0,0,0,0,0,0,0,0,0,0,0,0,0,0,0,0,0,0,0,0,D31,0,0~
,0,0,0,0,0,0,0,0,0,0)';
      PINUSE='POWER';
      NO_LOAD_CHECK='Both';
      NO_IO_CHECK='Both';
      NO_ASSERT_CHECK='TRUE';
      NO_DIR_CHECK='TRUE';
      ALLOW_CONNECT='TRUE';
    'VSS_D35':
      PIN_NUMBER='(0,0,0,0,0,0,0,0,0,0,0,0,0,0,0,0,0,0,0,0,0,0,0,0,0,0,0,D35,0,0~
,0,0,0,0,0,0,0,0,0,0)';
      PINUSE='POWER';
      NO_LOAD_CHECK='Both';
      NO_IO_CHECK='Both';
      NO_ASSERT_CHECK='TRUE';
      NO_DIR_CHECK='TRUE';
      ALLOW_CONNECT='TRUE';
    'VSS_D37':
      PIN_NUMBER='(0,0,0,0,0,0,0,0,0,0,0,0,0,0,0,0,0,0,0,0,0,0,0,0,0,0,0,D37,0,0~
,0,0,0,0,0,0,0,0,0,0)';
      PINUSE='POWER';
      NO_LOAD_CHECK='Both';
      NO_IO_CHECK='Both';
      NO_ASSERT_CHECK='TRUE';
      NO_DIR_CHECK='TRUE';
      ALLOW_CONNECT='TRUE';
    'VSS_D39':
      PIN_NUMBER='(0,0,0,0,0,0,0,0,0,0,0,0,0,0,0,0,0,0,0,0,0,0,0,0,0,0,0,D39,0,0~
,0,0,0,0,0,0,0,0,0,0)';
      PINUSE='POWER';
      NO_LOAD_CHECK='Both';
      NO_IO_CHECK='Both';
      NO_ASSERT_CHECK='TRUE';
      NO_DIR_CHECK='TRUE';
      ALLOW_CONNECT='TRUE';
    'VSS_D40':
      PIN_NUMBER='(0,0,0,0,0,0,0,0,0,0,0,0,0,0,0,0,0,0,0,0,0,0,0,0,0,0,0,D40,0,0~
,0,0,0,0,0,0,0,0,0,0)';
      PINUSE='POWER';
      NO_LOAD_CHECK='Both';
      NO_IO_CHECK='Both';
      NO_ASSERT_CHECK='TRUE';
      NO_DIR_CHECK='TRUE';
      ALLOW_CONNECT='TRUE';
    'VSS_D41':
      PIN_NUMBER='(0,0,0,0,0,0,0,0,0,0,0,0,0,0,0,0,0,0,0,0,0,0,0,0,0,0,0,D41,0,0~
,0,0,0,0,0,0,0,0,0,0)';
      PINUSE='POWER';
      NO_LOAD_CHECK='Both';
      NO_IO_CHECK='Both';
      NO_ASSERT_CHECK='TRUE';
      NO_DIR_CHECK='TRUE';
      ALLOW_CONNECT='TRUE';
    'VSS_D42':
      PIN_NUMBER='(0,0,0,0,0,0,0,0,0,0,0,0,0,0,0,0,0,0,0,0,0,0,0,0,0,0,0,D42,0,0~
,0,0,0,0,0,0,0,0,0,0)';
      PINUSE='POWER';
      NO_LOAD_CHECK='Both';
      NO_IO_CHECK='Both';
      NO_ASSERT_CHECK='TRUE';
      NO_DIR_CHECK='TRUE';
      ALLOW_CONNECT='TRUE';
    'VSS_D43':
      PIN_NUMBER='(0,0,0,0,0,0,0,0,0,0,0,0,0,0,0,0,0,0,0,0,0,0,0,0,0,0,0,D43,0,0~
,0,0,0,0,0,0,0,0,0,0)';
      PINUSE='POWER';
      NO_LOAD_CHECK='Both';
      NO_IO_CHECK='Both';
      NO_ASSERT_CHECK='TRUE';
      NO_DIR_CHECK='TRUE';
      ALLOW_CONNECT='TRUE';
    'VSS_D44':
      PIN_NUMBER='(0,0,0,0,0,0,0,0,0,0,0,0,0,0,0,0,0,0,0,0,0,0,0,0,0,0,0,D44,0,0~
,0,0,0,0,0,0,0,0,0,0)';
      PINUSE='POWER';
      NO_LOAD_CHECK='Both';
      NO_IO_CHECK='Both';
      NO_ASSERT_CHECK='TRUE';
      NO_DIR_CHECK='TRUE';
      ALLOW_CONNECT='TRUE';
    'VSS_D45':
      PIN_NUMBER='(0,0,0,0,0,0,0,0,0,0,0,0,0,0,0,0,0,0,0,0,0,0,0,0,0,0,0,D45,0,0~
,0,0,0,0,0,0,0,0,0,0)';
      PINUSE='POWER';
      NO_LOAD_CHECK='Both';
      NO_IO_CHECK='Both';
      NO_ASSERT_CHECK='TRUE';
      NO_DIR_CHECK='TRUE';
      ALLOW_CONNECT='TRUE';
    'VSS_D46':
      PIN_NUMBER='(0,0,0,0,0,0,0,0,0,0,0,0,0,0,0,0,0,0,0,0,0,0,0,0,0,0,0,D46,0,0~
,0,0,0,0,0,0,0,0,0,0)';
      PINUSE='POWER';
      NO_LOAD_CHECK='Both';
      NO_IO_CHECK='Both';
      NO_ASSERT_CHECK='TRUE';
      NO_DIR_CHECK='TRUE';
      ALLOW_CONNECT='TRUE';
    'VSS_D47':
      PIN_NUMBER='(0,0,0,0,0,0,0,0,0,0,0,0,0,0,0,0,0,0,0,0,0,0,0,0,0,0,0,D47,0,0~
,0,0,0,0,0,0,0,0,0,0)';
      PINUSE='POWER';
      NO_LOAD_CHECK='Both';
      NO_IO_CHECK='Both';
      NO_ASSERT_CHECK='TRUE';
      NO_DIR_CHECK='TRUE';
      ALLOW_CONNECT='TRUE';
    'VSS_D48':
      PIN_NUMBER='(0,0,0,0,0,0,0,0,0,0,0,0,0,0,0,0,0,0,0,0,0,0,0,0,0,0,0,D48,0,0~
,0,0,0,0,0,0,0,0,0,0)';
      PINUSE='POWER';
      NO_LOAD_CHECK='Both';
      NO_IO_CHECK='Both';
      NO_ASSERT_CHECK='TRUE';
      NO_DIR_CHECK='TRUE';
      ALLOW_CONNECT='TRUE';
    'VSS_D49':
      PIN_NUMBER='(0,0,0,0,0,0,0,0,0,0,0,0,0,0,0,0,0,0,0,0,0,0,0,0,0,0,0,D49,0,0~
,0,0,0,0,0,0,0,0,0,0)';
      PINUSE='POWER';
      NO_LOAD_CHECK='Both';
      NO_IO_CHECK='Both';
      NO_ASSERT_CHECK='TRUE';
      NO_DIR_CHECK='TRUE';
      ALLOW_CONNECT='TRUE';
    'VSS_D50':
      PIN_NUMBER='(0,0,0,0,0,0,0,0,0,0,0,0,0,0,0,0,0,0,0,0,0,0,0,0,0,0,0,D50,0,0~
,0,0,0,0,0,0,0,0,0,0)';
      PINUSE='POWER';
      NO_LOAD_CHECK='Both';
      NO_IO_CHECK='Both';
      NO_ASSERT_CHECK='TRUE';
      NO_DIR_CHECK='TRUE';
      ALLOW_CONNECT='TRUE';
    'VSS_D51':
      PIN_NUMBER='(0,0,0,0,0,0,0,0,0,0,0,0,0,0,0,0,0,0,0,0,0,0,0,0,0,0,0,D51,0,0~
,0,0,0,0,0,0,0,0,0,0)';
      PINUSE='POWER';
      NO_LOAD_CHECK='Both';
      NO_IO_CHECK='Both';
      NO_ASSERT_CHECK='TRUE';
      NO_DIR_CHECK='TRUE';
      ALLOW_CONNECT='TRUE';
    'VSS_D52':
      PIN_NUMBER='(0,0,0,0,0,0,0,0,0,0,0,0,0,0,0,0,0,0,0,0,0,0,0,0,0,0,0,D52,0,0~
,0,0,0,0,0,0,0,0,0,0)';
      PINUSE='POWER';
      NO_LOAD_CHECK='Both';
      NO_IO_CHECK='Both';
      NO_ASSERT_CHECK='TRUE';
      NO_DIR_CHECK='TRUE';
      ALLOW_CONNECT='TRUE';
    'VSS_D53':
      PIN_NUMBER='(0,0,0,0,0,0,0,0,0,0,0,0,0,0,0,0,0,0,0,0,0,0,0,0,0,0,0,D53,0,0~
,0,0,0,0,0,0,0,0,0,0)';
      PINUSE='POWER';
      NO_LOAD_CHECK='Both';
      NO_IO_CHECK='Both';
      NO_ASSERT_CHECK='TRUE';
      NO_DIR_CHECK='TRUE';
      ALLOW_CONNECT='TRUE';
    'VSS_D54':
      PIN_NUMBER='(0,0,0,0,0,0,0,0,0,0,0,0,0,0,0,0,0,0,0,0,0,0,0,0,0,0,0,D54,0,0~
,0,0,0,0,0,0,0,0,0,0)';
      PINUSE='POWER';
      NO_LOAD_CHECK='Both';
      NO_IO_CHECK='Both';
      NO_ASSERT_CHECK='TRUE';
      NO_DIR_CHECK='TRUE';
      ALLOW_CONNECT='TRUE';
    'VSS_D57':
      PIN_NUMBER='(0,0,0,0,0,0,0,0,0,0,0,0,0,0,0,0,0,0,0,0,0,0,0,0,0,0,0,D57,0,0~
,0,0,0,0,0,0,0,0,0,0)';
      PINUSE='POWER';
      NO_LOAD_CHECK='Both';
      NO_IO_CHECK='Both';
      NO_ASSERT_CHECK='TRUE';
      NO_DIR_CHECK='TRUE';
      ALLOW_CONNECT='TRUE';
    'VSS_D59':
      PIN_NUMBER='(0,0,0,0,0,0,0,0,0,0,0,0,0,0,0,0,0,0,0,0,0,0,0,0,0,0,0,D59,0,0~
,0,0,0,0,0,0,0,0,0,0)';
      PINUSE='POWER';
      NO_LOAD_CHECK='Both';
      NO_IO_CHECK='Both';
      NO_ASSERT_CHECK='TRUE';
      NO_DIR_CHECK='TRUE';
      ALLOW_CONNECT='TRUE';
    'VSS_D60':
      PIN_NUMBER='(0,0,0,0,0,0,0,0,0,0,0,0,0,0,0,0,0,0,0,0,0,0,0,0,0,0,0,D60,0,0~
,0,0,0,0,0,0,0,0,0,0)';
      PINUSE='POWER';
      NO_LOAD_CHECK='Both';
      NO_IO_CHECK='Both';
      NO_ASSERT_CHECK='TRUE';
      NO_DIR_CHECK='TRUE';
      ALLOW_CONNECT='TRUE';
    'VSS_D61':
      PIN_NUMBER='(0,0,0,0,0,0,0,0,0,0,0,0,0,0,0,0,0,0,0,0,0,0,0,0,0,0,0,D61,0,0~
,0,0,0,0,0,0,0,0,0,0)';
      PINUSE='POWER';
      NO_LOAD_CHECK='Both';
      NO_IO_CHECK='Both';
      NO_ASSERT_CHECK='TRUE';
      NO_DIR_CHECK='TRUE';
      ALLOW_CONNECT='TRUE';
    'VSS_D63':
      PIN_NUMBER='(0,0,0,0,0,0,0,0,0,0,0,0,0,0,0,0,0,0,0,0,0,0,0,0,0,0,0,D63,0,0~
,0,0,0,0,0,0,0,0,0,0)';
      PINUSE='POWER';
      NO_LOAD_CHECK='Both';
      NO_IO_CHECK='Both';
      NO_ASSERT_CHECK='TRUE';
      NO_DIR_CHECK='TRUE';
      ALLOW_CONNECT='TRUE';
    'VSS_D64':
      PIN_NUMBER='(0,0,0,0,0,0,0,0,0,0,0,0,0,0,0,0,0,0,0,0,0,0,0,0,0,0,0,D64,0,0~
,0,0,0,0,0,0,0,0,0,0)';
      PINUSE='POWER';
      NO_LOAD_CHECK='Both';
      NO_IO_CHECK='Both';
      NO_ASSERT_CHECK='TRUE';
      NO_DIR_CHECK='TRUE';
      ALLOW_CONNECT='TRUE';
    'VSS_D66':
      PIN_NUMBER='(0,0,0,0,0,0,0,0,0,0,0,0,0,0,0,0,0,0,0,0,0,0,0,0,0,0,0,D66,0,0~
,0,0,0,0,0,0,0,0,0,0)';
      PINUSE='POWER';
      NO_LOAD_CHECK='Both';
      NO_IO_CHECK='Both';
      NO_ASSERT_CHECK='TRUE';
      NO_DIR_CHECK='TRUE';
      ALLOW_CONNECT='TRUE';
    'VSS_D67':
      PIN_NUMBER='(0,0,0,0,0,0,0,0,0,0,0,0,0,0,0,0,0,0,0,0,0,0,0,0,0,0,0,D67,0,0~
,0,0,0,0,0,0,0,0,0,0)';
      PINUSE='POWER';
      NO_LOAD_CHECK='Both';
      NO_IO_CHECK='Both';
      NO_ASSERT_CHECK='TRUE';
      NO_DIR_CHECK='TRUE';
      ALLOW_CONNECT='TRUE';
    'VSS_D70':
      PIN_NUMBER='(0,0,0,0,0,0,0,0,0,0,0,0,0,0,0,0,0,0,0,0,0,0,0,0,0,0,0,D70,0,0~
,0,0,0,0,0,0,0,0,0,0)';
      PINUSE='POWER';
      NO_LOAD_CHECK='Both';
      NO_IO_CHECK='Both';
      NO_ASSERT_CHECK='TRUE';
      NO_DIR_CHECK='TRUE';
      ALLOW_CONNECT='TRUE';
    'VSS_D71':
      PIN_NUMBER='(0,0,0,0,0,0,0,0,0,0,0,0,0,0,0,0,0,0,0,0,0,0,0,0,0,0,0,D71,0,0~
,0,0,0,0,0,0,0,0,0,0)';
      PINUSE='POWER';
      NO_LOAD_CHECK='Both';
      NO_IO_CHECK='Both';
      NO_ASSERT_CHECK='TRUE';
      NO_DIR_CHECK='TRUE';
      ALLOW_CONNECT='TRUE';
    'VSS_D73':
      PIN_NUMBER='(0,0,0,0,0,0,0,0,0,0,0,0,0,0,0,0,0,0,0,0,0,0,0,0,0,0,0,D73,0,0~
,0,0,0,0,0,0,0,0,0,0)';
      PINUSE='POWER';
      NO_LOAD_CHECK='Both';
      NO_IO_CHECK='Both';
      NO_ASSERT_CHECK='TRUE';
      NO_DIR_CHECK='TRUE';
      ALLOW_CONNECT='TRUE';
    'VSS_D74':
      PIN_NUMBER='(0,0,0,0,0,0,0,0,0,0,0,0,0,0,0,0,0,0,0,0,0,0,0,0,0,0,0,D74,0,0~
,0,0,0,0,0,0,0,0,0,0)';
      PINUSE='POWER';
      NO_LOAD_CHECK='Both';
      NO_IO_CHECK='Both';
      NO_ASSERT_CHECK='TRUE';
      NO_DIR_CHECK='TRUE';
      ALLOW_CONNECT='TRUE';
    'VSS_E1':
      PIN_NUMBER='(0,0,0,0,0,0,0,0,0,0,0,0,0,0,0,0,0,0,0,0,0,0,0,0,0,0,0,E1,0,0,~
0,0,0,0,0,0,0,0,0,0)';
      PINUSE='POWER';
      NO_LOAD_CHECK='Both';
      NO_IO_CHECK='Both';
      NO_ASSERT_CHECK='TRUE';
      NO_DIR_CHECK='TRUE';
      ALLOW_CONNECT='TRUE';
    'VSS_E3':
      PIN_NUMBER='(0,0,0,0,0,0,0,0,0,0,0,0,0,0,0,0,0,0,0,0,0,0,0,0,0,0,0,E3,0,0,~
0,0,0,0,0,0,0,0,0,0)';
      PINUSE='POWER';
      NO_LOAD_CHECK='Both';
      NO_IO_CHECK='Both';
      NO_ASSERT_CHECK='TRUE';
      NO_DIR_CHECK='TRUE';
      ALLOW_CONNECT='TRUE';
    'VSS_E6':
      PIN_NUMBER='(0,0,0,0,0,0,0,0,0,0,0,0,0,0,0,0,0,0,0,0,0,0,0,0,0,0,0,E6,0,0,~
0,0,0,0,0,0,0,0,0,0)';
      PINUSE='POWER';
      NO_LOAD_CHECK='Both';
      NO_IO_CHECK='Both';
      NO_ASSERT_CHECK='TRUE';
      NO_DIR_CHECK='TRUE';
      ALLOW_CONNECT='TRUE';
    'VSS_E7':
      PIN_NUMBER='(0,0,0,0,0,0,0,0,0,0,0,0,0,0,0,0,0,0,0,0,0,0,0,0,0,0,0,E7,0,0,~
0,0,0,0,0,0,0,0,0,0)';
      PINUSE='POWER';
      NO_LOAD_CHECK='Both';
      NO_IO_CHECK='Both';
      NO_ASSERT_CHECK='TRUE';
      NO_DIR_CHECK='TRUE';
      ALLOW_CONNECT='TRUE';
    'VSS_E8':
      PIN_NUMBER='(0,0,0,0,0,0,0,0,0,0,0,0,0,0,0,0,0,0,0,0,0,0,0,0,0,0,0,E8,0,0,~
0,0,0,0,0,0,0,0,0,0)';
      PINUSE='POWER';
      NO_LOAD_CHECK='Both';
      NO_IO_CHECK='Both';
      NO_ASSERT_CHECK='TRUE';
      NO_DIR_CHECK='TRUE';
      ALLOW_CONNECT='TRUE';
    'VSS_E10':
      PIN_NUMBER='(0,0,0,0,0,0,0,0,0,0,0,0,0,0,0,0,0,0,0,0,0,0,0,0,0,0,0,E10,0,0~
,0,0,0,0,0,0,0,0,0,0)';
      PINUSE='POWER';
      NO_LOAD_CHECK='Both';
      NO_IO_CHECK='Both';
      NO_ASSERT_CHECK='TRUE';
      NO_DIR_CHECK='TRUE';
      ALLOW_CONNECT='TRUE';
    'VSS_E13':
      PIN_NUMBER='(0,0,0,0,0,0,0,0,0,0,0,0,0,0,0,0,0,0,0,0,0,0,0,0,0,0,0,E13,0,0~
,0,0,0,0,0,0,0,0,0,0)';
      PINUSE='POWER';
      NO_LOAD_CHECK='Both';
      NO_IO_CHECK='Both';
      NO_ASSERT_CHECK='TRUE';
      NO_DIR_CHECK='TRUE';
      ALLOW_CONNECT='TRUE';
    'VSS_E14':
      PIN_NUMBER='(0,0,0,0,0,0,0,0,0,0,0,0,0,0,0,0,0,0,0,0,0,0,0,0,0,0,0,E14,0,0~
,0,0,0,0,0,0,0,0,0,0)';
      PINUSE='POWER';
      NO_LOAD_CHECK='Both';
      NO_IO_CHECK='Both';
      NO_ASSERT_CHECK='TRUE';
      NO_DIR_CHECK='TRUE';
      ALLOW_CONNECT='TRUE';
    'VSS_E15':
      PIN_NUMBER='(0,0,0,0,0,0,0,0,0,0,0,0,0,0,0,0,0,0,0,0,0,0,0,0,0,0,0,E15,0,0~
,0,0,0,0,0,0,0,0,0,0)';
      PINUSE='POWER';
      NO_LOAD_CHECK='Both';
      NO_IO_CHECK='Both';
      NO_ASSERT_CHECK='TRUE';
      NO_DIR_CHECK='TRUE';
      ALLOW_CONNECT='TRUE';
    'VSS_E17':
      PIN_NUMBER='(0,0,0,0,0,0,0,0,0,0,0,0,0,0,0,0,0,0,0,0,0,0,0,0,0,0,0,E17,0,0~
,0,0,0,0,0,0,0,0,0,0)';
      PINUSE='POWER';
      NO_LOAD_CHECK='Both';
      NO_IO_CHECK='Both';
      NO_ASSERT_CHECK='TRUE';
      NO_DIR_CHECK='TRUE';
      ALLOW_CONNECT='TRUE';
    'VSS_E18':
      PIN_NUMBER='(0,0,0,0,0,0,0,0,0,0,0,0,0,0,0,0,0,0,0,0,0,0,0,0,0,0,0,E18,0,0~
,0,0,0,0,0,0,0,0,0,0)';
      PINUSE='POWER';
      NO_LOAD_CHECK='Both';
      NO_IO_CHECK='Both';
      NO_ASSERT_CHECK='TRUE';
      NO_DIR_CHECK='TRUE';
      ALLOW_CONNECT='TRUE';
    'VSS_E20':
      PIN_NUMBER='(0,0,0,0,0,0,0,0,0,0,0,0,0,0,0,0,0,0,0,0,0,0,0,0,0,0,0,E20,0,0~
,0,0,0,0,0,0,0,0,0,0)';
      PINUSE='POWER';
      NO_LOAD_CHECK='Both';
      NO_IO_CHECK='Both';
      NO_ASSERT_CHECK='TRUE';
      NO_DIR_CHECK='TRUE';
      ALLOW_CONNECT='TRUE';
    'VSS_E21':
      PIN_NUMBER='(0,0,0,0,0,0,0,0,0,0,0,0,0,0,0,0,0,0,0,0,0,0,0,0,0,0,0,E21,0,0~
,0,0,0,0,0,0,0,0,0,0)';
      PINUSE='POWER';
      NO_LOAD_CHECK='Both';
      NO_IO_CHECK='Both';
      NO_ASSERT_CHECK='TRUE';
      NO_DIR_CHECK='TRUE';
      ALLOW_CONNECT='TRUE';
    'VSS_E52':
      PIN_NUMBER='(0,0,0,0,0,0,0,0,0,0,0,0,0,0,0,0,0,0,0,0,0,0,0,0,0,0,0,E52,0,0~
,0,0,0,0,0,0,0,0,0,0)';
      PINUSE='POWER';
      NO_LOAD_CHECK='Both';
      NO_IO_CHECK='Both';
      NO_ASSERT_CHECK='TRUE';
      NO_DIR_CHECK='TRUE';
      ALLOW_CONNECT='TRUE';
    'VSS_E53':
      PIN_NUMBER='(0,0,0,0,0,0,0,0,0,0,0,0,0,0,0,0,0,0,0,0,0,0,0,0,0,0,0,E53,0,0~
,0,0,0,0,0,0,0,0,0,0)';
      PINUSE='POWER';
      NO_LOAD_CHECK='Both';
      NO_IO_CHECK='Both';
      NO_ASSERT_CHECK='TRUE';
      NO_DIR_CHECK='TRUE';
      ALLOW_CONNECT='TRUE';
    'VSS_E55':
      PIN_NUMBER='(0,0,0,0,0,0,0,0,0,0,0,0,0,0,0,0,0,0,0,0,0,0,0,0,0,0,0,E55,0,0~
,0,0,0,0,0,0,0,0,0,0)';
      PINUSE='POWER';
      NO_LOAD_CHECK='Both';
      NO_IO_CHECK='Both';
      NO_ASSERT_CHECK='TRUE';
      NO_DIR_CHECK='TRUE';
      ALLOW_CONNECT='TRUE';
    'VSS_E56':
      PIN_NUMBER='(0,0,0,0,0,0,0,0,0,0,0,0,0,0,0,0,0,0,0,0,0,0,0,0,0,0,0,E56,0,0~
,0,0,0,0,0,0,0,0,0,0)';
      PINUSE='POWER';
      NO_LOAD_CHECK='Both';
      NO_IO_CHECK='Both';
      NO_ASSERT_CHECK='TRUE';
      NO_DIR_CHECK='TRUE';
      ALLOW_CONNECT='TRUE';
    'VSS_E58':
      PIN_NUMBER='(0,0,0,0,0,0,0,0,0,0,0,0,0,0,0,0,0,0,0,0,0,0,0,0,0,0,0,E58,0,0~
,0,0,0,0,0,0,0,0,0,0)';
      PINUSE='POWER';
      NO_LOAD_CHECK='Both';
      NO_IO_CHECK='Both';
      NO_ASSERT_CHECK='TRUE';
      NO_DIR_CHECK='TRUE';
      ALLOW_CONNECT='TRUE';
    'VSS_E59':
      PIN_NUMBER='(0,0,0,0,0,0,0,0,0,0,0,0,0,0,0,0,0,0,0,0,0,0,0,0,0,0,0,E59,0,0~
,0,0,0,0,0,0,0,0,0,0)';
      PINUSE='POWER';
      NO_LOAD_CHECK='Both';
      NO_IO_CHECK='Both';
      NO_ASSERT_CHECK='TRUE';
      NO_DIR_CHECK='TRUE';
      ALLOW_CONNECT='TRUE';
    'VSS_E61':
      PIN_NUMBER='(0,0,0,0,0,0,0,0,0,0,0,0,0,0,0,0,0,0,0,0,0,0,0,0,0,0,0,E61,0,0~
,0,0,0,0,0,0,0,0,0,0)';
      PINUSE='POWER';
      NO_LOAD_CHECK='Both';
      NO_IO_CHECK='Both';
      NO_ASSERT_CHECK='TRUE';
      NO_DIR_CHECK='TRUE';
      ALLOW_CONNECT='TRUE';
    'VSS_E62':
      PIN_NUMBER='(0,0,0,0,0,0,0,0,0,0,0,0,0,0,0,0,0,0,0,0,0,0,0,0,0,0,0,E62,0,0~
,0,0,0,0,0,0,0,0,0,0)';
      PINUSE='POWER';
      NO_LOAD_CHECK='Both';
      NO_IO_CHECK='Both';
      NO_ASSERT_CHECK='TRUE';
      NO_DIR_CHECK='TRUE';
      ALLOW_CONNECT='TRUE';
    'VSS_E63':
      PIN_NUMBER='(0,0,0,0,0,0,0,0,0,0,0,0,0,0,0,0,0,0,0,0,0,0,0,0,0,0,0,E63,0,0~
,0,0,0,0,0,0,0,0,0,0)';
      PINUSE='POWER';
      NO_LOAD_CHECK='Both';
      NO_IO_CHECK='Both';
      NO_ASSERT_CHECK='TRUE';
      NO_DIR_CHECK='TRUE';
      ALLOW_CONNECT='TRUE';
    'VSS_E65':
      PIN_NUMBER='(0,0,0,0,0,0,0,0,0,0,0,0,0,0,0,0,0,0,0,0,0,0,0,0,0,0,0,E65,0,0~
,0,0,0,0,0,0,0,0,0,0)';
      PINUSE='POWER';
      NO_LOAD_CHECK='Both';
      NO_IO_CHECK='Both';
      NO_ASSERT_CHECK='TRUE';
      NO_DIR_CHECK='TRUE';
      ALLOW_CONNECT='TRUE';
    'VSS_E66':
      PIN_NUMBER='(0,0,0,0,0,0,0,0,0,0,0,0,0,0,0,0,0,0,0,0,0,0,0,0,0,0,0,E66,0,0~
,0,0,0,0,0,0,0,0,0,0)';
      PINUSE='POWER';
      NO_LOAD_CHECK='Both';
      NO_IO_CHECK='Both';
      NO_ASSERT_CHECK='TRUE';
      NO_DIR_CHECK='TRUE';
      ALLOW_CONNECT='TRUE';
    'VSS_E68':
      PIN_NUMBER='(0,0,0,0,0,0,0,0,0,0,0,0,0,0,0,0,0,0,0,0,0,0,0,0,0,0,0,E68,0,0~
,0,0,0,0,0,0,0,0,0,0)';
      PINUSE='POWER';
      NO_LOAD_CHECK='Both';
      NO_IO_CHECK='Both';
      NO_ASSERT_CHECK='TRUE';
      NO_DIR_CHECK='TRUE';
      ALLOW_CONNECT='TRUE';
    'VSS_E69':
      PIN_NUMBER='(0,0,0,0,0,0,0,0,0,0,0,0,0,0,0,0,0,0,0,0,0,0,0,0,0,0,0,E69,0,0~
,0,0,0,0,0,0,0,0,0,0)';
      PINUSE='POWER';
      NO_LOAD_CHECK='Both';
      NO_IO_CHECK='Both';
      NO_ASSERT_CHECK='TRUE';
      NO_DIR_CHECK='TRUE';
      ALLOW_CONNECT='TRUE';
    'VSS_E70':
      PIN_NUMBER='(0,0,0,0,0,0,0,0,0,0,0,0,0,0,0,0,0,0,0,0,0,0,0,0,0,0,0,E70,0,0~
,0,0,0,0,0,0,0,0,0,0)';
      PINUSE='POWER';
      NO_LOAD_CHECK='Both';
      NO_IO_CHECK='Both';
      NO_ASSERT_CHECK='TRUE';
      NO_DIR_CHECK='TRUE';
      ALLOW_CONNECT='TRUE';
    'VSS_E72':
      PIN_NUMBER='(0,0,0,0,0,0,0,0,0,0,0,0,0,0,0,0,0,0,0,0,0,0,0,0,0,0,0,E72,0,0~
,0,0,0,0,0,0,0,0,0,0)';
      PINUSE='POWER';
      NO_LOAD_CHECK='Both';
      NO_IO_CHECK='Both';
      NO_ASSERT_CHECK='TRUE';
      NO_DIR_CHECK='TRUE';
      ALLOW_CONNECT='TRUE';
    'VSS_E73':
      PIN_NUMBER='(0,0,0,0,0,0,0,0,0,0,0,0,0,0,0,0,0,0,0,0,0,0,0,0,0,0,0,E73,0,0~
,0,0,0,0,0,0,0,0,0,0)';
      PINUSE='POWER';
      NO_LOAD_CHECK='Both';
      NO_IO_CHECK='Both';
      NO_ASSERT_CHECK='TRUE';
      NO_DIR_CHECK='TRUE';
      ALLOW_CONNECT='TRUE';
    'VSS_E75':
      PIN_NUMBER='(0,0,0,0,0,0,0,0,0,0,0,0,0,0,0,0,0,0,0,0,0,0,0,0,0,0,0,E75,0,0~
,0,0,0,0,0,0,0,0,0,0)';
      PINUSE='POWER';
      NO_LOAD_CHECK='Both';
      NO_IO_CHECK='Both';
      NO_ASSERT_CHECK='TRUE';
      NO_DIR_CHECK='TRUE';
      ALLOW_CONNECT='TRUE';
    'VSS_F3':
      PIN_NUMBER='(0,0,0,0,0,0,0,0,0,0,0,0,0,0,0,0,0,0,0,0,0,0,0,0,0,0,0,F3,0,0,~
0,0,0,0,0,0,0,0,0,0)';
      PINUSE='POWER';
      NO_LOAD_CHECK='Both';
      NO_IO_CHECK='Both';
      NO_ASSERT_CHECK='TRUE';
      NO_DIR_CHECK='TRUE';
      ALLOW_CONNECT='TRUE';
    'VSS_F5':
      PIN_NUMBER='(0,0,0,0,0,0,0,0,0,0,0,0,0,0,0,0,0,0,0,0,0,0,0,0,0,0,0,F5,0,0,~
0,0,0,0,0,0,0,0,0,0)';
      PINUSE='POWER';
      NO_LOAD_CHECK='Both';
      NO_IO_CHECK='Both';
      NO_ASSERT_CHECK='TRUE';
      NO_DIR_CHECK='TRUE';
      ALLOW_CONNECT='TRUE';
    'VSS_F8':
      PIN_NUMBER='(0,0,0,0,0,0,0,0,0,0,0,0,0,0,0,0,0,0,0,0,0,0,0,0,0,0,0,F8,0,0,~
0,0,0,0,0,0,0,0,0,0)';
      PINUSE='POWER';
      NO_LOAD_CHECK='Both';
      NO_IO_CHECK='Both';
      NO_ASSERT_CHECK='TRUE';
      NO_DIR_CHECK='TRUE';
      ALLOW_CONNECT='TRUE';
    'VSS_F10':
      PIN_NUMBER='(0,0,0,0,0,0,0,0,0,0,0,0,0,0,0,0,0,0,0,0,0,0,0,0,0,0,0,F10,0,0~
,0,0,0,0,0,0,0,0,0,0)';
      PINUSE='POWER';
      NO_LOAD_CHECK='Both';
      NO_IO_CHECK='Both';
      NO_ASSERT_CHECK='TRUE';
      NO_DIR_CHECK='TRUE';
      ALLOW_CONNECT='TRUE';
    'VSS_F12':
      PIN_NUMBER='(0,0,0,0,0,0,0,0,0,0,0,0,0,0,0,0,0,0,0,0,0,0,0,0,0,0,0,F12,0,0~
,0,0,0,0,0,0,0,0,0,0)';
      PINUSE='POWER';
      NO_LOAD_CHECK='Both';
      NO_IO_CHECK='Both';
      NO_ASSERT_CHECK='TRUE';
      NO_DIR_CHECK='TRUE';
      ALLOW_CONNECT='TRUE';
    'VSS_F15':
      PIN_NUMBER='(0,0,0,0,0,0,0,0,0,0,0,0,0,0,0,0,0,0,0,0,0,0,0,0,0,0,0,F15,0,0~
,0,0,0,0,0,0,0,0,0,0)';
      PINUSE='POWER';
      NO_LOAD_CHECK='Both';
      NO_IO_CHECK='Both';
      NO_ASSERT_CHECK='TRUE';
      NO_DIR_CHECK='TRUE';
      ALLOW_CONNECT='TRUE';
    'VSS_F17':
      PIN_NUMBER='(0,0,0,0,0,0,0,0,0,0,0,0,0,0,0,0,0,0,0,0,0,0,0,0,0,0,0,F17,0,0~
,0,0,0,0,0,0,0,0,0,0)';
      PINUSE='POWER';
      NO_LOAD_CHECK='Both';
      NO_IO_CHECK='Both';
      NO_ASSERT_CHECK='TRUE';
      NO_DIR_CHECK='TRUE';
      ALLOW_CONNECT='TRUE';
    'VSS_F19':
      PIN_NUMBER='(0,0,0,0,0,0,0,0,0,0,0,0,0,0,0,0,0,0,0,0,0,0,0,0,0,0,0,F19,0,0~
,0,0,0,0,0,0,0,0,0,0)';
      PINUSE='POWER';
      NO_LOAD_CHECK='Both';
      NO_IO_CHECK='Both';
      NO_ASSERT_CHECK='TRUE';
      NO_DIR_CHECK='TRUE';
      ALLOW_CONNECT='TRUE';
    'VSS_F23':
      PIN_NUMBER='(0,0,0,0,0,0,0,0,0,0,0,0,0,0,0,0,0,0,0,0,0,0,0,0,0,0,0,F23,0,0~
,0,0,0,0,0,0,0,0,0,0)';
      PINUSE='POWER';
      NO_LOAD_CHECK='Both';
      NO_IO_CHECK='Both';
      NO_ASSERT_CHECK='TRUE';
      NO_DIR_CHECK='TRUE';
      ALLOW_CONNECT='TRUE';
    'VSS_F24':
      PIN_NUMBER='(0,0,0,0,0,0,0,0,0,0,0,0,0,0,0,0,0,0,0,0,0,0,0,0,0,0,0,F24,0,0~
,0,0,0,0,0,0,0,0,0,0)';
      PINUSE='POWER';
      NO_LOAD_CHECK='Both';
      NO_IO_CHECK='Both';
      NO_ASSERT_CHECK='TRUE';
      NO_DIR_CHECK='TRUE';
      ALLOW_CONNECT='TRUE';
    'VSS_F26':
      PIN_NUMBER='(0,0,0,0,0,0,0,0,0,0,0,0,0,0,0,0,0,0,0,0,0,0,0,0,0,0,0,F26,0,0~
,0,0,0,0,0,0,0,0,0,0)';
      PINUSE='POWER';
      NO_LOAD_CHECK='Both';
      NO_IO_CHECK='Both';
      NO_ASSERT_CHECK='TRUE';
      NO_DIR_CHECK='TRUE';
      ALLOW_CONNECT='TRUE';
    'VSS_F27':
      PIN_NUMBER='(0,0,0,0,0,0,0,0,0,0,0,0,0,0,0,0,0,0,0,0,0,0,0,0,0,0,0,F27,0,0~
,0,0,0,0,0,0,0,0,0,0)';
      PINUSE='POWER';
      NO_LOAD_CHECK='Both';
      NO_IO_CHECK='Both';
      NO_ASSERT_CHECK='TRUE';
      NO_DIR_CHECK='TRUE';
      ALLOW_CONNECT='TRUE';
    'VSS_F29':
      PIN_NUMBER='(0,0,0,0,0,0,0,0,0,0,0,0,0,0,0,0,0,0,0,0,0,0,0,0,0,0,0,F29,0,0~
,0,0,0,0,0,0,0,0,0,0)';
      PINUSE='POWER';
      NO_LOAD_CHECK='Both';
      NO_IO_CHECK='Both';
      NO_ASSERT_CHECK='TRUE';
      NO_DIR_CHECK='TRUE';
      ALLOW_CONNECT='TRUE';
    'VSS_F30':
      PIN_NUMBER='(0,0,0,0,0,0,0,0,0,0,0,0,0,0,0,0,0,0,0,0,0,0,0,0,0,0,0,F30,0,0~
,0,0,0,0,0,0,0,0,0,0)';
      PINUSE='POWER';
      NO_LOAD_CHECK='Both';
      NO_IO_CHECK='Both';
      NO_ASSERT_CHECK='TRUE';
      NO_DIR_CHECK='TRUE';
      ALLOW_CONNECT='TRUE';
    'VSS_F32':
      PIN_NUMBER='(0,0,0,0,0,0,0,0,0,0,0,0,0,0,0,0,0,0,0,0,0,0,0,0,0,0,0,F32,0,0~
,0,0,0,0,0,0,0,0,0,0)';
      PINUSE='POWER';
      NO_LOAD_CHECK='Both';
      NO_IO_CHECK='Both';
      NO_ASSERT_CHECK='TRUE';
      NO_DIR_CHECK='TRUE';
      ALLOW_CONNECT='TRUE';
    'VSS_F33':
      PIN_NUMBER='(0,0,0,0,0,0,0,0,0,0,0,0,0,0,0,0,0,0,0,0,0,0,0,0,0,0,0,F33,0,0~
,0,0,0,0,0,0,0,0,0,0)';
      PINUSE='POWER';
      NO_LOAD_CHECK='Both';
      NO_IO_CHECK='Both';
      NO_ASSERT_CHECK='TRUE';
      NO_DIR_CHECK='TRUE';
      ALLOW_CONNECT='TRUE';
    'VSS_F35':
      PIN_NUMBER='(0,0,0,0,0,0,0,0,0,0,0,0,0,0,0,0,0,0,0,0,0,0,0,0,0,0,0,F35,0,0~
,0,0,0,0,0,0,0,0,0,0)';
      PINUSE='POWER';
      NO_LOAD_CHECK='Both';
      NO_IO_CHECK='Both';
      NO_ASSERT_CHECK='TRUE';
      NO_DIR_CHECK='TRUE';
      ALLOW_CONNECT='TRUE';
    'VSS_F36':
      PIN_NUMBER='(0,0,0,0,0,0,0,0,0,0,0,0,0,0,0,0,0,0,0,0,0,0,0,0,0,0,0,F36,0,0~
,0,0,0,0,0,0,0,0,0,0)';
      PINUSE='POWER';
      NO_LOAD_CHECK='Both';
      NO_IO_CHECK='Both';
      NO_ASSERT_CHECK='TRUE';
      NO_DIR_CHECK='TRUE';
      ALLOW_CONNECT='TRUE';
    'VSS_F37':
      PIN_NUMBER='(0,0,0,0,0,0,0,0,0,0,0,0,0,0,0,0,0,0,0,0,0,0,0,0,0,0,0,F37,0,0~
,0,0,0,0,0,0,0,0,0,0)';
      PINUSE='POWER';
      NO_LOAD_CHECK='Both';
      NO_IO_CHECK='Both';
      NO_ASSERT_CHECK='TRUE';
      NO_DIR_CHECK='TRUE';
      ALLOW_CONNECT='TRUE';
    'VSS_F39':
      PIN_NUMBER='(0,0,0,0,0,0,0,0,0,0,0,0,0,0,0,0,0,0,0,0,0,0,0,0,0,0,0,F39,0,0~
,0,0,0,0,0,0,0,0,0,0)';
      PINUSE='POWER';
      NO_LOAD_CHECK='Both';
      NO_IO_CHECK='Both';
      NO_ASSERT_CHECK='TRUE';
      NO_DIR_CHECK='TRUE';
      ALLOW_CONNECT='TRUE';
    'VSS_F40':
      PIN_NUMBER='(0,0,0,0,0,0,0,0,0,0,0,0,0,0,0,0,0,0,0,0,0,0,0,0,0,0,0,F40,0,0~
,0,0,0,0,0,0,0,0,0,0)';
      PINUSE='POWER';
      NO_LOAD_CHECK='Both';
      NO_IO_CHECK='Both';
      NO_ASSERT_CHECK='TRUE';
      NO_DIR_CHECK='TRUE';
      ALLOW_CONNECT='TRUE';
    'VSS_F41':
      PIN_NUMBER='(0,0,0,0,0,0,0,0,0,0,0,0,0,0,0,0,0,0,0,0,0,0,0,0,0,0,0,F41,0,0~
,0,0,0,0,0,0,0,0,0,0)';
      PINUSE='POWER';
      NO_LOAD_CHECK='Both';
      NO_IO_CHECK='Both';
      NO_ASSERT_CHECK='TRUE';
      NO_DIR_CHECK='TRUE';
      ALLOW_CONNECT='TRUE';
    'VSS_F43':
      PIN_NUMBER='(0,0,0,0,0,0,0,0,0,0,0,0,0,0,0,0,0,0,0,0,0,0,0,0,0,0,0,F43,0,0~
,0,0,0,0,0,0,0,0,0,0)';
      PINUSE='POWER';
      NO_LOAD_CHECK='Both';
      NO_IO_CHECK='Both';
      NO_ASSERT_CHECK='TRUE';
      NO_DIR_CHECK='TRUE';
      ALLOW_CONNECT='TRUE';
    'VSS_F44':
      PIN_NUMBER='(0,0,0,0,0,0,0,0,0,0,0,0,0,0,0,0,0,0,0,0,0,0,0,0,0,0,0,F44,0,0~
,0,0,0,0,0,0,0,0,0,0)';
      PINUSE='POWER';
      NO_LOAD_CHECK='Both';
      NO_IO_CHECK='Both';
      NO_ASSERT_CHECK='TRUE';
      NO_DIR_CHECK='TRUE';
      ALLOW_CONNECT='TRUE';
    'VSS_F46':
      PIN_NUMBER='(0,0,0,0,0,0,0,0,0,0,0,0,0,0,0,0,0,0,0,0,0,0,0,0,0,0,0,F46,0,0~
,0,0,0,0,0,0,0,0,0,0)';
      PINUSE='POWER';
      NO_LOAD_CHECK='Both';
      NO_IO_CHECK='Both';
      NO_ASSERT_CHECK='TRUE';
      NO_DIR_CHECK='TRUE';
      ALLOW_CONNECT='TRUE';
    'VSS_F47':
      PIN_NUMBER='(0,0,0,0,0,0,0,0,0,0,0,0,0,0,0,0,0,0,0,0,0,0,0,0,0,0,0,F47,0,0~
,0,0,0,0,0,0,0,0,0,0)';
      PINUSE='POWER';
      NO_LOAD_CHECK='Both';
      NO_IO_CHECK='Both';
      NO_ASSERT_CHECK='TRUE';
      NO_DIR_CHECK='TRUE';
      ALLOW_CONNECT='TRUE';
    'VSS_F49':
      PIN_NUMBER='(0,0,0,0,0,0,0,0,0,0,0,0,0,0,0,0,0,0,0,0,0,0,0,0,0,0,0,F49,0,0~
,0,0,0,0,0,0,0,0,0,0)';
      PINUSE='POWER';
      NO_LOAD_CHECK='Both';
      NO_IO_CHECK='Both';
      NO_ASSERT_CHECK='TRUE';
      NO_DIR_CHECK='TRUE';
      ALLOW_CONNECT='TRUE';
    'VSS_F50':
      PIN_NUMBER='(0,0,0,0,0,0,0,0,0,0,0,0,0,0,0,0,0,0,0,0,0,0,0,0,0,0,0,F50,0,0~
,0,0,0,0,0,0,0,0,0,0)';
      PINUSE='POWER';
      NO_LOAD_CHECK='Both';
      NO_IO_CHECK='Both';
      NO_ASSERT_CHECK='TRUE';
      NO_DIR_CHECK='TRUE';
      ALLOW_CONNECT='TRUE';
    'VSS_F52':
      PIN_NUMBER='(0,0,0,0,0,0,0,0,0,0,0,0,0,0,0,0,0,0,0,0,0,0,0,0,0,0,0,F52,0,0~
,0,0,0,0,0,0,0,0,0,0)';
      PINUSE='POWER';
      NO_LOAD_CHECK='Both';
      NO_IO_CHECK='Both';
      NO_ASSERT_CHECK='TRUE';
      NO_DIR_CHECK='TRUE';
      ALLOW_CONNECT='TRUE';
    'VSS_F53':
      PIN_NUMBER='(0,0,0,0,0,0,0,0,0,0,0,0,0,0,0,0,0,0,0,0,0,0,0,0,0,0,0,F53,0,0~
,0,0,0,0,0,0,0,0,0,0)';
      PINUSE='POWER';
      NO_LOAD_CHECK='Both';
      NO_IO_CHECK='Both';
      NO_ASSERT_CHECK='TRUE';
      NO_DIR_CHECK='TRUE';
      ALLOW_CONNECT='TRUE';
    'VSS_F57':
      PIN_NUMBER='(0,0,0,0,0,0,0,0,0,0,0,0,0,0,0,0,0,0,0,0,0,0,0,0,0,0,0,F57,0,0~
,0,0,0,0,0,0,0,0,0,0)';
      PINUSE='POWER';
      NO_LOAD_CHECK='Both';
      NO_IO_CHECK='Both';
      NO_ASSERT_CHECK='TRUE';
      NO_DIR_CHECK='TRUE';
      ALLOW_CONNECT='TRUE';
    'VSS_F59':
      PIN_NUMBER='(0,0,0,0,0,0,0,0,0,0,0,0,0,0,0,0,0,0,0,0,0,0,0,0,0,0,0,F59,0,0~
,0,0,0,0,0,0,0,0,0,0)';
      PINUSE='POWER';
      NO_LOAD_CHECK='Both';
      NO_IO_CHECK='Both';
      NO_ASSERT_CHECK='TRUE';
      NO_DIR_CHECK='TRUE';
      ALLOW_CONNECT='TRUE';
    'VSS_F61':
      PIN_NUMBER='(0,0,0,0,0,0,0,0,0,0,0,0,0,0,0,0,0,0,0,0,0,0,0,0,0,0,0,F61,0,0~
,0,0,0,0,0,0,0,0,0,0)';
      PINUSE='POWER';
      NO_LOAD_CHECK='Both';
      NO_IO_CHECK='Both';
      NO_ASSERT_CHECK='TRUE';
      NO_DIR_CHECK='TRUE';
      ALLOW_CONNECT='TRUE';
    'VSS_F64':
      PIN_NUMBER='(0,0,0,0,0,0,0,0,0,0,0,0,0,0,0,0,0,0,0,0,0,0,0,0,0,0,0,F64,0,0~
,0,0,0,0,0,0,0,0,0,0)';
      PINUSE='POWER';
      NO_LOAD_CHECK='Both';
      NO_IO_CHECK='Both';
      NO_ASSERT_CHECK='TRUE';
      NO_DIR_CHECK='TRUE';
      ALLOW_CONNECT='TRUE';
    'VSS_F66':
      PIN_NUMBER='(0,0,0,0,0,0,0,0,0,0,0,0,0,0,0,0,0,0,0,0,0,0,0,0,0,0,0,F66,0,0~
,0,0,0,0,0,0,0,0,0,0)';
      PINUSE='POWER';
      NO_LOAD_CHECK='Both';
      NO_IO_CHECK='Both';
      NO_ASSERT_CHECK='TRUE';
      NO_DIR_CHECK='TRUE';
      ALLOW_CONNECT='TRUE';
    'VSS_F68':
      PIN_NUMBER='(0,0,0,0,0,0,0,0,0,0,0,0,0,0,0,0,0,0,0,0,0,0,0,0,0,0,0,F68,0,0~
,0,0,0,0,0,0,0,0,0,0)';
      PINUSE='POWER';
      NO_LOAD_CHECK='Both';
      NO_IO_CHECK='Both';
      NO_ASSERT_CHECK='TRUE';
      NO_DIR_CHECK='TRUE';
      ALLOW_CONNECT='TRUE';
    'VSS_F71':
      PIN_NUMBER='(0,0,0,0,0,0,0,0,0,0,0,0,0,0,0,0,0,0,0,0,0,0,0,0,0,0,0,F71,0,0~
,0,0,0,0,0,0,0,0,0,0)';
      PINUSE='POWER';
      NO_LOAD_CHECK='Both';
      NO_IO_CHECK='Both';
      NO_ASSERT_CHECK='TRUE';
      NO_DIR_CHECK='TRUE';
      ALLOW_CONNECT='TRUE';
    'VSS_F73':
      PIN_NUMBER='(0,0,0,0,0,0,0,0,0,0,0,0,0,0,0,0,0,0,0,0,0,0,0,0,0,0,0,F73,0,0~
,0,0,0,0,0,0,0,0,0,0)';
      PINUSE='POWER';
      NO_LOAD_CHECK='Both';
      NO_IO_CHECK='Both';
      NO_ASSERT_CHECK='TRUE';
      NO_DIR_CHECK='TRUE';
      ALLOW_CONNECT='TRUE';
    'VSS_G1':
      PIN_NUMBER='(0,0,0,0,0,0,0,0,0,0,0,0,0,0,0,0,0,0,0,0,0,0,0,0,0,0,0,G1,0,0,~
0,0,0,0,0,0,0,0,0,0)';
      PINUSE='POWER';
      NO_LOAD_CHECK='Both';
      NO_IO_CHECK='Both';
      NO_ASSERT_CHECK='TRUE';
      NO_DIR_CHECK='TRUE';
      ALLOW_CONNECT='TRUE';
    'VSS_G4':
      PIN_NUMBER='(0,0,0,0,0,0,0,0,0,0,0,0,0,0,0,0,0,0,0,0,0,0,0,0,0,0,0,G4,0,0,~
0,0,0,0,0,0,0,0,0,0)';
      PINUSE='POWER';
      NO_LOAD_CHECK='Both';
      NO_IO_CHECK='Both';
      NO_ASSERT_CHECK='TRUE';
      NO_DIR_CHECK='TRUE';
      ALLOW_CONNECT='TRUE';
    'VSS_G6':
      PIN_NUMBER='(0,0,0,0,0,0,0,0,0,0,0,0,0,0,0,0,0,0,0,0,0,0,0,0,0,0,0,G6,0,0,~
0,0,0,0,0,0,0,0,0,0)';
      PINUSE='POWER';
      NO_LOAD_CHECK='Both';
      NO_IO_CHECK='Both';
      NO_ASSERT_CHECK='TRUE';
      NO_DIR_CHECK='TRUE';
      ALLOW_CONNECT='TRUE';
    'VSS_G8':
      PIN_NUMBER='(0,0,0,0,0,0,0,0,0,0,0,0,0,0,0,0,0,0,0,0,0,0,0,0,0,0,0,G8,0,0,~
0,0,0,0,0,0,0,0,0,0)';
      PINUSE='POWER';
      NO_LOAD_CHECK='Both';
      NO_IO_CHECK='Both';
      NO_ASSERT_CHECK='TRUE';
      NO_DIR_CHECK='TRUE';
      ALLOW_CONNECT='TRUE';
    'VSS_G11':
      PIN_NUMBER='(0,0,0,0,0,0,0,0,0,0,0,0,0,0,0,0,0,0,0,0,0,0,0,0,0,0,0,G11,0,0~
,0,0,0,0,0,0,0,0,0,0)';
      PINUSE='POWER';
      NO_LOAD_CHECK='Both';
      NO_IO_CHECK='Both';
      NO_ASSERT_CHECK='TRUE';
      NO_DIR_CHECK='TRUE';
      ALLOW_CONNECT='TRUE';
    'VSS_G13':
      PIN_NUMBER='(0,0,0,0,0,0,0,0,0,0,0,0,0,0,0,0,0,0,0,0,0,0,0,0,0,0,0,G13,0,0~
,0,0,0,0,0,0,0,0,0,0)';
      PINUSE='POWER';
      NO_LOAD_CHECK='Both';
      NO_IO_CHECK='Both';
      NO_ASSERT_CHECK='TRUE';
      NO_DIR_CHECK='TRUE';
      ALLOW_CONNECT='TRUE';
    'VSS_G15':
      PIN_NUMBER='(0,0,0,0,0,0,0,0,0,0,0,0,0,0,0,0,0,0,0,0,0,0,0,0,0,0,0,G15,0,0~
,0,0,0,0,0,0,0,0,0,0)';
      PINUSE='POWER';
      NO_LOAD_CHECK='Both';
      NO_IO_CHECK='Both';
      NO_ASSERT_CHECK='TRUE';
      NO_DIR_CHECK='TRUE';
      ALLOW_CONNECT='TRUE';
    'VSS_G18':
      PIN_NUMBER='(0,0,0,0,0,0,0,0,0,0,0,0,0,0,0,0,0,0,0,0,0,0,0,0,0,0,0,G18,0,0~
,0,0,0,0,0,0,0,0,0,0)';
      PINUSE='POWER';
      NO_LOAD_CHECK='Both';
      NO_IO_CHECK='Both';
      NO_ASSERT_CHECK='TRUE';
      NO_DIR_CHECK='TRUE';
      ALLOW_CONNECT='TRUE';
    'VSS_G20':
      PIN_NUMBER='(0,0,0,0,0,0,0,0,0,0,0,0,0,0,0,0,0,0,0,0,0,0,0,0,0,0,0,G20,0,0~
,0,0,0,0,0,0,0,0,0,0)';
      PINUSE='POWER';
      NO_LOAD_CHECK='Both';
      NO_IO_CHECK='Both';
      NO_ASSERT_CHECK='TRUE';
      NO_DIR_CHECK='TRUE';
      ALLOW_CONNECT='TRUE';
    'VSS_G22':
      PIN_NUMBER='(0,0,0,0,0,0,0,0,0,0,0,0,0,0,0,0,0,0,0,0,0,0,0,0,0,0,0,G22,0,0~
,0,0,0,0,0,0,0,0,0,0)';
      PINUSE='POWER';
      NO_LOAD_CHECK='Both';
      NO_IO_CHECK='Both';
      NO_ASSERT_CHECK='TRUE';
      NO_DIR_CHECK='TRUE';
      ALLOW_CONNECT='TRUE';
    'VSS_G25':
      PIN_NUMBER='(0,0,0,0,0,0,0,0,0,0,0,0,0,0,0,0,0,0,0,0,0,0,0,0,0,0,0,G25,0,0~
,0,0,0,0,0,0,0,0,0,0)';
      PINUSE='POWER';
      NO_LOAD_CHECK='Both';
      NO_IO_CHECK='Both';
      NO_ASSERT_CHECK='TRUE';
      NO_DIR_CHECK='TRUE';
      ALLOW_CONNECT='TRUE';
    'VSS_G28':
      PIN_NUMBER='(0,0,0,0,0,0,0,0,0,0,0,0,0,0,0,0,0,0,0,0,0,0,0,0,0,0,0,G28,0,0~
,0,0,0,0,0,0,0,0,0,0)';
      PINUSE='POWER';
      NO_LOAD_CHECK='Both';
      NO_IO_CHECK='Both';
      NO_ASSERT_CHECK='TRUE';
      NO_DIR_CHECK='TRUE';
      ALLOW_CONNECT='TRUE';
    'VSS_G31':
      PIN_NUMBER='(0,0,0,0,0,0,0,0,0,0,0,0,0,0,0,0,0,0,0,0,0,0,0,0,0,0,0,G31,0,0~
,0,0,0,0,0,0,0,0,0,0)';
      PINUSE='POWER';
      NO_LOAD_CHECK='Both';
      NO_IO_CHECK='Both';
      NO_ASSERT_CHECK='TRUE';
      NO_DIR_CHECK='TRUE';
      ALLOW_CONNECT='TRUE';
    'VSS_G34':
      PIN_NUMBER='(0,0,0,0,0,0,0,0,0,0,0,0,0,0,0,0,0,0,0,0,0,0,0,0,0,0,0,G34,0,0~
,0,0,0,0,0,0,0,0,0,0)';
      PINUSE='POWER';
      NO_LOAD_CHECK='Both';
      NO_IO_CHECK='Both';
      NO_ASSERT_CHECK='TRUE';
      NO_DIR_CHECK='TRUE';
      ALLOW_CONNECT='TRUE';
    'VSS_G42':
      PIN_NUMBER='(0,0,0,0,0,0,0,0,0,0,0,0,0,0,0,0,0,0,0,0,0,0,0,0,0,0,0,G42,0,0~
,0,0,0,0,0,0,0,0,0,0)';
      PINUSE='POWER';
      NO_LOAD_CHECK='Both';
      NO_IO_CHECK='Both';
      NO_ASSERT_CHECK='TRUE';
      NO_DIR_CHECK='TRUE';
      ALLOW_CONNECT='TRUE';
    'VSS_G45':
      PIN_NUMBER='(0,0,0,0,0,0,0,0,0,0,0,0,0,0,0,0,0,0,0,0,0,0,0,0,0,0,0,G45,0,0~
,0,0,0,0,0,0,0,0,0,0)';
      PINUSE='POWER';
      NO_LOAD_CHECK='Both';
      NO_IO_CHECK='Both';
      NO_ASSERT_CHECK='TRUE';
      NO_DIR_CHECK='TRUE';
      ALLOW_CONNECT='TRUE';
    'VSS_G48':
      PIN_NUMBER='(0,0,0,0,0,0,0,0,0,0,0,0,0,0,0,0,0,0,0,0,0,0,0,0,0,0,0,G48,0,0~
,0,0,0,0,0,0,0,0,0,0)';
      PINUSE='POWER';
      NO_LOAD_CHECK='Both';
      NO_IO_CHECK='Both';
      NO_ASSERT_CHECK='TRUE';
      NO_DIR_CHECK='TRUE';
      ALLOW_CONNECT='TRUE';
    'VSS_G51':
      PIN_NUMBER='(0,0,0,0,0,0,0,0,0,0,0,0,0,0,0,0,0,0,0,0,0,0,0,0,0,0,0,G51,0,0~
,0,0,0,0,0,0,0,0,0,0)';
      PINUSE='POWER';
      NO_LOAD_CHECK='Both';
      NO_IO_CHECK='Both';
      NO_ASSERT_CHECK='TRUE';
      NO_DIR_CHECK='TRUE';
      ALLOW_CONNECT='TRUE';
    'VSS_G54':
      PIN_NUMBER='(0,0,0,0,0,0,0,0,0,0,0,0,0,0,0,0,0,0,0,0,0,0,0,0,0,0,0,G54,0,0~
,0,0,0,0,0,0,0,0,0,0)';
      PINUSE='POWER';
      NO_LOAD_CHECK='Both';
      NO_IO_CHECK='Both';
      NO_ASSERT_CHECK='TRUE';
      NO_DIR_CHECK='TRUE';
      ALLOW_CONNECT='TRUE';
    'VSS_G56':
      PIN_NUMBER='(0,0,0,0,0,0,0,0,0,0,0,0,0,0,0,0,0,0,0,0,0,0,0,0,0,0,0,G56,0,0~
,0,0,0,0,0,0,0,0,0,0)';
      PINUSE='POWER';
      NO_LOAD_CHECK='Both';
      NO_IO_CHECK='Both';
      NO_ASSERT_CHECK='TRUE';
      NO_DIR_CHECK='TRUE';
      ALLOW_CONNECT='TRUE';
    'VSS_G58':
      PIN_NUMBER='(0,0,0,0,0,0,0,0,0,0,0,0,0,0,0,0,0,0,0,0,0,0,0,0,0,0,0,G58,0,0~
,0,0,0,0,0,0,0,0,0,0)';
      PINUSE='POWER';
      NO_LOAD_CHECK='Both';
      NO_IO_CHECK='Both';
      NO_ASSERT_CHECK='TRUE';
      NO_DIR_CHECK='TRUE';
      ALLOW_CONNECT='TRUE';
    'VSS_G61':
      PIN_NUMBER='(0,0,0,0,0,0,0,0,0,0,0,0,0,0,0,0,0,0,0,0,0,0,0,0,0,0,0,G61,0,0~
,0,0,0,0,0,0,0,0,0,0)';
      PINUSE='POWER';
      NO_LOAD_CHECK='Both';
      NO_IO_CHECK='Both';
      NO_ASSERT_CHECK='TRUE';
      NO_DIR_CHECK='TRUE';
      ALLOW_CONNECT='TRUE';
    'VSS_G63':
      PIN_NUMBER='(0,0,0,0,0,0,0,0,0,0,0,0,0,0,0,0,0,0,0,0,0,0,0,0,0,0,0,G63,0,0~
,0,0,0,0,0,0,0,0,0,0)';
      PINUSE='POWER';
      NO_LOAD_CHECK='Both';
      NO_IO_CHECK='Both';
      NO_ASSERT_CHECK='TRUE';
      NO_DIR_CHECK='TRUE';
      ALLOW_CONNECT='TRUE';
    'VSS_G65':
      PIN_NUMBER='(0,0,0,0,0,0,0,0,0,0,0,0,0,0,0,0,0,0,0,0,0,0,0,0,0,0,0,G65,0,0~
,0,0,0,0,0,0,0,0,0,0)';
      PINUSE='POWER';
      NO_LOAD_CHECK='Both';
      NO_IO_CHECK='Both';
      NO_ASSERT_CHECK='TRUE';
      NO_DIR_CHECK='TRUE';
      ALLOW_CONNECT='TRUE';
    'VSS_G68':
      PIN_NUMBER='(0,0,0,0,0,0,0,0,0,0,0,0,0,0,0,0,0,0,0,0,0,0,0,0,0,0,0,G68,0,0~
,0,0,0,0,0,0,0,0,0,0)';
      PINUSE='POWER';
      NO_LOAD_CHECK='Both';
      NO_IO_CHECK='Both';
      NO_ASSERT_CHECK='TRUE';
      NO_DIR_CHECK='TRUE';
      ALLOW_CONNECT='TRUE';
    'VSS_G70':
      PIN_NUMBER='(0,0,0,0,0,0,0,0,0,0,0,0,0,0,0,0,0,0,0,0,0,0,0,0,0,0,0,G70,0,0~
,0,0,0,0,0,0,0,0,0,0)';
      PINUSE='POWER';
      NO_LOAD_CHECK='Both';
      NO_IO_CHECK='Both';
      NO_ASSERT_CHECK='TRUE';
      NO_DIR_CHECK='TRUE';
      ALLOW_CONNECT='TRUE';
    'VSS_G72':
      PIN_NUMBER='(0,0,0,0,0,0,0,0,0,0,0,0,0,0,0,0,0,0,0,0,0,0,0,0,0,0,0,G72,0,0~
,0,0,0,0,0,0,0,0,0,0)';
      PINUSE='POWER';
      NO_LOAD_CHECK='Both';
      NO_IO_CHECK='Both';
      NO_ASSERT_CHECK='TRUE';
      NO_DIR_CHECK='TRUE';
      ALLOW_CONNECT='TRUE';
    'VSS_G75':
      PIN_NUMBER='(0,0,0,0,0,0,0,0,0,0,0,0,0,0,0,0,0,0,0,0,0,0,0,0,0,0,0,G75,0,0~
,0,0,0,0,0,0,0,0,0,0)';
      PINUSE='POWER';
      NO_LOAD_CHECK='Both';
      NO_IO_CHECK='Both';
      NO_ASSERT_CHECK='TRUE';
      NO_DIR_CHECK='TRUE';
      ALLOW_CONNECT='TRUE';
    'VSS_H3':
      PIN_NUMBER='(0,0,0,0,0,0,0,0,0,0,0,0,0,0,0,0,0,0,0,0,0,0,0,0,0,0,0,H3,0,0,~
0,0,0,0,0,0,0,0,0,0)';
      PINUSE='POWER';
      NO_LOAD_CHECK='Both';
      NO_IO_CHECK='Both';
      NO_ASSERT_CHECK='TRUE';
      NO_DIR_CHECK='TRUE';
      ALLOW_CONNECT='TRUE';
    'VSS_H8':
      PIN_NUMBER='(0,0,0,0,0,0,0,0,0,0,0,0,0,0,0,0,0,0,0,0,0,0,0,0,0,0,0,H8,0,0,~
0,0,0,0,0,0,0,0,0,0)';
      PINUSE='POWER';
      NO_LOAD_CHECK='Both';
      NO_IO_CHECK='Both';
      NO_ASSERT_CHECK='TRUE';
      NO_DIR_CHECK='TRUE';
      ALLOW_CONNECT='TRUE';
    'VSS_H10':
      PIN_NUMBER='(0,0,0,0,0,0,0,0,0,0,0,0,0,0,0,0,0,0,0,0,0,0,0,0,0,0,0,H10,0,0~
,0,0,0,0,0,0,0,0,0,0)';
      PINUSE='POWER';
      NO_LOAD_CHECK='Both';
      NO_IO_CHECK='Both';
      NO_ASSERT_CHECK='TRUE';
      NO_DIR_CHECK='TRUE';
      ALLOW_CONNECT='TRUE';
    'VSS_H15':
      PIN_NUMBER='(0,0,0,0,0,0,0,0,0,0,0,0,0,0,0,0,0,0,0,0,0,0,0,0,0,0,0,H15,0,0~
,0,0,0,0,0,0,0,0,0,0)';
      PINUSE='POWER';
      NO_LOAD_CHECK='Both';
      NO_IO_CHECK='Both';
      NO_ASSERT_CHECK='TRUE';
      NO_DIR_CHECK='TRUE';
      ALLOW_CONNECT='TRUE';
    'VSS_H17':
      PIN_NUMBER='(0,0,0,0,0,0,0,0,0,0,0,0,0,0,0,0,0,0,0,0,0,0,0,0,0,0,0,H17,0,0~
,0,0,0,0,0,0,0,0,0,0)';
      PINUSE='POWER';
      NO_LOAD_CHECK='Both';
      NO_IO_CHECK='Both';
      NO_ASSERT_CHECK='TRUE';
      NO_DIR_CHECK='TRUE';
      ALLOW_CONNECT='TRUE';
    'VSS_H22':
      PIN_NUMBER='(0,0,0,0,0,0,0,0,0,0,0,0,0,0,0,0,0,0,0,0,0,0,0,0,0,0,0,H22,0,0~
,0,0,0,0,0,0,0,0,0,0)';
      PINUSE='POWER';
      NO_LOAD_CHECK='Both';
      NO_IO_CHECK='Both';
      NO_ASSERT_CHECK='TRUE';
      NO_DIR_CHECK='TRUE';
      ALLOW_CONNECT='TRUE';
    'VSS_H25':
      PIN_NUMBER='(0,0,0,0,0,0,0,0,0,0,0,0,0,0,0,0,0,0,0,0,0,0,0,0,0,0,0,H25,0,0~
,0,0,0,0,0,0,0,0,0,0)';
      PINUSE='POWER';
      NO_LOAD_CHECK='Both';
      NO_IO_CHECK='Both';
      NO_ASSERT_CHECK='TRUE';
      NO_DIR_CHECK='TRUE';
      ALLOW_CONNECT='TRUE';
    'VSS_H28':
      PIN_NUMBER='(0,0,0,0,0,0,0,0,0,0,0,0,0,0,0,0,0,0,0,0,0,0,0,0,0,0,0,H28,0,0~
,0,0,0,0,0,0,0,0,0,0)';
      PINUSE='POWER';
      NO_LOAD_CHECK='Both';
      NO_IO_CHECK='Both';
      NO_ASSERT_CHECK='TRUE';
      NO_DIR_CHECK='TRUE';
      ALLOW_CONNECT='TRUE';
    'VSS_H31':
      PIN_NUMBER='(0,0,0,0,0,0,0,0,0,0,0,0,0,0,0,0,0,0,0,0,0,0,0,0,0,0,0,H31,0,0~
,0,0,0,0,0,0,0,0,0,0)';
      PINUSE='POWER';
      NO_LOAD_CHECK='Both';
      NO_IO_CHECK='Both';
      NO_ASSERT_CHECK='TRUE';
      NO_DIR_CHECK='TRUE';
      ALLOW_CONNECT='TRUE';
    'VSS_H34':
      PIN_NUMBER='(0,0,0,0,0,0,0,0,0,0,0,0,0,0,0,0,0,0,0,0,0,0,0,0,0,0,0,H34,0,0~
,0,0,0,0,0,0,0,0,0,0)';
      PINUSE='POWER';
      NO_LOAD_CHECK='Both';
      NO_IO_CHECK='Both';
      NO_ASSERT_CHECK='TRUE';
      NO_DIR_CHECK='TRUE';
      ALLOW_CONNECT='TRUE';
    'VSS_R48':
      PIN_NUMBER='(0,0,0,0,0,0,0,0,0,0,0,0,0,0,0,0,0,0,0,0,0,0,0,0,0,0,0,0,R48,0~
,0,0,0,0,0,0,0,0,0,0)';
      PINUSE='POWER';
      NO_LOAD_CHECK='Both';
      NO_IO_CHECK='Both';
      NO_ASSERT_CHECK='TRUE';
      NO_DIR_CHECK='TRUE';
      ALLOW_CONNECT='TRUE';
    'VSS_R51':
      PIN_NUMBER='(0,0,0,0,0,0,0,0,0,0,0,0,0,0,0,0,0,0,0,0,0,0,0,0,0,0,0,0,R51,0~
,0,0,0,0,0,0,0,0,0,0)';
      PINUSE='POWER';
      NO_LOAD_CHECK='Both';
      NO_IO_CHECK='Both';
      NO_ASSERT_CHECK='TRUE';
      NO_DIR_CHECK='TRUE';
      ALLOW_CONNECT='TRUE';
    'VSS_R54':
      PIN_NUMBER='(0,0,0,0,0,0,0,0,0,0,0,0,0,0,0,0,0,0,0,0,0,0,0,0,0,0,0,0,R54,0~
,0,0,0,0,0,0,0,0,0,0)';
      PINUSE='POWER';
      NO_LOAD_CHECK='Both';
      NO_IO_CHECK='Both';
      NO_ASSERT_CHECK='TRUE';
      NO_DIR_CHECK='TRUE';
      ALLOW_CONNECT='TRUE';
    'VSS_R56':
      PIN_NUMBER='(0,0,0,0,0,0,0,0,0,0,0,0,0,0,0,0,0,0,0,0,0,0,0,0,0,0,0,0,R56,0~
,0,0,0,0,0,0,0,0,0,0)';
      PINUSE='POWER';
      NO_LOAD_CHECK='Both';
      NO_IO_CHECK='Both';
      NO_ASSERT_CHECK='TRUE';
      NO_DIR_CHECK='TRUE';
      ALLOW_CONNECT='TRUE';
    'VSS_R58':
      PIN_NUMBER='(0,0,0,0,0,0,0,0,0,0,0,0,0,0,0,0,0,0,0,0,0,0,0,0,0,0,0,0,R58,0~
,0,0,0,0,0,0,0,0,0,0)';
      PINUSE='POWER';
      NO_LOAD_CHECK='Both';
      NO_IO_CHECK='Both';
      NO_ASSERT_CHECK='TRUE';
      NO_DIR_CHECK='TRUE';
      ALLOW_CONNECT='TRUE';
    'VSS_R61':
      PIN_NUMBER='(0,0,0,0,0,0,0,0,0,0,0,0,0,0,0,0,0,0,0,0,0,0,0,0,0,0,0,0,R61,0~
,0,0,0,0,0,0,0,0,0,0)';
      PINUSE='POWER';
      NO_LOAD_CHECK='Both';
      NO_IO_CHECK='Both';
      NO_ASSERT_CHECK='TRUE';
      NO_DIR_CHECK='TRUE';
      ALLOW_CONNECT='TRUE';
    'VSS_R63':
      PIN_NUMBER='(0,0,0,0,0,0,0,0,0,0,0,0,0,0,0,0,0,0,0,0,0,0,0,0,0,0,0,0,R63,0~
,0,0,0,0,0,0,0,0,0,0)';
      PINUSE='POWER';
      NO_LOAD_CHECK='Both';
      NO_IO_CHECK='Both';
      NO_ASSERT_CHECK='TRUE';
      NO_DIR_CHECK='TRUE';
      ALLOW_CONNECT='TRUE';
    'VSS_R65':
      PIN_NUMBER='(0,0,0,0,0,0,0,0,0,0,0,0,0,0,0,0,0,0,0,0,0,0,0,0,0,0,0,0,R65,0~
,0,0,0,0,0,0,0,0,0,0)';
      PINUSE='POWER';
      NO_LOAD_CHECK='Both';
      NO_IO_CHECK='Both';
      NO_ASSERT_CHECK='TRUE';
      NO_DIR_CHECK='TRUE';
      ALLOW_CONNECT='TRUE';
    'VSS_R68':
      PIN_NUMBER='(0,0,0,0,0,0,0,0,0,0,0,0,0,0,0,0,0,0,0,0,0,0,0,0,0,0,0,0,R68,0~
,0,0,0,0,0,0,0,0,0,0)';
      PINUSE='POWER';
      NO_LOAD_CHECK='Both';
      NO_IO_CHECK='Both';
      NO_ASSERT_CHECK='TRUE';
      NO_DIR_CHECK='TRUE';
      ALLOW_CONNECT='TRUE';
    'VSS_R70':
      PIN_NUMBER='(0,0,0,0,0,0,0,0,0,0,0,0,0,0,0,0,0,0,0,0,0,0,0,0,0,0,0,0,R70,0~
,0,0,0,0,0,0,0,0,0,0)';
      PINUSE='POWER';
      NO_LOAD_CHECK='Both';
      NO_IO_CHECK='Both';
      NO_ASSERT_CHECK='TRUE';
      NO_DIR_CHECK='TRUE';
      ALLOW_CONNECT='TRUE';
    'VSS_R72':
      PIN_NUMBER='(0,0,0,0,0,0,0,0,0,0,0,0,0,0,0,0,0,0,0,0,0,0,0,0,0,0,0,0,R72,0~
,0,0,0,0,0,0,0,0,0,0)';
      PINUSE='POWER';
      NO_LOAD_CHECK='Both';
      NO_IO_CHECK='Both';
      NO_ASSERT_CHECK='TRUE';
      NO_DIR_CHECK='TRUE';
      ALLOW_CONNECT='TRUE';
    'VSS_R75':
      PIN_NUMBER='(0,0,0,0,0,0,0,0,0,0,0,0,0,0,0,0,0,0,0,0,0,0,0,0,0,0,0,0,R75,0~
,0,0,0,0,0,0,0,0,0,0)';
      PINUSE='POWER';
      NO_LOAD_CHECK='Both';
      NO_IO_CHECK='Both';
      NO_ASSERT_CHECK='TRUE';
      NO_DIR_CHECK='TRUE';
      ALLOW_CONNECT='TRUE';
    'VSS_T3':
      PIN_NUMBER='(0,0,0,0,0,0,0,0,0,0,0,0,0,0,0,0,0,0,0,0,0,0,0,0,0,0,0,0,T3,0,~
0,0,0,0,0,0,0,0,0,0)';
      PINUSE='POWER';
      NO_LOAD_CHECK='Both';
      NO_IO_CHECK='Both';
      NO_ASSERT_CHECK='TRUE';
      NO_DIR_CHECK='TRUE';
      ALLOW_CONNECT='TRUE';
    'VSS_T5':
      PIN_NUMBER='(0,0,0,0,0,0,0,0,0,0,0,0,0,0,0,0,0,0,0,0,0,0,0,0,0,0,0,0,T5,0,~
0,0,0,0,0,0,0,0,0,0)';
      PINUSE='POWER';
      NO_LOAD_CHECK='Both';
      NO_IO_CHECK='Both';
      NO_ASSERT_CHECK='TRUE';
      NO_DIR_CHECK='TRUE';
      ALLOW_CONNECT='TRUE';
    'VSS_T8':
      PIN_NUMBER='(0,0,0,0,0,0,0,0,0,0,0,0,0,0,0,0,0,0,0,0,0,0,0,0,0,0,0,0,T8,0,~
0,0,0,0,0,0,0,0,0,0)';
      PINUSE='POWER';
      NO_LOAD_CHECK='Both';
      NO_IO_CHECK='Both';
      NO_ASSERT_CHECK='TRUE';
      NO_DIR_CHECK='TRUE';
      ALLOW_CONNECT='TRUE';
    'VSS_T10':
      PIN_NUMBER='(0,0,0,0,0,0,0,0,0,0,0,0,0,0,0,0,0,0,0,0,0,0,0,0,0,0,0,0,T10,0~
,0,0,0,0,0,0,0,0,0,0)';
      PINUSE='POWER';
      NO_LOAD_CHECK='Both';
      NO_IO_CHECK='Both';
      NO_ASSERT_CHECK='TRUE';
      NO_DIR_CHECK='TRUE';
      ALLOW_CONNECT='TRUE';
    'VSS_T12':
      PIN_NUMBER='(0,0,0,0,0,0,0,0,0,0,0,0,0,0,0,0,0,0,0,0,0,0,0,0,0,0,0,0,T12,0~
,0,0,0,0,0,0,0,0,0,0)';
      PINUSE='POWER';
      NO_LOAD_CHECK='Both';
      NO_IO_CHECK='Both';
      NO_ASSERT_CHECK='TRUE';
      NO_DIR_CHECK='TRUE';
      ALLOW_CONNECT='TRUE';
    'VSS_T15':
      PIN_NUMBER='(0,0,0,0,0,0,0,0,0,0,0,0,0,0,0,0,0,0,0,0,0,0,0,0,0,0,0,0,T15,0~
,0,0,0,0,0,0,0,0,0,0)';
      PINUSE='POWER';
      NO_LOAD_CHECK='Both';
      NO_IO_CHECK='Both';
      NO_ASSERT_CHECK='TRUE';
      NO_DIR_CHECK='TRUE';
      ALLOW_CONNECT='TRUE';
    'VSS_T17':
      PIN_NUMBER='(0,0,0,0,0,0,0,0,0,0,0,0,0,0,0,0,0,0,0,0,0,0,0,0,0,0,0,0,T17,0~
,0,0,0,0,0,0,0,0,0,0)';
      PINUSE='POWER';
      NO_LOAD_CHECK='Both';
      NO_IO_CHECK='Both';
      NO_ASSERT_CHECK='TRUE';
      NO_DIR_CHECK='TRUE';
      ALLOW_CONNECT='TRUE';
    'VSS_T19':
      PIN_NUMBER='(0,0,0,0,0,0,0,0,0,0,0,0,0,0,0,0,0,0,0,0,0,0,0,0,0,0,0,0,T19,0~
,0,0,0,0,0,0,0,0,0,0)';
      PINUSE='POWER';
      NO_LOAD_CHECK='Both';
      NO_IO_CHECK='Both';
      NO_ASSERT_CHECK='TRUE';
      NO_DIR_CHECK='TRUE';
      ALLOW_CONNECT='TRUE';
    'VSS_T22':
      PIN_NUMBER='(0,0,0,0,0,0,0,0,0,0,0,0,0,0,0,0,0,0,0,0,0,0,0,0,0,0,0,0,T22,0~
,0,0,0,0,0,0,0,0,0,0)';
      PINUSE='POWER';
      NO_LOAD_CHECK='Both';
      NO_IO_CHECK='Both';
      NO_ASSERT_CHECK='TRUE';
      NO_DIR_CHECK='TRUE';
      ALLOW_CONNECT='TRUE';
    'VSS_T25':
      PIN_NUMBER='(0,0,0,0,0,0,0,0,0,0,0,0,0,0,0,0,0,0,0,0,0,0,0,0,0,0,0,0,T25,0~
,0,0,0,0,0,0,0,0,0,0)';
      PINUSE='POWER';
      NO_LOAD_CHECK='Both';
      NO_IO_CHECK='Both';
      NO_ASSERT_CHECK='TRUE';
      NO_DIR_CHECK='TRUE';
      ALLOW_CONNECT='TRUE';
    'VSS_T28':
      PIN_NUMBER='(0,0,0,0,0,0,0,0,0,0,0,0,0,0,0,0,0,0,0,0,0,0,0,0,0,0,0,0,T28,0~
,0,0,0,0,0,0,0,0,0,0)';
      PINUSE='POWER';
      NO_LOAD_CHECK='Both';
      NO_IO_CHECK='Both';
      NO_ASSERT_CHECK='TRUE';
      NO_DIR_CHECK='TRUE';
      ALLOW_CONNECT='TRUE';
    'VSS_T31':
      PIN_NUMBER='(0,0,0,0,0,0,0,0,0,0,0,0,0,0,0,0,0,0,0,0,0,0,0,0,0,0,0,0,T31,0~
,0,0,0,0,0,0,0,0,0,0)';
      PINUSE='POWER';
      NO_LOAD_CHECK='Both';
      NO_IO_CHECK='Both';
      NO_ASSERT_CHECK='TRUE';
      NO_DIR_CHECK='TRUE';
      ALLOW_CONNECT='TRUE';
    'VSS_T34':
      PIN_NUMBER='(0,0,0,0,0,0,0,0,0,0,0,0,0,0,0,0,0,0,0,0,0,0,0,0,0,0,0,0,T34,0~
,0,0,0,0,0,0,0,0,0,0)';
      PINUSE='POWER';
      NO_LOAD_CHECK='Both';
      NO_IO_CHECK='Both';
      NO_ASSERT_CHECK='TRUE';
      NO_DIR_CHECK='TRUE';
      ALLOW_CONNECT='TRUE';
    'VSS_T37':
      PIN_NUMBER='(0,0,0,0,0,0,0,0,0,0,0,0,0,0,0,0,0,0,0,0,0,0,0,0,0,0,0,0,T37,0~
,0,0,0,0,0,0,0,0,0,0)';
      PINUSE='POWER';
      NO_LOAD_CHECK='Both';
      NO_IO_CHECK='Both';
      NO_ASSERT_CHECK='TRUE';
      NO_DIR_CHECK='TRUE';
      ALLOW_CONNECT='TRUE';
    'VSS_T39':
      PIN_NUMBER='(0,0,0,0,0,0,0,0,0,0,0,0,0,0,0,0,0,0,0,0,0,0,0,0,0,0,0,0,T39,0~
,0,0,0,0,0,0,0,0,0,0)';
      PINUSE='POWER';
      NO_LOAD_CHECK='Both';
      NO_IO_CHECK='Both';
      NO_ASSERT_CHECK='TRUE';
      NO_DIR_CHECK='TRUE';
      ALLOW_CONNECT='TRUE';
    'VSS_T42':
      PIN_NUMBER='(0,0,0,0,0,0,0,0,0,0,0,0,0,0,0,0,0,0,0,0,0,0,0,0,0,0,0,0,T42,0~
,0,0,0,0,0,0,0,0,0,0)';
      PINUSE='POWER';
      NO_LOAD_CHECK='Both';
      NO_IO_CHECK='Both';
      NO_ASSERT_CHECK='TRUE';
      NO_DIR_CHECK='TRUE';
      ALLOW_CONNECT='TRUE';
    'VSS_T45':
      PIN_NUMBER='(0,0,0,0,0,0,0,0,0,0,0,0,0,0,0,0,0,0,0,0,0,0,0,0,0,0,0,0,T45,0~
,0,0,0,0,0,0,0,0,0,0)';
      PINUSE='POWER';
      NO_LOAD_CHECK='Both';
      NO_IO_CHECK='Both';
      NO_ASSERT_CHECK='TRUE';
      NO_DIR_CHECK='TRUE';
      ALLOW_CONNECT='TRUE';
    'VSS_T48':
      PIN_NUMBER='(0,0,0,0,0,0,0,0,0,0,0,0,0,0,0,0,0,0,0,0,0,0,0,0,0,0,0,0,T48,0~
,0,0,0,0,0,0,0,0,0,0)';
      PINUSE='POWER';
      NO_LOAD_CHECK='Both';
      NO_IO_CHECK='Both';
      NO_ASSERT_CHECK='TRUE';
      NO_DIR_CHECK='TRUE';
      ALLOW_CONNECT='TRUE';
    'VSS_T51':
      PIN_NUMBER='(0,0,0,0,0,0,0,0,0,0,0,0,0,0,0,0,0,0,0,0,0,0,0,0,0,0,0,0,T51,0~
,0,0,0,0,0,0,0,0,0,0)';
      PINUSE='POWER';
      NO_LOAD_CHECK='Both';
      NO_IO_CHECK='Both';
      NO_ASSERT_CHECK='TRUE';
      NO_DIR_CHECK='TRUE';
      ALLOW_CONNECT='TRUE';
    'VSS_T54':
      PIN_NUMBER='(0,0,0,0,0,0,0,0,0,0,0,0,0,0,0,0,0,0,0,0,0,0,0,0,0,0,0,0,T54,0~
,0,0,0,0,0,0,0,0,0,0)';
      PINUSE='POWER';
      NO_LOAD_CHECK='Both';
      NO_IO_CHECK='Both';
      NO_ASSERT_CHECK='TRUE';
      NO_DIR_CHECK='TRUE';
      ALLOW_CONNECT='TRUE';
    'VSS_T57':
      PIN_NUMBER='(0,0,0,0,0,0,0,0,0,0,0,0,0,0,0,0,0,0,0,0,0,0,0,0,0,0,0,0,T57,0~
,0,0,0,0,0,0,0,0,0,0)';
      PINUSE='POWER';
      NO_LOAD_CHECK='Both';
      NO_IO_CHECK='Both';
      NO_ASSERT_CHECK='TRUE';
      NO_DIR_CHECK='TRUE';
      ALLOW_CONNECT='TRUE';
    'VSS_T59':
      PIN_NUMBER='(0,0,0,0,0,0,0,0,0,0,0,0,0,0,0,0,0,0,0,0,0,0,0,0,0,0,0,0,T59,0~
,0,0,0,0,0,0,0,0,0,0)';
      PINUSE='POWER';
      NO_LOAD_CHECK='Both';
      NO_IO_CHECK='Both';
      NO_ASSERT_CHECK='TRUE';
      NO_DIR_CHECK='TRUE';
      ALLOW_CONNECT='TRUE';
    'VSS_T61':
      PIN_NUMBER='(0,0,0,0,0,0,0,0,0,0,0,0,0,0,0,0,0,0,0,0,0,0,0,0,0,0,0,0,T61,0~
,0,0,0,0,0,0,0,0,0,0)';
      PINUSE='POWER';
      NO_LOAD_CHECK='Both';
      NO_IO_CHECK='Both';
      NO_ASSERT_CHECK='TRUE';
      NO_DIR_CHECK='TRUE';
      ALLOW_CONNECT='TRUE';
    'VSS_T64':
      PIN_NUMBER='(0,0,0,0,0,0,0,0,0,0,0,0,0,0,0,0,0,0,0,0,0,0,0,0,0,0,0,0,T64,0~
,0,0,0,0,0,0,0,0,0,0)';
      PINUSE='POWER';
      NO_LOAD_CHECK='Both';
      NO_IO_CHECK='Both';
      NO_ASSERT_CHECK='TRUE';
      NO_DIR_CHECK='TRUE';
      ALLOW_CONNECT='TRUE';
    'VSS_J15':
      PIN_NUMBER='(0,0,0,0,0,0,0,0,0,0,0,0,0,0,0,0,0,0,0,0,0,0,0,0,0,0,0,0,J15,0~
,0,0,0,0,0,0,0,0,0,0)';
      PINUSE='POWER';
      NO_LOAD_CHECK='Both';
      NO_IO_CHECK='Both';
      NO_ASSERT_CHECK='TRUE';
      NO_DIR_CHECK='TRUE';
      ALLOW_CONNECT='TRUE';
    'VSS_J18':
      PIN_NUMBER='(0,0,0,0,0,0,0,0,0,0,0,0,0,0,0,0,0,0,0,0,0,0,0,0,0,0,0,0,J18,0~
,0,0,0,0,0,0,0,0,0,0)';
      PINUSE='POWER';
      NO_LOAD_CHECK='Both';
      NO_IO_CHECK='Both';
      NO_ASSERT_CHECK='TRUE';
      NO_DIR_CHECK='TRUE';
      ALLOW_CONNECT='TRUE';
    'VSS_J20':
      PIN_NUMBER='(0,0,0,0,0,0,0,0,0,0,0,0,0,0,0,0,0,0,0,0,0,0,0,0,0,0,0,0,J20,0~
,0,0,0,0,0,0,0,0,0,0)';
      PINUSE='POWER';
      NO_LOAD_CHECK='Both';
      NO_IO_CHECK='Both';
      NO_ASSERT_CHECK='TRUE';
      NO_DIR_CHECK='TRUE';
      ALLOW_CONNECT='TRUE';
    'VSS_J22':
      PIN_NUMBER='(0,0,0,0,0,0,0,0,0,0,0,0,0,0,0,0,0,0,0,0,0,0,0,0,0,0,0,0,J22,0~
,0,0,0,0,0,0,0,0,0,0)';
      PINUSE='POWER';
      NO_LOAD_CHECK='Both';
      NO_IO_CHECK='Both';
      NO_ASSERT_CHECK='TRUE';
      NO_DIR_CHECK='TRUE';
      ALLOW_CONNECT='TRUE';
    'VSS_J25':
      PIN_NUMBER='(0,0,0,0,0,0,0,0,0,0,0,0,0,0,0,0,0,0,0,0,0,0,0,0,0,0,0,0,J25,0~
,0,0,0,0,0,0,0,0,0,0)';
      PINUSE='POWER';
      NO_LOAD_CHECK='Both';
      NO_IO_CHECK='Both';
      NO_ASSERT_CHECK='TRUE';
      NO_DIR_CHECK='TRUE';
      ALLOW_CONNECT='TRUE';
    'VSS_J28':
      PIN_NUMBER='(0,0,0,0,0,0,0,0,0,0,0,0,0,0,0,0,0,0,0,0,0,0,0,0,0,0,0,0,J28,0~
,0,0,0,0,0,0,0,0,0,0)';
      PINUSE='POWER';
      NO_LOAD_CHECK='Both';
      NO_IO_CHECK='Both';
      NO_ASSERT_CHECK='TRUE';
      NO_DIR_CHECK='TRUE';
      ALLOW_CONNECT='TRUE';
    'VSS_J31':
      PIN_NUMBER='(0,0,0,0,0,0,0,0,0,0,0,0,0,0,0,0,0,0,0,0,0,0,0,0,0,0,0,0,J31,0~
,0,0,0,0,0,0,0,0,0,0)';
      PINUSE='POWER';
      NO_LOAD_CHECK='Both';
      NO_IO_CHECK='Both';
      NO_ASSERT_CHECK='TRUE';
      NO_DIR_CHECK='TRUE';
      ALLOW_CONNECT='TRUE';
    'VSS_J34':
      PIN_NUMBER='(0,0,0,0,0,0,0,0,0,0,0,0,0,0,0,0,0,0,0,0,0,0,0,0,0,0,0,0,J34,0~
,0,0,0,0,0,0,0,0,0,0)';
      PINUSE='POWER';
      NO_LOAD_CHECK='Both';
      NO_IO_CHECK='Both';
      NO_ASSERT_CHECK='TRUE';
      NO_DIR_CHECK='TRUE';
      ALLOW_CONNECT='TRUE';
    'VSS_J42':
      PIN_NUMBER='(0,0,0,0,0,0,0,0,0,0,0,0,0,0,0,0,0,0,0,0,0,0,0,0,0,0,0,0,J42,0~
,0,0,0,0,0,0,0,0,0,0)';
      PINUSE='POWER';
      NO_LOAD_CHECK='Both';
      NO_IO_CHECK='Both';
      NO_ASSERT_CHECK='TRUE';
      NO_DIR_CHECK='TRUE';
      ALLOW_CONNECT='TRUE';
    'VSS_J45':
      PIN_NUMBER='(0,0,0,0,0,0,0,0,0,0,0,0,0,0,0,0,0,0,0,0,0,0,0,0,0,0,0,0,J45,0~
,0,0,0,0,0,0,0,0,0,0)';
      PINUSE='POWER';
      NO_LOAD_CHECK='Both';
      NO_IO_CHECK='Both';
      NO_ASSERT_CHECK='TRUE';
      NO_DIR_CHECK='TRUE';
      ALLOW_CONNECT='TRUE';
    'VSS_J48':
      PIN_NUMBER='(0,0,0,0,0,0,0,0,0,0,0,0,0,0,0,0,0,0,0,0,0,0,0,0,0,0,0,0,J48,0~
,0,0,0,0,0,0,0,0,0,0)';
      PINUSE='POWER';
      NO_LOAD_CHECK='Both';
      NO_IO_CHECK='Both';
      NO_ASSERT_CHECK='TRUE';
      NO_DIR_CHECK='TRUE';
      ALLOW_CONNECT='TRUE';
    'VSS_J51':
      PIN_NUMBER='(0,0,0,0,0,0,0,0,0,0,0,0,0,0,0,0,0,0,0,0,0,0,0,0,0,0,0,0,J51,0~
,0,0,0,0,0,0,0,0,0,0)';
      PINUSE='POWER';
      NO_LOAD_CHECK='Both';
      NO_IO_CHECK='Both';
      NO_ASSERT_CHECK='TRUE';
      NO_DIR_CHECK='TRUE';
      ALLOW_CONNECT='TRUE';
    'VSS_J54':
      PIN_NUMBER='(0,0,0,0,0,0,0,0,0,0,0,0,0,0,0,0,0,0,0,0,0,0,0,0,0,0,0,0,J54,0~
,0,0,0,0,0,0,0,0,0,0)';
      PINUSE='POWER';
      NO_LOAD_CHECK='Both';
      NO_IO_CHECK='Both';
      NO_ASSERT_CHECK='TRUE';
      NO_DIR_CHECK='TRUE';
      ALLOW_CONNECT='TRUE';
    'VSS_J56':
      PIN_NUMBER='(0,0,0,0,0,0,0,0,0,0,0,0,0,0,0,0,0,0,0,0,0,0,0,0,0,0,0,0,J56,0~
,0,0,0,0,0,0,0,0,0,0)';
      PINUSE='POWER';
      NO_LOAD_CHECK='Both';
      NO_IO_CHECK='Both';
      NO_ASSERT_CHECK='TRUE';
      NO_DIR_CHECK='TRUE';
      ALLOW_CONNECT='TRUE';
    'VSS_J58':
      PIN_NUMBER='(0,0,0,0,0,0,0,0,0,0,0,0,0,0,0,0,0,0,0,0,0,0,0,0,0,0,0,0,J58,0~
,0,0,0,0,0,0,0,0,0,0)';
      PINUSE='POWER';
      NO_LOAD_CHECK='Both';
      NO_IO_CHECK='Both';
      NO_ASSERT_CHECK='TRUE';
      NO_DIR_CHECK='TRUE';
      ALLOW_CONNECT='TRUE';
    'VSS_J61':
      PIN_NUMBER='(0,0,0,0,0,0,0,0,0,0,0,0,0,0,0,0,0,0,0,0,0,0,0,0,0,0,0,0,J61,0~
,0,0,0,0,0,0,0,0,0,0)';
      PINUSE='POWER';
      NO_LOAD_CHECK='Both';
      NO_IO_CHECK='Both';
      NO_ASSERT_CHECK='TRUE';
      NO_DIR_CHECK='TRUE';
      ALLOW_CONNECT='TRUE';
    'VSS_J63':
      PIN_NUMBER='(0,0,0,0,0,0,0,0,0,0,0,0,0,0,0,0,0,0,0,0,0,0,0,0,0,0,0,0,J63,0~
,0,0,0,0,0,0,0,0,0,0)';
      PINUSE='POWER';
      NO_LOAD_CHECK='Both';
      NO_IO_CHECK='Both';
      NO_ASSERT_CHECK='TRUE';
      NO_DIR_CHECK='TRUE';
      ALLOW_CONNECT='TRUE';
    'VSS_J65':
      PIN_NUMBER='(0,0,0,0,0,0,0,0,0,0,0,0,0,0,0,0,0,0,0,0,0,0,0,0,0,0,0,0,J65,0~
,0,0,0,0,0,0,0,0,0,0)';
      PINUSE='POWER';
      NO_LOAD_CHECK='Both';
      NO_IO_CHECK='Both';
      NO_ASSERT_CHECK='TRUE';
      NO_DIR_CHECK='TRUE';
      ALLOW_CONNECT='TRUE';
    'VSS_J68':
      PIN_NUMBER='(0,0,0,0,0,0,0,0,0,0,0,0,0,0,0,0,0,0,0,0,0,0,0,0,0,0,0,0,J68,0~
,0,0,0,0,0,0,0,0,0,0)';
      PINUSE='POWER';
      NO_LOAD_CHECK='Both';
      NO_IO_CHECK='Both';
      NO_ASSERT_CHECK='TRUE';
      NO_DIR_CHECK='TRUE';
      ALLOW_CONNECT='TRUE';
    'VSS_J70':
      PIN_NUMBER='(0,0,0,0,0,0,0,0,0,0,0,0,0,0,0,0,0,0,0,0,0,0,0,0,0,0,0,0,J70,0~
,0,0,0,0,0,0,0,0,0,0)';
      PINUSE='POWER';
      NO_LOAD_CHECK='Both';
      NO_IO_CHECK='Both';
      NO_ASSERT_CHECK='TRUE';
      NO_DIR_CHECK='TRUE';
      ALLOW_CONNECT='TRUE';
    'VSS_J72':
      PIN_NUMBER='(0,0,0,0,0,0,0,0,0,0,0,0,0,0,0,0,0,0,0,0,0,0,0,0,0,0,0,0,J72,0~
,0,0,0,0,0,0,0,0,0,0)';
      PINUSE='POWER';
      NO_LOAD_CHECK='Both';
      NO_IO_CHECK='Both';
      NO_ASSERT_CHECK='TRUE';
      NO_DIR_CHECK='TRUE';
      ALLOW_CONNECT='TRUE';
    'VSS_J75':
      PIN_NUMBER='(0,0,0,0,0,0,0,0,0,0,0,0,0,0,0,0,0,0,0,0,0,0,0,0,0,0,0,0,J75,0~
,0,0,0,0,0,0,0,0,0,0)';
      PINUSE='POWER';
      NO_LOAD_CHECK='Both';
      NO_IO_CHECK='Both';
      NO_ASSERT_CHECK='TRUE';
      NO_DIR_CHECK='TRUE';
      ALLOW_CONNECT='TRUE';
    'VSS_K3':
      PIN_NUMBER='(0,0,0,0,0,0,0,0,0,0,0,0,0,0,0,0,0,0,0,0,0,0,0,0,0,0,0,0,K3,0,~
0,0,0,0,0,0,0,0,0,0)';
      PINUSE='POWER';
      NO_LOAD_CHECK='Both';
      NO_IO_CHECK='Both';
      NO_ASSERT_CHECK='TRUE';
      NO_DIR_CHECK='TRUE';
      ALLOW_CONNECT='TRUE';
    'VSS_K5':
      PIN_NUMBER='(0,0,0,0,0,0,0,0,0,0,0,0,0,0,0,0,0,0,0,0,0,0,0,0,0,0,0,0,K5,0,~
0,0,0,0,0,0,0,0,0,0)';
      PINUSE='POWER';
      NO_LOAD_CHECK='Both';
      NO_IO_CHECK='Both';
      NO_ASSERT_CHECK='TRUE';
      NO_DIR_CHECK='TRUE';
      ALLOW_CONNECT='TRUE';
    'VSS_K8':
      PIN_NUMBER='(0,0,0,0,0,0,0,0,0,0,0,0,0,0,0,0,0,0,0,0,0,0,0,0,0,0,0,0,K8,0,~
0,0,0,0,0,0,0,0,0,0)';
      PINUSE='POWER';
      NO_LOAD_CHECK='Both';
      NO_IO_CHECK='Both';
      NO_ASSERT_CHECK='TRUE';
      NO_DIR_CHECK='TRUE';
      ALLOW_CONNECT='TRUE';
    'VSS_K10':
      PIN_NUMBER='(0,0,0,0,0,0,0,0,0,0,0,0,0,0,0,0,0,0,0,0,0,0,0,0,0,0,0,0,K10,0~
,0,0,0,0,0,0,0,0,0,0)';
      PINUSE='POWER';
      NO_LOAD_CHECK='Both';
      NO_IO_CHECK='Both';
      NO_ASSERT_CHECK='TRUE';
      NO_DIR_CHECK='TRUE';
      ALLOW_CONNECT='TRUE';
    'VSS_K12':
      PIN_NUMBER='(0,0,0,0,0,0,0,0,0,0,0,0,0,0,0,0,0,0,0,0,0,0,0,0,0,0,0,0,K12,0~
,0,0,0,0,0,0,0,0,0,0)';
      PINUSE='POWER';
      NO_LOAD_CHECK='Both';
      NO_IO_CHECK='Both';
      NO_ASSERT_CHECK='TRUE';
      NO_DIR_CHECK='TRUE';
      ALLOW_CONNECT='TRUE';
    'VSS_K15':
      PIN_NUMBER='(0,0,0,0,0,0,0,0,0,0,0,0,0,0,0,0,0,0,0,0,0,0,0,0,0,0,0,0,K15,0~
,0,0,0,0,0,0,0,0,0,0)';
      PINUSE='POWER';
      NO_LOAD_CHECK='Both';
      NO_IO_CHECK='Both';
      NO_ASSERT_CHECK='TRUE';
      NO_DIR_CHECK='TRUE';
      ALLOW_CONNECT='TRUE';
    'VSS_K17':
      PIN_NUMBER='(0,0,0,0,0,0,0,0,0,0,0,0,0,0,0,0,0,0,0,0,0,0,0,0,0,0,0,0,K17,0~
,0,0,0,0,0,0,0,0,0,0)';
      PINUSE='POWER';
      NO_LOAD_CHECK='Both';
      NO_IO_CHECK='Both';
      NO_ASSERT_CHECK='TRUE';
      NO_DIR_CHECK='TRUE';
      ALLOW_CONNECT='TRUE';
    'VSS_K19':
      PIN_NUMBER='(0,0,0,0,0,0,0,0,0,0,0,0,0,0,0,0,0,0,0,0,0,0,0,0,0,0,0,0,K19,0~
,0,0,0,0,0,0,0,0,0,0)';
      PINUSE='POWER';
      NO_LOAD_CHECK='Both';
      NO_IO_CHECK='Both';
      NO_ASSERT_CHECK='TRUE';
      NO_DIR_CHECK='TRUE';
      ALLOW_CONNECT='TRUE';
    'VSS_K24':
      PIN_NUMBER='(0,0,0,0,0,0,0,0,0,0,0,0,0,0,0,0,0,0,0,0,0,0,0,0,0,0,0,0,K24,0~
,0,0,0,0,0,0,0,0,0,0)';
      PINUSE='POWER';
      NO_LOAD_CHECK='Both';
      NO_IO_CHECK='Both';
      NO_ASSERT_CHECK='TRUE';
      NO_DIR_CHECK='TRUE';
      ALLOW_CONNECT='TRUE';
    'VSS_K25':
      PIN_NUMBER='(0,0,0,0,0,0,0,0,0,0,0,0,0,0,0,0,0,0,0,0,0,0,0,0,0,0,0,0,K25,0~
,0,0,0,0,0,0,0,0,0,0)';
      PINUSE='POWER';
      NO_LOAD_CHECK='Both';
      NO_IO_CHECK='Both';
      NO_ASSERT_CHECK='TRUE';
      NO_DIR_CHECK='TRUE';
      ALLOW_CONNECT='TRUE';
    'VSS_K26':
      PIN_NUMBER='(0,0,0,0,0,0,0,0,0,0,0,0,0,0,0,0,0,0,0,0,0,0,0,0,0,0,0,0,K26,0~
,0,0,0,0,0,0,0,0,0,0)';
      PINUSE='POWER';
      NO_LOAD_CHECK='Both';
      NO_IO_CHECK='Both';
      NO_ASSERT_CHECK='TRUE';
      NO_DIR_CHECK='TRUE';
      ALLOW_CONNECT='TRUE';
    'VSS_K27':
      PIN_NUMBER='(0,0,0,0,0,0,0,0,0,0,0,0,0,0,0,0,0,0,0,0,0,0,0,0,0,0,0,0,K27,0~
,0,0,0,0,0,0,0,0,0,0)';
      PINUSE='POWER';
      NO_LOAD_CHECK='Both';
      NO_IO_CHECK='Both';
      NO_ASSERT_CHECK='TRUE';
      NO_DIR_CHECK='TRUE';
      ALLOW_CONNECT='TRUE';
    'VSS_K28':
      PIN_NUMBER='(0,0,0,0,0,0,0,0,0,0,0,0,0,0,0,0,0,0,0,0,0,0,0,0,0,0,0,0,K28,0~
,0,0,0,0,0,0,0,0,0,0)';
      PINUSE='POWER';
      NO_LOAD_CHECK='Both';
      NO_IO_CHECK='Both';
      NO_ASSERT_CHECK='TRUE';
      NO_DIR_CHECK='TRUE';
      ALLOW_CONNECT='TRUE';
    'VSS_K29':
      PIN_NUMBER='(0,0,0,0,0,0,0,0,0,0,0,0,0,0,0,0,0,0,0,0,0,0,0,0,0,0,0,0,K29,0~
,0,0,0,0,0,0,0,0,0,0)';
      PINUSE='POWER';
      NO_LOAD_CHECK='Both';
      NO_IO_CHECK='Both';
      NO_ASSERT_CHECK='TRUE';
      NO_DIR_CHECK='TRUE';
      ALLOW_CONNECT='TRUE';
    'VSS_K30':
      PIN_NUMBER='(0,0,0,0,0,0,0,0,0,0,0,0,0,0,0,0,0,0,0,0,0,0,0,0,0,0,0,0,K30,0~
,0,0,0,0,0,0,0,0,0,0)';
      PINUSE='POWER';
      NO_LOAD_CHECK='Both';
      NO_IO_CHECK='Both';
      NO_ASSERT_CHECK='TRUE';
      NO_DIR_CHECK='TRUE';
      ALLOW_CONNECT='TRUE';
    'VSS_K31':
      PIN_NUMBER='(0,0,0,0,0,0,0,0,0,0,0,0,0,0,0,0,0,0,0,0,0,0,0,0,0,0,0,0,K31,0~
,0,0,0,0,0,0,0,0,0,0)';
      PINUSE='POWER';
      NO_LOAD_CHECK='Both';
      NO_IO_CHECK='Both';
      NO_ASSERT_CHECK='TRUE';
      NO_DIR_CHECK='TRUE';
      ALLOW_CONNECT='TRUE';
    'VSS_K32':
      PIN_NUMBER='(0,0,0,0,0,0,0,0,0,0,0,0,0,0,0,0,0,0,0,0,0,0,0,0,0,0,0,0,K32,0~
,0,0,0,0,0,0,0,0,0,0)';
      PINUSE='POWER';
      NO_LOAD_CHECK='Both';
      NO_IO_CHECK='Both';
      NO_ASSERT_CHECK='TRUE';
      NO_DIR_CHECK='TRUE';
      ALLOW_CONNECT='TRUE';
    'VSS_K33':
      PIN_NUMBER='(0,0,0,0,0,0,0,0,0,0,0,0,0,0,0,0,0,0,0,0,0,0,0,0,0,0,0,0,K33,0~
,0,0,0,0,0,0,0,0,0,0)';
      PINUSE='POWER';
      NO_LOAD_CHECK='Both';
      NO_IO_CHECK='Both';
      NO_ASSERT_CHECK='TRUE';
      NO_DIR_CHECK='TRUE';
      ALLOW_CONNECT='TRUE';
    'VSS_K34':
      PIN_NUMBER='(0,0,0,0,0,0,0,0,0,0,0,0,0,0,0,0,0,0,0,0,0,0,0,0,0,0,0,0,K34,0~
,0,0,0,0,0,0,0,0,0,0)';
      PINUSE='POWER';
      NO_LOAD_CHECK='Both';
      NO_IO_CHECK='Both';
      NO_ASSERT_CHECK='TRUE';
      NO_DIR_CHECK='TRUE';
      ALLOW_CONNECT='TRUE';
    'VSS_K37':
      PIN_NUMBER='(0,0,0,0,0,0,0,0,0,0,0,0,0,0,0,0,0,0,0,0,0,0,0,0,0,0,0,0,K37,0~
,0,0,0,0,0,0,0,0,0,0)';
      PINUSE='POWER';
      NO_LOAD_CHECK='Both';
      NO_IO_CHECK='Both';
      NO_ASSERT_CHECK='TRUE';
      NO_DIR_CHECK='TRUE';
      ALLOW_CONNECT='TRUE';
    'VSS_K39':
      PIN_NUMBER='(0,0,0,0,0,0,0,0,0,0,0,0,0,0,0,0,0,0,0,0,0,0,0,0,0,0,0,0,K39,0~
,0,0,0,0,0,0,0,0,0,0)';
      PINUSE='POWER';
      NO_LOAD_CHECK='Both';
      NO_IO_CHECK='Both';
      NO_ASSERT_CHECK='TRUE';
      NO_DIR_CHECK='TRUE';
      ALLOW_CONNECT='TRUE';
    'VSS_K42':
      PIN_NUMBER='(0,0,0,0,0,0,0,0,0,0,0,0,0,0,0,0,0,0,0,0,0,0,0,0,0,0,0,0,K42,0~
,0,0,0,0,0,0,0,0,0,0)';
      PINUSE='POWER';
      NO_LOAD_CHECK='Both';
      NO_IO_CHECK='Both';
      NO_ASSERT_CHECK='TRUE';
      NO_DIR_CHECK='TRUE';
      ALLOW_CONNECT='TRUE';
    'VSS_K43':
      PIN_NUMBER='(0,0,0,0,0,0,0,0,0,0,0,0,0,0,0,0,0,0,0,0,0,0,0,0,0,0,0,0,K43,0~
,0,0,0,0,0,0,0,0,0,0)';
      PINUSE='POWER';
      NO_LOAD_CHECK='Both';
      NO_IO_CHECK='Both';
      NO_ASSERT_CHECK='TRUE';
      NO_DIR_CHECK='TRUE';
      ALLOW_CONNECT='TRUE';
    'VSS_K44':
      PIN_NUMBER='(0,0,0,0,0,0,0,0,0,0,0,0,0,0,0,0,0,0,0,0,0,0,0,0,0,0,0,0,K44,0~
,0,0,0,0,0,0,0,0,0,0)';
      PINUSE='POWER';
      NO_LOAD_CHECK='Both';
      NO_IO_CHECK='Both';
      NO_ASSERT_CHECK='TRUE';
      NO_DIR_CHECK='TRUE';
      ALLOW_CONNECT='TRUE';
    'VSS_K45':
      PIN_NUMBER='(0,0,0,0,0,0,0,0,0,0,0,0,0,0,0,0,0,0,0,0,0,0,0,0,0,0,0,0,K45,0~
,0,0,0,0,0,0,0,0,0,0)';
      PINUSE='POWER';
      NO_LOAD_CHECK='Both';
      NO_IO_CHECK='Both';
      NO_ASSERT_CHECK='TRUE';
      NO_DIR_CHECK='TRUE';
      ALLOW_CONNECT='TRUE';
    'VSS_K46':
      PIN_NUMBER='(0,0,0,0,0,0,0,0,0,0,0,0,0,0,0,0,0,0,0,0,0,0,0,0,0,0,0,0,K46,0~
,0,0,0,0,0,0,0,0,0,0)';
      PINUSE='POWER';
      NO_LOAD_CHECK='Both';
      NO_IO_CHECK='Both';
      NO_ASSERT_CHECK='TRUE';
      NO_DIR_CHECK='TRUE';
      ALLOW_CONNECT='TRUE';
    'VSS_K47':
      PIN_NUMBER='(0,0,0,0,0,0,0,0,0,0,0,0,0,0,0,0,0,0,0,0,0,0,0,0,0,0,0,0,K47,0~
,0,0,0,0,0,0,0,0,0,0)';
      PINUSE='POWER';
      NO_LOAD_CHECK='Both';
      NO_IO_CHECK='Both';
      NO_ASSERT_CHECK='TRUE';
      NO_DIR_CHECK='TRUE';
      ALLOW_CONNECT='TRUE';
    'VSS_K48':
      PIN_NUMBER='(0,0,0,0,0,0,0,0,0,0,0,0,0,0,0,0,0,0,0,0,0,0,0,0,0,0,0,0,K48,0~
,0,0,0,0,0,0,0,0,0,0)';
      PINUSE='POWER';
      NO_LOAD_CHECK='Both';
      NO_IO_CHECK='Both';
      NO_ASSERT_CHECK='TRUE';
      NO_DIR_CHECK='TRUE';
      ALLOW_CONNECT='TRUE';
    'VSS_K49':
      PIN_NUMBER='(0,0,0,0,0,0,0,0,0,0,0,0,0,0,0,0,0,0,0,0,0,0,0,0,0,0,0,0,K49,0~
,0,0,0,0,0,0,0,0,0,0)';
      PINUSE='POWER';
      NO_LOAD_CHECK='Both';
      NO_IO_CHECK='Both';
      NO_ASSERT_CHECK='TRUE';
      NO_DIR_CHECK='TRUE';
      ALLOW_CONNECT='TRUE';
    'VSS_K50':
      PIN_NUMBER='(0,0,0,0,0,0,0,0,0,0,0,0,0,0,0,0,0,0,0,0,0,0,0,0,0,0,0,0,K50,0~
,0,0,0,0,0,0,0,0,0,0)';
      PINUSE='POWER';
      NO_LOAD_CHECK='Both';
      NO_IO_CHECK='Both';
      NO_ASSERT_CHECK='TRUE';
      NO_DIR_CHECK='TRUE';
      ALLOW_CONNECT='TRUE';
    'VSS_K51':
      PIN_NUMBER='(0,0,0,0,0,0,0,0,0,0,0,0,0,0,0,0,0,0,0,0,0,0,0,0,0,0,0,0,K51,0~
,0,0,0,0,0,0,0,0,0,0)';
      PINUSE='POWER';
      NO_LOAD_CHECK='Both';
      NO_IO_CHECK='Both';
      NO_ASSERT_CHECK='TRUE';
      NO_DIR_CHECK='TRUE';
      ALLOW_CONNECT='TRUE';
    'VSS_K52':
      PIN_NUMBER='(0,0,0,0,0,0,0,0,0,0,0,0,0,0,0,0,0,0,0,0,0,0,0,0,0,0,0,0,K52,0~
,0,0,0,0,0,0,0,0,0,0)';
      PINUSE='POWER';
      NO_LOAD_CHECK='Both';
      NO_IO_CHECK='Both';
      NO_ASSERT_CHECK='TRUE';
      NO_DIR_CHECK='TRUE';
      ALLOW_CONNECT='TRUE';
    'VSS_K53':
      PIN_NUMBER='(0,0,0,0,0,0,0,0,0,0,0,0,0,0,0,0,0,0,0,0,0,0,0,0,0,0,0,0,K53,0~
,0,0,0,0,0,0,0,0,0,0)';
      PINUSE='POWER';
      NO_LOAD_CHECK='Both';
      NO_IO_CHECK='Both';
      NO_ASSERT_CHECK='TRUE';
      NO_DIR_CHECK='TRUE';
      ALLOW_CONNECT='TRUE';
    'VSS_K57':
      PIN_NUMBER='(0,0,0,0,0,0,0,0,0,0,0,0,0,0,0,0,0,0,0,0,0,0,0,0,0,0,0,0,K57,0~
,0,0,0,0,0,0,0,0,0,0)';
      PINUSE='POWER';
      NO_LOAD_CHECK='Both';
      NO_IO_CHECK='Both';
      NO_ASSERT_CHECK='TRUE';
      NO_DIR_CHECK='TRUE';
      ALLOW_CONNECT='TRUE';
    'VSS_K61':
      PIN_NUMBER='(0,0,0,0,0,0,0,0,0,0,0,0,0,0,0,0,0,0,0,0,0,0,0,0,0,0,0,0,K61,0~
,0,0,0,0,0,0,0,0,0,0)';
      PINUSE='POWER';
      NO_LOAD_CHECK='Both';
      NO_IO_CHECK='Both';
      NO_ASSERT_CHECK='TRUE';
      NO_DIR_CHECK='TRUE';
      ALLOW_CONNECT='TRUE';
    'VSS_K64':
      PIN_NUMBER='(0,0,0,0,0,0,0,0,0,0,0,0,0,0,0,0,0,0,0,0,0,0,0,0,0,0,0,0,K64,0~
,0,0,0,0,0,0,0,0,0,0)';
      PINUSE='POWER';
      NO_LOAD_CHECK='Both';
      NO_IO_CHECK='Both';
      NO_ASSERT_CHECK='TRUE';
      NO_DIR_CHECK='TRUE';
      ALLOW_CONNECT='TRUE';
    'VSS_K66':
      PIN_NUMBER='(0,0,0,0,0,0,0,0,0,0,0,0,0,0,0,0,0,0,0,0,0,0,0,0,0,0,0,0,K66,0~
,0,0,0,0,0,0,0,0,0,0)';
      PINUSE='POWER';
      NO_LOAD_CHECK='Both';
      NO_IO_CHECK='Both';
      NO_ASSERT_CHECK='TRUE';
      NO_DIR_CHECK='TRUE';
      ALLOW_CONNECT='TRUE';
    'VSS_K68':
      PIN_NUMBER='(0,0,0,0,0,0,0,0,0,0,0,0,0,0,0,0,0,0,0,0,0,0,0,0,0,0,0,0,K68,0~
,0,0,0,0,0,0,0,0,0,0)';
      PINUSE='POWER';
      NO_LOAD_CHECK='Both';
      NO_IO_CHECK='Both';
      NO_ASSERT_CHECK='TRUE';
      NO_DIR_CHECK='TRUE';
      ALLOW_CONNECT='TRUE';
    'VSS_K71':
      PIN_NUMBER='(0,0,0,0,0,0,0,0,0,0,0,0,0,0,0,0,0,0,0,0,0,0,0,0,0,0,0,0,K71,0~
,0,0,0,0,0,0,0,0,0,0)';
      PINUSE='POWER';
      NO_LOAD_CHECK='Both';
      NO_IO_CHECK='Both';
      NO_ASSERT_CHECK='TRUE';
      NO_DIR_CHECK='TRUE';
      ALLOW_CONNECT='TRUE';
    'VSS_K73':
      PIN_NUMBER='(0,0,0,0,0,0,0,0,0,0,0,0,0,0,0,0,0,0,0,0,0,0,0,0,0,0,0,0,K73,0~
,0,0,0,0,0,0,0,0,0,0)';
      PINUSE='POWER';
      NO_LOAD_CHECK='Both';
      NO_IO_CHECK='Both';
      NO_ASSERT_CHECK='TRUE';
      NO_DIR_CHECK='TRUE';
      ALLOW_CONNECT='TRUE';
    'VSS_L1':
      PIN_NUMBER='(0,0,0,0,0,0,0,0,0,0,0,0,0,0,0,0,0,0,0,0,0,0,0,0,0,0,0,0,L1,0,~
0,0,0,0,0,0,0,0,0,0)';
      PINUSE='POWER';
      NO_LOAD_CHECK='Both';
      NO_IO_CHECK='Both';
      NO_ASSERT_CHECK='TRUE';
      NO_DIR_CHECK='TRUE';
      ALLOW_CONNECT='TRUE';
    'VSS_L6':
      PIN_NUMBER='(0,0,0,0,0,0,0,0,0,0,0,0,0,0,0,0,0,0,0,0,0,0,0,0,0,0,0,0,L6,0,~
0,0,0,0,0,0,0,0,0,0)';
      PINUSE='POWER';
      NO_LOAD_CHECK='Both';
      NO_IO_CHECK='Both';
      NO_ASSERT_CHECK='TRUE';
      NO_DIR_CHECK='TRUE';
      ALLOW_CONNECT='TRUE';
    'VSS_L8':
      PIN_NUMBER='(0,0,0,0,0,0,0,0,0,0,0,0,0,0,0,0,0,0,0,0,0,0,0,0,0,0,0,0,L8,0,~
0,0,0,0,0,0,0,0,0,0)';
      PINUSE='POWER';
      NO_LOAD_CHECK='Both';
      NO_IO_CHECK='Both';
      NO_ASSERT_CHECK='TRUE';
      NO_DIR_CHECK='TRUE';
      ALLOW_CONNECT='TRUE';
    'VSS_L13':
      PIN_NUMBER='(0,0,0,0,0,0,0,0,0,0,0,0,0,0,0,0,0,0,0,0,0,0,0,0,0,0,0,0,L13,0~
,0,0,0,0,0,0,0,0,0,0)';
      PINUSE='POWER';
      NO_LOAD_CHECK='Both';
      NO_IO_CHECK='Both';
      NO_ASSERT_CHECK='TRUE';
      NO_DIR_CHECK='TRUE';
      ALLOW_CONNECT='TRUE';
    'VSS_L15':
      PIN_NUMBER='(0,0,0,0,0,0,0,0,0,0,0,0,0,0,0,0,0,0,0,0,0,0,0,0,0,0,0,0,L15,0~
,0,0,0,0,0,0,0,0,0,0)';
      PINUSE='POWER';
      NO_LOAD_CHECK='Both';
      NO_IO_CHECK='Both';
      NO_ASSERT_CHECK='TRUE';
      NO_DIR_CHECK='TRUE';
      ALLOW_CONNECT='TRUE';
    'VSS_L20':
      PIN_NUMBER='(0,0,0,0,0,0,0,0,0,0,0,0,0,0,0,0,0,0,0,0,0,0,0,0,0,0,0,0,L20,0~
,0,0,0,0,0,0,0,0,0,0)';
      PINUSE='POWER';
      NO_LOAD_CHECK='Both';
      NO_IO_CHECK='Both';
      NO_ASSERT_CHECK='TRUE';
      NO_DIR_CHECK='TRUE';
      ALLOW_CONNECT='TRUE';
    'VSS_L22':
      PIN_NUMBER='(0,0,0,0,0,0,0,0,0,0,0,0,0,0,0,0,0,0,0,0,0,0,0,0,0,0,0,0,L22,0~
,0,0,0,0,0,0,0,0,0,0)';
      PINUSE='POWER';
      NO_LOAD_CHECK='Both';
      NO_IO_CHECK='Both';
      NO_ASSERT_CHECK='TRUE';
      NO_DIR_CHECK='TRUE';
      ALLOW_CONNECT='TRUE';
    'VSS_L25':
      PIN_NUMBER='(0,0,0,0,0,0,0,0,0,0,0,0,0,0,0,0,0,0,0,0,0,0,0,0,0,0,0,0,L25,0~
,0,0,0,0,0,0,0,0,0,0)';
      PINUSE='POWER';
      NO_LOAD_CHECK='Both';
      NO_IO_CHECK='Both';
      NO_ASSERT_CHECK='TRUE';
      NO_DIR_CHECK='TRUE';
      ALLOW_CONNECT='TRUE';
    'VSS_L28':
      PIN_NUMBER='(0,0,0,0,0,0,0,0,0,0,0,0,0,0,0,0,0,0,0,0,0,0,0,0,0,0,0,0,L28,0~
,0,0,0,0,0,0,0,0,0,0)';
      PINUSE='POWER';
      NO_LOAD_CHECK='Both';
      NO_IO_CHECK='Both';
      NO_ASSERT_CHECK='TRUE';
      NO_DIR_CHECK='TRUE';
      ALLOW_CONNECT='TRUE';
    'VSS_L31':
      PIN_NUMBER='(0,0,0,0,0,0,0,0,0,0,0,0,0,0,0,0,0,0,0,0,0,0,0,0,0,0,0,0,L31,0~
,0,0,0,0,0,0,0,0,0,0)';
      PINUSE='POWER';
      NO_LOAD_CHECK='Both';
      NO_IO_CHECK='Both';
      NO_ASSERT_CHECK='TRUE';
      NO_DIR_CHECK='TRUE';
      ALLOW_CONNECT='TRUE';
    'VSS_L34':
      PIN_NUMBER='(0,0,0,0,0,0,0,0,0,0,0,0,0,0,0,0,0,0,0,0,0,0,0,0,0,0,0,0,L34,0~
,0,0,0,0,0,0,0,0,0,0)';
      PINUSE='POWER';
      NO_LOAD_CHECK='Both';
      NO_IO_CHECK='Both';
      NO_ASSERT_CHECK='TRUE';
      NO_DIR_CHECK='TRUE';
      ALLOW_CONNECT='TRUE';
    'VSS_L35':
      PIN_NUMBER='(0,0,0,0,0,0,0,0,0,0,0,0,0,0,0,0,0,0,0,0,0,0,0,0,0,0,0,0,L35,0~
,0,0,0,0,0,0,0,0,0,0)';
      PINUSE='POWER';
      NO_LOAD_CHECK='Both';
      NO_IO_CHECK='Both';
      NO_ASSERT_CHECK='TRUE';
      NO_DIR_CHECK='TRUE';
      ALLOW_CONNECT='TRUE';
    'VSS_L36':
      PIN_NUMBER='(0,0,0,0,0,0,0,0,0,0,0,0,0,0,0,0,0,0,0,0,0,0,0,0,0,0,0,0,L36,0~
,0,0,0,0,0,0,0,0,0,0)';
      PINUSE='POWER';
      NO_LOAD_CHECK='Both';
      NO_IO_CHECK='Both';
      NO_ASSERT_CHECK='TRUE';
      NO_DIR_CHECK='TRUE';
      ALLOW_CONNECT='TRUE';
    'VSS_L40':
      PIN_NUMBER='(0,0,0,0,0,0,0,0,0,0,0,0,0,0,0,0,0,0,0,0,0,0,0,0,0,0,0,0,L40,0~
,0,0,0,0,0,0,0,0,0,0)';
      PINUSE='POWER';
      NO_LOAD_CHECK='Both';
      NO_IO_CHECK='Both';
      NO_ASSERT_CHECK='TRUE';
      NO_DIR_CHECK='TRUE';
      ALLOW_CONNECT='TRUE';
    'VSS_L41':
      PIN_NUMBER='(0,0,0,0,0,0,0,0,0,0,0,0,0,0,0,0,0,0,0,0,0,0,0,0,0,0,0,0,L41,0~
,0,0,0,0,0,0,0,0,0,0)';
      PINUSE='POWER';
      NO_LOAD_CHECK='Both';
      NO_IO_CHECK='Both';
      NO_ASSERT_CHECK='TRUE';
      NO_DIR_CHECK='TRUE';
      ALLOW_CONNECT='TRUE';
    'VSS_L42':
      PIN_NUMBER='(0,0,0,0,0,0,0,0,0,0,0,0,0,0,0,0,0,0,0,0,0,0,0,0,0,0,0,0,L42,0~
,0,0,0,0,0,0,0,0,0,0)';
      PINUSE='POWER';
      NO_LOAD_CHECK='Both';
      NO_IO_CHECK='Both';
      NO_ASSERT_CHECK='TRUE';
      NO_DIR_CHECK='TRUE';
      ALLOW_CONNECT='TRUE';
    'VSS_L45':
      PIN_NUMBER='(0,0,0,0,0,0,0,0,0,0,0,0,0,0,0,0,0,0,0,0,0,0,0,0,0,0,0,0,L45,0~
,0,0,0,0,0,0,0,0,0,0)';
      PINUSE='POWER';
      NO_LOAD_CHECK='Both';
      NO_IO_CHECK='Both';
      NO_ASSERT_CHECK='TRUE';
      NO_DIR_CHECK='TRUE';
      ALLOW_CONNECT='TRUE';
    'VSS_L48':
      PIN_NUMBER='(0,0,0,0,0,0,0,0,0,0,0,0,0,0,0,0,0,0,0,0,0,0,0,0,0,0,0,0,L48,0~
,0,0,0,0,0,0,0,0,0,0)';
      PINUSE='POWER';
      NO_LOAD_CHECK='Both';
      NO_IO_CHECK='Both';
      NO_ASSERT_CHECK='TRUE';
      NO_DIR_CHECK='TRUE';
      ALLOW_CONNECT='TRUE';
    'VSS_L51':
      PIN_NUMBER='(0,0,0,0,0,0,0,0,0,0,0,0,0,0,0,0,0,0,0,0,0,0,0,0,0,0,0,0,L51,0~
,0,0,0,0,0,0,0,0,0,0)';
      PINUSE='POWER';
      NO_LOAD_CHECK='Both';
      NO_IO_CHECK='Both';
      NO_ASSERT_CHECK='TRUE';
      NO_DIR_CHECK='TRUE';
      ALLOW_CONNECT='TRUE';
    'VSS_L54':
      PIN_NUMBER='(0,0,0,0,0,0,0,0,0,0,0,0,0,0,0,0,0,0,0,0,0,0,0,0,0,0,0,0,L54,0~
,0,0,0,0,0,0,0,0,0,0)';
      PINUSE='POWER';
      NO_LOAD_CHECK='Both';
      NO_IO_CHECK='Both';
      NO_ASSERT_CHECK='TRUE';
      NO_DIR_CHECK='TRUE';
      ALLOW_CONNECT='TRUE';
    'VSS_L56':
      PIN_NUMBER='(0,0,0,0,0,0,0,0,0,0,0,0,0,0,0,0,0,0,0,0,0,0,0,0,0,0,0,0,L56,0~
,0,0,0,0,0,0,0,0,0,0)';
      PINUSE='POWER';
      NO_LOAD_CHECK='Both';
      NO_IO_CHECK='Both';
      NO_ASSERT_CHECK='TRUE';
      NO_DIR_CHECK='TRUE';
      ALLOW_CONNECT='TRUE';
    'VSS_L61':
      PIN_NUMBER='(0,0,0,0,0,0,0,0,0,0,0,0,0,0,0,0,0,0,0,0,0,0,0,0,0,0,0,0,L61,0~
,0,0,0,0,0,0,0,0,0,0)';
      PINUSE='POWER';
      NO_LOAD_CHECK='Both';
      NO_IO_CHECK='Both';
      NO_ASSERT_CHECK='TRUE';
      NO_DIR_CHECK='TRUE';
      ALLOW_CONNECT='TRUE';
    'VSS_L63':
      PIN_NUMBER='(0,0,0,0,0,0,0,0,0,0,0,0,0,0,0,0,0,0,0,0,0,0,0,0,0,0,0,0,L63,0~
,0,0,0,0,0,0,0,0,0,0)';
      PINUSE='POWER';
      NO_LOAD_CHECK='Both';
      NO_IO_CHECK='Both';
      NO_ASSERT_CHECK='TRUE';
      NO_DIR_CHECK='TRUE';
      ALLOW_CONNECT='TRUE';
    'VSS_L68':
      PIN_NUMBER='(0,0,0,0,0,0,0,0,0,0,0,0,0,0,0,0,0,0,0,0,0,0,0,0,0,0,0,0,L68,0~
,0,0,0,0,0,0,0,0,0,0)';
      PINUSE='POWER';
      NO_LOAD_CHECK='Both';
      NO_IO_CHECK='Both';
      NO_ASSERT_CHECK='TRUE';
      NO_DIR_CHECK='TRUE';
      ALLOW_CONNECT='TRUE';
    'VSS_L70':
      PIN_NUMBER='(0,0,0,0,0,0,0,0,0,0,0,0,0,0,0,0,0,0,0,0,0,0,0,0,0,0,0,0,L70,0~
,0,0,0,0,0,0,0,0,0,0)';
      PINUSE='POWER';
      NO_LOAD_CHECK='Both';
      NO_IO_CHECK='Both';
      NO_ASSERT_CHECK='TRUE';
      NO_DIR_CHECK='TRUE';
      ALLOW_CONNECT='TRUE';
    'VSS_L75':
      PIN_NUMBER='(0,0,0,0,0,0,0,0,0,0,0,0,0,0,0,0,0,0,0,0,0,0,0,0,0,0,0,0,L75,0~
,0,0,0,0,0,0,0,0,0,0)';
      PINUSE='POWER';
      NO_LOAD_CHECK='Both';
      NO_IO_CHECK='Both';
      NO_ASSERT_CHECK='TRUE';
      NO_DIR_CHECK='TRUE';
      ALLOW_CONNECT='TRUE';
    'VSS_M3':
      PIN_NUMBER='(0,0,0,0,0,0,0,0,0,0,0,0,0,0,0,0,0,0,0,0,0,0,0,0,0,0,0,0,M3,0,~
0,0,0,0,0,0,0,0,0,0)';
      PINUSE='POWER';
      NO_LOAD_CHECK='Both';
      NO_IO_CHECK='Both';
      NO_ASSERT_CHECK='TRUE';
      NO_DIR_CHECK='TRUE';
      ALLOW_CONNECT='TRUE';
    'VSS_M5':
      PIN_NUMBER='(0,0,0,0,0,0,0,0,0,0,0,0,0,0,0,0,0,0,0,0,0,0,0,0,0,0,0,0,M5,0,~
0,0,0,0,0,0,0,0,0,0)';
      PINUSE='POWER';
      NO_LOAD_CHECK='Both';
      NO_IO_CHECK='Both';
      NO_ASSERT_CHECK='TRUE';
      NO_DIR_CHECK='TRUE';
      ALLOW_CONNECT='TRUE';
    'VSS_M8':
      PIN_NUMBER='(0,0,0,0,0,0,0,0,0,0,0,0,0,0,0,0,0,0,0,0,0,0,0,0,0,0,0,0,M8,0,~
0,0,0,0,0,0,0,0,0,0)';
      PINUSE='POWER';
      NO_LOAD_CHECK='Both';
      NO_IO_CHECK='Both';
      NO_ASSERT_CHECK='TRUE';
      NO_DIR_CHECK='TRUE';
      ALLOW_CONNECT='TRUE';
    'VSS_M10':
      PIN_NUMBER='(0,0,0,0,0,0,0,0,0,0,0,0,0,0,0,0,0,0,0,0,0,0,0,0,0,0,0,0,M10,0~
,0,0,0,0,0,0,0,0,0,0)';
      PINUSE='POWER';
      NO_LOAD_CHECK='Both';
      NO_IO_CHECK='Both';
      NO_ASSERT_CHECK='TRUE';
      NO_DIR_CHECK='TRUE';
      ALLOW_CONNECT='TRUE';
    'VSS_M12':
      PIN_NUMBER='(0,0,0,0,0,0,0,0,0,0,0,0,0,0,0,0,0,0,0,0,0,0,0,0,0,0,0,0,M12,0~
,0,0,0,0,0,0,0,0,0,0)';
      PINUSE='POWER';
      NO_LOAD_CHECK='Both';
      NO_IO_CHECK='Both';
      NO_ASSERT_CHECK='TRUE';
      NO_DIR_CHECK='TRUE';
      ALLOW_CONNECT='TRUE';
    'VSS_M15':
      PIN_NUMBER='(0,0,0,0,0,0,0,0,0,0,0,0,0,0,0,0,0,0,0,0,0,0,0,0,0,0,0,0,M15,0~
,0,0,0,0,0,0,0,0,0,0)';
      PINUSE='POWER';
      NO_LOAD_CHECK='Both';
      NO_IO_CHECK='Both';
      NO_ASSERT_CHECK='TRUE';
      NO_DIR_CHECK='TRUE';
      ALLOW_CONNECT='TRUE';
    'VSS_M17':
      PIN_NUMBER='(0,0,0,0,0,0,0,0,0,0,0,0,0,0,0,0,0,0,0,0,0,0,0,0,0,0,0,0,M17,0~
,0,0,0,0,0,0,0,0,0,0)';
      PINUSE='POWER';
      NO_LOAD_CHECK='Both';
      NO_IO_CHECK='Both';
      NO_ASSERT_CHECK='TRUE';
      NO_DIR_CHECK='TRUE';
      ALLOW_CONNECT='TRUE';
    'VSS_M19':
      PIN_NUMBER='(0,0,0,0,0,0,0,0,0,0,0,0,0,0,0,0,0,0,0,0,0,0,0,0,0,0,0,0,M19,0~
,0,0,0,0,0,0,0,0,0,0)';
      PINUSE='POWER';
      NO_LOAD_CHECK='Both';
      NO_IO_CHECK='Both';
      NO_ASSERT_CHECK='TRUE';
      NO_DIR_CHECK='TRUE';
      ALLOW_CONNECT='TRUE';
    'VSS_M22':
      PIN_NUMBER='(0,0,0,0,0,0,0,0,0,0,0,0,0,0,0,0,0,0,0,0,0,0,0,0,0,0,0,0,M22,0~
,0,0,0,0,0,0,0,0,0,0)';
      PINUSE='POWER';
      NO_LOAD_CHECK='Both';
      NO_IO_CHECK='Both';
      NO_ASSERT_CHECK='TRUE';
      NO_DIR_CHECK='TRUE';
      ALLOW_CONNECT='TRUE';
    'VSS_M25':
      PIN_NUMBER='(0,0,0,0,0,0,0,0,0,0,0,0,0,0,0,0,0,0,0,0,0,0,0,0,0,0,0,0,M25,0~
,0,0,0,0,0,0,0,0,0,0)';
      PINUSE='POWER';
      NO_LOAD_CHECK='Both';
      NO_IO_CHECK='Both';
      NO_ASSERT_CHECK='TRUE';
      NO_DIR_CHECK='TRUE';
      ALLOW_CONNECT='TRUE';
    'VSS_M28':
      PIN_NUMBER='(0,0,0,0,0,0,0,0,0,0,0,0,0,0,0,0,0,0,0,0,0,0,0,0,0,0,0,0,M28,0~
,0,0,0,0,0,0,0,0,0,0)';
      PINUSE='POWER';
      NO_LOAD_CHECK='Both';
      NO_IO_CHECK='Both';
      NO_ASSERT_CHECK='TRUE';
      NO_DIR_CHECK='TRUE';
      ALLOW_CONNECT='TRUE';
    'VSS_M31':
      PIN_NUMBER='(0,0,0,0,0,0,0,0,0,0,0,0,0,0,0,0,0,0,0,0,0,0,0,0,0,0,0,0,M31,0~
,0,0,0,0,0,0,0,0,0,0)';
      PINUSE='POWER';
      NO_LOAD_CHECK='Both';
      NO_IO_CHECK='Both';
      NO_ASSERT_CHECK='TRUE';
      NO_DIR_CHECK='TRUE';
      ALLOW_CONNECT='TRUE';
    'VSS_M34':
      PIN_NUMBER='(0,0,0,0,0,0,0,0,0,0,0,0,0,0,0,0,0,0,0,0,0,0,0,0,0,0,0,0,M34,0~
,0,0,0,0,0,0,0,0,0,0)';
      PINUSE='POWER';
      NO_LOAD_CHECK='Both';
      NO_IO_CHECK='Both';
      NO_ASSERT_CHECK='TRUE';
      NO_DIR_CHECK='TRUE';
      ALLOW_CONNECT='TRUE';
    'VSS_M37':
      PIN_NUMBER='(0,0,0,0,0,0,0,0,0,0,0,0,0,0,0,0,0,0,0,0,0,0,0,0,0,0,0,0,M37,0~
,0,0,0,0,0,0,0,0,0,0)';
      PINUSE='POWER';
      NO_LOAD_CHECK='Both';
      NO_IO_CHECK='Both';
      NO_ASSERT_CHECK='TRUE';
      NO_DIR_CHECK='TRUE';
      ALLOW_CONNECT='TRUE';
    'VSS_M39':
      PIN_NUMBER='(0,0,0,0,0,0,0,0,0,0,0,0,0,0,0,0,0,0,0,0,0,0,0,0,0,0,0,0,M39,0~
,0,0,0,0,0,0,0,0,0,0)';
      PINUSE='POWER';
      NO_LOAD_CHECK='Both';
      NO_IO_CHECK='Both';
      NO_ASSERT_CHECK='TRUE';
      NO_DIR_CHECK='TRUE';
      ALLOW_CONNECT='TRUE';
    'VSS_M42':
      PIN_NUMBER='(0,0,0,0,0,0,0,0,0,0,0,0,0,0,0,0,0,0,0,0,0,0,0,0,0,0,0,0,M42,0~
,0,0,0,0,0,0,0,0,0,0)';
      PINUSE='POWER';
      NO_LOAD_CHECK='Both';
      NO_IO_CHECK='Both';
      NO_ASSERT_CHECK='TRUE';
      NO_DIR_CHECK='TRUE';
      ALLOW_CONNECT='TRUE';
    'VSS_M45':
      PIN_NUMBER='(0,0,0,0,0,0,0,0,0,0,0,0,0,0,0,0,0,0,0,0,0,0,0,0,0,0,0,0,M45,0~
,0,0,0,0,0,0,0,0,0,0)';
      PINUSE='POWER';
      NO_LOAD_CHECK='Both';
      NO_IO_CHECK='Both';
      NO_ASSERT_CHECK='TRUE';
      NO_DIR_CHECK='TRUE';
      ALLOW_CONNECT='TRUE';
    'VSS_M48':
      PIN_NUMBER='(0,0,0,0,0,0,0,0,0,0,0,0,0,0,0,0,0,0,0,0,0,0,0,0,0,0,0,0,M48,0~
,0,0,0,0,0,0,0,0,0,0)';
      PINUSE='POWER';
      NO_LOAD_CHECK='Both';
      NO_IO_CHECK='Both';
      NO_ASSERT_CHECK='TRUE';
      NO_DIR_CHECK='TRUE';
      ALLOW_CONNECT='TRUE';
    'VSS_M51':
      PIN_NUMBER='(0,0,0,0,0,0,0,0,0,0,0,0,0,0,0,0,0,0,0,0,0,0,0,0,0,0,0,0,M51,0~
,0,0,0,0,0,0,0,0,0,0)';
      PINUSE='POWER';
      NO_LOAD_CHECK='Both';
      NO_IO_CHECK='Both';
      NO_ASSERT_CHECK='TRUE';
      NO_DIR_CHECK='TRUE';
      ALLOW_CONNECT='TRUE';
    'VSS_M54':
      PIN_NUMBER='(0,0,0,0,0,0,0,0,0,0,0,0,0,0,0,0,0,0,0,0,0,0,0,0,0,0,0,0,M54,0~
,0,0,0,0,0,0,0,0,0,0)';
      PINUSE='POWER';
      NO_LOAD_CHECK='Both';
      NO_IO_CHECK='Both';
      NO_ASSERT_CHECK='TRUE';
      NO_DIR_CHECK='TRUE';
      ALLOW_CONNECT='TRUE';
    'VSS_M57':
      PIN_NUMBER='(0,0,0,0,0,0,0,0,0,0,0,0,0,0,0,0,0,0,0,0,0,0,0,0,0,0,0,0,M57,0~
,0,0,0,0,0,0,0,0,0,0)';
      PINUSE='POWER';
      NO_LOAD_CHECK='Both';
      NO_IO_CHECK='Both';
      NO_ASSERT_CHECK='TRUE';
      NO_DIR_CHECK='TRUE';
      ALLOW_CONNECT='TRUE';
    'VSS_M59':
      PIN_NUMBER='(0,0,0,0,0,0,0,0,0,0,0,0,0,0,0,0,0,0,0,0,0,0,0,0,0,0,0,0,M59,0~
,0,0,0,0,0,0,0,0,0,0)';
      PINUSE='POWER';
      NO_LOAD_CHECK='Both';
      NO_IO_CHECK='Both';
      NO_ASSERT_CHECK='TRUE';
      NO_DIR_CHECK='TRUE';
      ALLOW_CONNECT='TRUE';
    'VSS_M61':
      PIN_NUMBER='(0,0,0,0,0,0,0,0,0,0,0,0,0,0,0,0,0,0,0,0,0,0,0,0,0,0,0,0,M61,0~
,0,0,0,0,0,0,0,0,0,0)';
      PINUSE='POWER';
      NO_LOAD_CHECK='Both';
      NO_IO_CHECK='Both';
      NO_ASSERT_CHECK='TRUE';
      NO_DIR_CHECK='TRUE';
      ALLOW_CONNECT='TRUE';
    'VSS_M64':
      PIN_NUMBER='(0,0,0,0,0,0,0,0,0,0,0,0,0,0,0,0,0,0,0,0,0,0,0,0,0,0,0,0,M64,0~
,0,0,0,0,0,0,0,0,0,0)';
      PINUSE='POWER';
      NO_LOAD_CHECK='Both';
      NO_IO_CHECK='Both';
      NO_ASSERT_CHECK='TRUE';
      NO_DIR_CHECK='TRUE';
      ALLOW_CONNECT='TRUE';
    'VSS_M66':
      PIN_NUMBER='(0,0,0,0,0,0,0,0,0,0,0,0,0,0,0,0,0,0,0,0,0,0,0,0,0,0,0,0,M66,0~
,0,0,0,0,0,0,0,0,0,0)';
      PINUSE='POWER';
      NO_LOAD_CHECK='Both';
      NO_IO_CHECK='Both';
      NO_ASSERT_CHECK='TRUE';
      NO_DIR_CHECK='TRUE';
      ALLOW_CONNECT='TRUE';
    'VSS_M68':
      PIN_NUMBER='(0,0,0,0,0,0,0,0,0,0,0,0,0,0,0,0,0,0,0,0,0,0,0,0,0,0,0,0,M68,0~
,0,0,0,0,0,0,0,0,0,0)';
      PINUSE='POWER';
      NO_LOAD_CHECK='Both';
      NO_IO_CHECK='Both';
      NO_ASSERT_CHECK='TRUE';
      NO_DIR_CHECK='TRUE';
      ALLOW_CONNECT='TRUE';
    'VSS_M71':
      PIN_NUMBER='(0,0,0,0,0,0,0,0,0,0,0,0,0,0,0,0,0,0,0,0,0,0,0,0,0,0,0,0,M71,0~
,0,0,0,0,0,0,0,0,0,0)';
      PINUSE='POWER';
      NO_LOAD_CHECK='Both';
      NO_IO_CHECK='Both';
      NO_ASSERT_CHECK='TRUE';
      NO_DIR_CHECK='TRUE';
      ALLOW_CONNECT='TRUE';
    'VSS_M73':
      PIN_NUMBER='(0,0,0,0,0,0,0,0,0,0,0,0,0,0,0,0,0,0,0,0,0,0,0,0,0,0,0,0,M73,0~
,0,0,0,0,0,0,0,0,0,0)';
      PINUSE='POWER';
      NO_LOAD_CHECK='Both';
      NO_IO_CHECK='Both';
      NO_ASSERT_CHECK='TRUE';
      NO_DIR_CHECK='TRUE';
      ALLOW_CONNECT='TRUE';
    'VSS_N1':
      PIN_NUMBER='(0,0,0,0,0,0,0,0,0,0,0,0,0,0,0,0,0,0,0,0,0,0,0,0,0,0,0,0,N1,0,~
0,0,0,0,0,0,0,0,0,0)';
      PINUSE='POWER';
      NO_LOAD_CHECK='Both';
      NO_IO_CHECK='Both';
      NO_ASSERT_CHECK='TRUE';
      NO_DIR_CHECK='TRUE';
      ALLOW_CONNECT='TRUE';
    'VSS_N4':
      PIN_NUMBER='(0,0,0,0,0,0,0,0,0,0,0,0,0,0,0,0,0,0,0,0,0,0,0,0,0,0,0,0,N4,0,~
0,0,0,0,0,0,0,0,0,0)';
      PINUSE='POWER';
      NO_LOAD_CHECK='Both';
      NO_IO_CHECK='Both';
      NO_ASSERT_CHECK='TRUE';
      NO_DIR_CHECK='TRUE';
      ALLOW_CONNECT='TRUE';
    'VSS_N6':
      PIN_NUMBER='(0,0,0,0,0,0,0,0,0,0,0,0,0,0,0,0,0,0,0,0,0,0,0,0,0,0,0,0,N6,0,~
0,0,0,0,0,0,0,0,0,0)';
      PINUSE='POWER';
      NO_LOAD_CHECK='Both';
      NO_IO_CHECK='Both';
      NO_ASSERT_CHECK='TRUE';
      NO_DIR_CHECK='TRUE';
      ALLOW_CONNECT='TRUE';
    'VSS_N8':
      PIN_NUMBER='(0,0,0,0,0,0,0,0,0,0,0,0,0,0,0,0,0,0,0,0,0,0,0,0,0,0,0,0,N8,0,~
0,0,0,0,0,0,0,0,0,0)';
      PINUSE='POWER';
      NO_LOAD_CHECK='Both';
      NO_IO_CHECK='Both';
      NO_ASSERT_CHECK='TRUE';
      NO_DIR_CHECK='TRUE';
      ALLOW_CONNECT='TRUE';
    'VSS_N11':
      PIN_NUMBER='(0,0,0,0,0,0,0,0,0,0,0,0,0,0,0,0,0,0,0,0,0,0,0,0,0,0,0,0,N11,0~
,0,0,0,0,0,0,0,0,0,0)';
      PINUSE='POWER';
      NO_LOAD_CHECK='Both';
      NO_IO_CHECK='Both';
      NO_ASSERT_CHECK='TRUE';
      NO_DIR_CHECK='TRUE';
      ALLOW_CONNECT='TRUE';
    'VSS_N13':
      PIN_NUMBER='(0,0,0,0,0,0,0,0,0,0,0,0,0,0,0,0,0,0,0,0,0,0,0,0,0,0,0,0,N13,0~
,0,0,0,0,0,0,0,0,0,0)';
      PINUSE='POWER';
      NO_LOAD_CHECK='Both';
      NO_IO_CHECK='Both';
      NO_ASSERT_CHECK='TRUE';
      NO_DIR_CHECK='TRUE';
      ALLOW_CONNECT='TRUE';
    'VSS_N15':
      PIN_NUMBER='(0,0,0,0,0,0,0,0,0,0,0,0,0,0,0,0,0,0,0,0,0,0,0,0,0,0,0,0,N15,0~
,0,0,0,0,0,0,0,0,0,0)';
      PINUSE='POWER';
      NO_LOAD_CHECK='Both';
      NO_IO_CHECK='Both';
      NO_ASSERT_CHECK='TRUE';
      NO_DIR_CHECK='TRUE';
      ALLOW_CONNECT='TRUE';
    'VSS_N18':
      PIN_NUMBER='(0,0,0,0,0,0,0,0,0,0,0,0,0,0,0,0,0,0,0,0,0,0,0,0,0,0,0,0,N18,0~
,0,0,0,0,0,0,0,0,0,0)';
      PINUSE='POWER';
      NO_LOAD_CHECK='Both';
      NO_IO_CHECK='Both';
      NO_ASSERT_CHECK='TRUE';
      NO_DIR_CHECK='TRUE';
      ALLOW_CONNECT='TRUE';
    'VSS_N20':
      PIN_NUMBER='(0,0,0,0,0,0,0,0,0,0,0,0,0,0,0,0,0,0,0,0,0,0,0,0,0,0,0,0,N20,0~
,0,0,0,0,0,0,0,0,0,0)';
      PINUSE='POWER';
      NO_LOAD_CHECK='Both';
      NO_IO_CHECK='Both';
      NO_ASSERT_CHECK='TRUE';
      NO_DIR_CHECK='TRUE';
      ALLOW_CONNECT='TRUE';
    'VSS_N22':
      PIN_NUMBER='(0,0,0,0,0,0,0,0,0,0,0,0,0,0,0,0,0,0,0,0,0,0,0,0,0,0,0,0,N22,0~
,0,0,0,0,0,0,0,0,0,0)';
      PINUSE='POWER';
      NO_LOAD_CHECK='Both';
      NO_IO_CHECK='Both';
      NO_ASSERT_CHECK='TRUE';
      NO_DIR_CHECK='TRUE';
      ALLOW_CONNECT='TRUE';
    'VSS_N25':
      PIN_NUMBER='(0,0,0,0,0,0,0,0,0,0,0,0,0,0,0,0,0,0,0,0,0,0,0,0,0,0,0,0,N25,0~
,0,0,0,0,0,0,0,0,0,0)';
      PINUSE='POWER';
      NO_LOAD_CHECK='Both';
      NO_IO_CHECK='Both';
      NO_ASSERT_CHECK='TRUE';
      NO_DIR_CHECK='TRUE';
      ALLOW_CONNECT='TRUE';
    'VSS_N28':
      PIN_NUMBER='(0,0,0,0,0,0,0,0,0,0,0,0,0,0,0,0,0,0,0,0,0,0,0,0,0,0,0,0,N28,0~
,0,0,0,0,0,0,0,0,0,0)';
      PINUSE='POWER';
      NO_LOAD_CHECK='Both';
      NO_IO_CHECK='Both';
      NO_ASSERT_CHECK='TRUE';
      NO_DIR_CHECK='TRUE';
      ALLOW_CONNECT='TRUE';
    'VSS_N31':
      PIN_NUMBER='(0,0,0,0,0,0,0,0,0,0,0,0,0,0,0,0,0,0,0,0,0,0,0,0,0,0,0,0,N31,0~
,0,0,0,0,0,0,0,0,0,0)';
      PINUSE='POWER';
      NO_LOAD_CHECK='Both';
      NO_IO_CHECK='Both';
      NO_ASSERT_CHECK='TRUE';
      NO_DIR_CHECK='TRUE';
      ALLOW_CONNECT='TRUE';
    'VSS_N34':
      PIN_NUMBER='(0,0,0,0,0,0,0,0,0,0,0,0,0,0,0,0,0,0,0,0,0,0,0,0,0,0,0,0,N34,0~
,0,0,0,0,0,0,0,0,0,0)';
      PINUSE='POWER';
      NO_LOAD_CHECK='Both';
      NO_IO_CHECK='Both';
      NO_ASSERT_CHECK='TRUE';
      NO_DIR_CHECK='TRUE';
      ALLOW_CONNECT='TRUE';
    'VSS_N42':
      PIN_NUMBER='(0,0,0,0,0,0,0,0,0,0,0,0,0,0,0,0,0,0,0,0,0,0,0,0,0,0,0,0,N42,0~
,0,0,0,0,0,0,0,0,0,0)';
      PINUSE='POWER';
      NO_LOAD_CHECK='Both';
      NO_IO_CHECK='Both';
      NO_ASSERT_CHECK='TRUE';
      NO_DIR_CHECK='TRUE';
      ALLOW_CONNECT='TRUE';
    'VSS_N45':
      PIN_NUMBER='(0,0,0,0,0,0,0,0,0,0,0,0,0,0,0,0,0,0,0,0,0,0,0,0,0,0,0,0,N45,0~
,0,0,0,0,0,0,0,0,0,0)';
      PINUSE='POWER';
      NO_LOAD_CHECK='Both';
      NO_IO_CHECK='Both';
      NO_ASSERT_CHECK='TRUE';
      NO_DIR_CHECK='TRUE';
      ALLOW_CONNECT='TRUE';
    'VSS_N48':
      PIN_NUMBER='(0,0,0,0,0,0,0,0,0,0,0,0,0,0,0,0,0,0,0,0,0,0,0,0,0,0,0,0,N48,0~
,0,0,0,0,0,0,0,0,0,0)';
      PINUSE='POWER';
      NO_LOAD_CHECK='Both';
      NO_IO_CHECK='Both';
      NO_ASSERT_CHECK='TRUE';
      NO_DIR_CHECK='TRUE';
      ALLOW_CONNECT='TRUE';
    'VSS_N51':
      PIN_NUMBER='(0,0,0,0,0,0,0,0,0,0,0,0,0,0,0,0,0,0,0,0,0,0,0,0,0,0,0,0,N51,0~
,0,0,0,0,0,0,0,0,0,0)';
      PINUSE='POWER';
      NO_LOAD_CHECK='Both';
      NO_IO_CHECK='Both';
      NO_ASSERT_CHECK='TRUE';
      NO_DIR_CHECK='TRUE';
      ALLOW_CONNECT='TRUE';
    'VSS_N54':
      PIN_NUMBER='(0,0,0,0,0,0,0,0,0,0,0,0,0,0,0,0,0,0,0,0,0,0,0,0,0,0,0,0,N54,0~
,0,0,0,0,0,0,0,0,0,0)';
      PINUSE='POWER';
      NO_LOAD_CHECK='Both';
      NO_IO_CHECK='Both';
      NO_ASSERT_CHECK='TRUE';
      NO_DIR_CHECK='TRUE';
      ALLOW_CONNECT='TRUE';
    'VSS_N56':
      PIN_NUMBER='(0,0,0,0,0,0,0,0,0,0,0,0,0,0,0,0,0,0,0,0,0,0,0,0,0,0,0,0,N56,0~
,0,0,0,0,0,0,0,0,0,0)';
      PINUSE='POWER';
      NO_LOAD_CHECK='Both';
      NO_IO_CHECK='Both';
      NO_ASSERT_CHECK='TRUE';
      NO_DIR_CHECK='TRUE';
      ALLOW_CONNECT='TRUE';
    'VSS_N58':
      PIN_NUMBER='(0,0,0,0,0,0,0,0,0,0,0,0,0,0,0,0,0,0,0,0,0,0,0,0,0,0,0,0,N58,0~
,0,0,0,0,0,0,0,0,0,0)';
      PINUSE='POWER';
      NO_LOAD_CHECK='Both';
      NO_IO_CHECK='Both';
      NO_ASSERT_CHECK='TRUE';
      NO_DIR_CHECK='TRUE';
      ALLOW_CONNECT='TRUE';
    'VSS_N61':
      PIN_NUMBER='(0,0,0,0,0,0,0,0,0,0,0,0,0,0,0,0,0,0,0,0,0,0,0,0,0,0,0,0,N61,0~
,0,0,0,0,0,0,0,0,0,0)';
      PINUSE='POWER';
      NO_LOAD_CHECK='Both';
      NO_IO_CHECK='Both';
      NO_ASSERT_CHECK='TRUE';
      NO_DIR_CHECK='TRUE';
      ALLOW_CONNECT='TRUE';
    'VSS_N63':
      PIN_NUMBER='(0,0,0,0,0,0,0,0,0,0,0,0,0,0,0,0,0,0,0,0,0,0,0,0,0,0,0,0,N63,0~
,0,0,0,0,0,0,0,0,0,0)';
      PINUSE='POWER';
      NO_LOAD_CHECK='Both';
      NO_IO_CHECK='Both';
      NO_ASSERT_CHECK='TRUE';
      NO_DIR_CHECK='TRUE';
      ALLOW_CONNECT='TRUE';
    'VSS_N65':
      PIN_NUMBER='(0,0,0,0,0,0,0,0,0,0,0,0,0,0,0,0,0,0,0,0,0,0,0,0,0,0,0,0,N65,0~
,0,0,0,0,0,0,0,0,0,0)';
      PINUSE='POWER';
      NO_LOAD_CHECK='Both';
      NO_IO_CHECK='Both';
      NO_ASSERT_CHECK='TRUE';
      NO_DIR_CHECK='TRUE';
      ALLOW_CONNECT='TRUE';
    'VSS_N68':
      PIN_NUMBER='(0,0,0,0,0,0,0,0,0,0,0,0,0,0,0,0,0,0,0,0,0,0,0,0,0,0,0,0,N68,0~
,0,0,0,0,0,0,0,0,0,0)';
      PINUSE='POWER';
      NO_LOAD_CHECK='Both';
      NO_IO_CHECK='Both';
      NO_ASSERT_CHECK='TRUE';
      NO_DIR_CHECK='TRUE';
      ALLOW_CONNECT='TRUE';
    'VSS_N70':
      PIN_NUMBER='(0,0,0,0,0,0,0,0,0,0,0,0,0,0,0,0,0,0,0,0,0,0,0,0,0,0,0,0,N70,0~
,0,0,0,0,0,0,0,0,0,0)';
      PINUSE='POWER';
      NO_LOAD_CHECK='Both';
      NO_IO_CHECK='Both';
      NO_ASSERT_CHECK='TRUE';
      NO_DIR_CHECK='TRUE';
      ALLOW_CONNECT='TRUE';
    'VSS_N72':
      PIN_NUMBER='(0,0,0,0,0,0,0,0,0,0,0,0,0,0,0,0,0,0,0,0,0,0,0,0,0,0,0,0,N72,0~
,0,0,0,0,0,0,0,0,0,0)';
      PINUSE='POWER';
      NO_LOAD_CHECK='Both';
      NO_IO_CHECK='Both';
      NO_ASSERT_CHECK='TRUE';
      NO_DIR_CHECK='TRUE';
      ALLOW_CONNECT='TRUE';
    'VSS_N75':
      PIN_NUMBER='(0,0,0,0,0,0,0,0,0,0,0,0,0,0,0,0,0,0,0,0,0,0,0,0,0,0,0,0,N75,0~
,0,0,0,0,0,0,0,0,0,0)';
      PINUSE='POWER';
      NO_LOAD_CHECK='Both';
      NO_IO_CHECK='Both';
      NO_ASSERT_CHECK='TRUE';
      NO_DIR_CHECK='TRUE';
      ALLOW_CONNECT='TRUE';
    'VSS_P3':
      PIN_NUMBER='(0,0,0,0,0,0,0,0,0,0,0,0,0,0,0,0,0,0,0,0,0,0,0,0,0,0,0,0,P3,0,~
0,0,0,0,0,0,0,0,0,0)';
      PINUSE='POWER';
      NO_LOAD_CHECK='Both';
      NO_IO_CHECK='Both';
      NO_ASSERT_CHECK='TRUE';
      NO_DIR_CHECK='TRUE';
      ALLOW_CONNECT='TRUE';
    'VSS_P8':
      PIN_NUMBER='(0,0,0,0,0,0,0,0,0,0,0,0,0,0,0,0,0,0,0,0,0,0,0,0,0,0,0,0,P8,0,~
0,0,0,0,0,0,0,0,0,0)';
      PINUSE='POWER';
      NO_LOAD_CHECK='Both';
      NO_IO_CHECK='Both';
      NO_ASSERT_CHECK='TRUE';
      NO_DIR_CHECK='TRUE';
      ALLOW_CONNECT='TRUE';
    'VSS_P10':
      PIN_NUMBER='(0,0,0,0,0,0,0,0,0,0,0,0,0,0,0,0,0,0,0,0,0,0,0,0,0,0,0,0,P10,0~
,0,0,0,0,0,0,0,0,0,0)';
      PINUSE='POWER';
      NO_LOAD_CHECK='Both';
      NO_IO_CHECK='Both';
      NO_ASSERT_CHECK='TRUE';
      NO_DIR_CHECK='TRUE';
      ALLOW_CONNECT='TRUE';
    'VSS_P15':
      PIN_NUMBER='(0,0,0,0,0,0,0,0,0,0,0,0,0,0,0,0,0,0,0,0,0,0,0,0,0,0,0,0,P15,0~
,0,0,0,0,0,0,0,0,0,0)';
      PINUSE='POWER';
      NO_LOAD_CHECK='Both';
      NO_IO_CHECK='Both';
      NO_ASSERT_CHECK='TRUE';
      NO_DIR_CHECK='TRUE';
      ALLOW_CONNECT='TRUE';
    'VSS_P17':
      PIN_NUMBER='(0,0,0,0,0,0,0,0,0,0,0,0,0,0,0,0,0,0,0,0,0,0,0,0,0,0,0,0,P17,0~
,0,0,0,0,0,0,0,0,0,0)';
      PINUSE='POWER';
      NO_LOAD_CHECK='Both';
      NO_IO_CHECK='Both';
      NO_ASSERT_CHECK='TRUE';
      NO_DIR_CHECK='TRUE';
      ALLOW_CONNECT='TRUE';
    'VSS_P23':
      PIN_NUMBER='(0,0,0,0,0,0,0,0,0,0,0,0,0,0,0,0,0,0,0,0,0,0,0,0,0,0,0,0,P23,0~
,0,0,0,0,0,0,0,0,0,0)';
      PINUSE='POWER';
      NO_LOAD_CHECK='Both';
      NO_IO_CHECK='Both';
      NO_ASSERT_CHECK='TRUE';
      NO_DIR_CHECK='TRUE';
      ALLOW_CONNECT='TRUE';
    'VSS_P24':
      PIN_NUMBER='(0,0,0,0,0,0,0,0,0,0,0,0,0,0,0,0,0,0,0,0,0,0,0,0,0,0,0,0,P24,0~
,0,0,0,0,0,0,0,0,0,0)';
      PINUSE='POWER';
      NO_LOAD_CHECK='Both';
      NO_IO_CHECK='Both';
      NO_ASSERT_CHECK='TRUE';
      NO_DIR_CHECK='TRUE';
      ALLOW_CONNECT='TRUE';
    'VSS_P26':
      PIN_NUMBER='(0,0,0,0,0,0,0,0,0,0,0,0,0,0,0,0,0,0,0,0,0,0,0,0,0,0,0,0,P26,0~
,0,0,0,0,0,0,0,0,0,0)';
      PINUSE='POWER';
      NO_LOAD_CHECK='Both';
      NO_IO_CHECK='Both';
      NO_ASSERT_CHECK='TRUE';
      NO_DIR_CHECK='TRUE';
      ALLOW_CONNECT='TRUE';
    'VSS_P27':
      PIN_NUMBER='(0,0,0,0,0,0,0,0,0,0,0,0,0,0,0,0,0,0,0,0,0,0,0,0,0,0,0,0,P27,0~
,0,0,0,0,0,0,0,0,0,0)';
      PINUSE='POWER';
      NO_LOAD_CHECK='Both';
      NO_IO_CHECK='Both';
      NO_ASSERT_CHECK='TRUE';
      NO_DIR_CHECK='TRUE';
      ALLOW_CONNECT='TRUE';
    'VSS_P28':
      PIN_NUMBER='(0,0,0,0,0,0,0,0,0,0,0,0,0,0,0,0,0,0,0,0,0,0,0,0,0,0,0,0,P28,0~
,0,0,0,0,0,0,0,0,0,0)';
      PINUSE='POWER';
      NO_LOAD_CHECK='Both';
      NO_IO_CHECK='Both';
      NO_ASSERT_CHECK='TRUE';
      NO_DIR_CHECK='TRUE';
      ALLOW_CONNECT='TRUE';
    'VSS_P29':
      PIN_NUMBER='(0,0,0,0,0,0,0,0,0,0,0,0,0,0,0,0,0,0,0,0,0,0,0,0,0,0,0,0,P29,0~
,0,0,0,0,0,0,0,0,0,0)';
      PINUSE='POWER';
      NO_LOAD_CHECK='Both';
      NO_IO_CHECK='Both';
      NO_ASSERT_CHECK='TRUE';
      NO_DIR_CHECK='TRUE';
      ALLOW_CONNECT='TRUE';
    'VSS_P30':
      PIN_NUMBER='(0,0,0,0,0,0,0,0,0,0,0,0,0,0,0,0,0,0,0,0,0,0,0,0,0,0,0,0,P30,0~
,0,0,0,0,0,0,0,0,0,0)';
      PINUSE='POWER';
      NO_LOAD_CHECK='Both';
      NO_IO_CHECK='Both';
      NO_ASSERT_CHECK='TRUE';
      NO_DIR_CHECK='TRUE';
      ALLOW_CONNECT='TRUE';
    'VSS_P31':
      PIN_NUMBER='(0,0,0,0,0,0,0,0,0,0,0,0,0,0,0,0,0,0,0,0,0,0,0,0,0,0,0,0,P31,0~
,0,0,0,0,0,0,0,0,0,0)';
      PINUSE='POWER';
      NO_LOAD_CHECK='Both';
      NO_IO_CHECK='Both';
      NO_ASSERT_CHECK='TRUE';
      NO_DIR_CHECK='TRUE';
      ALLOW_CONNECT='TRUE';
    'VSS_P32':
      PIN_NUMBER='(0,0,0,0,0,0,0,0,0,0,0,0,0,0,0,0,0,0,0,0,0,0,0,0,0,0,0,0,P32,0~
,0,0,0,0,0,0,0,0,0,0)';
      PINUSE='POWER';
      NO_LOAD_CHECK='Both';
      NO_IO_CHECK='Both';
      NO_ASSERT_CHECK='TRUE';
      NO_DIR_CHECK='TRUE';
      ALLOW_CONNECT='TRUE';
    'VSS_P33':
      PIN_NUMBER='(0,0,0,0,0,0,0,0,0,0,0,0,0,0,0,0,0,0,0,0,0,0,0,0,0,0,0,0,P33,0~
,0,0,0,0,0,0,0,0,0,0)';
      PINUSE='POWER';
      NO_LOAD_CHECK='Both';
      NO_IO_CHECK='Both';
      NO_ASSERT_CHECK='TRUE';
      NO_DIR_CHECK='TRUE';
      ALLOW_CONNECT='TRUE';
    'VSS_P34':
      PIN_NUMBER='(0,0,0,0,0,0,0,0,0,0,0,0,0,0,0,0,0,0,0,0,0,0,0,0,0,0,0,0,P34,0~
,0,0,0,0,0,0,0,0,0,0)';
      PINUSE='POWER';
      NO_LOAD_CHECK='Both';
      NO_IO_CHECK='Both';
      NO_ASSERT_CHECK='TRUE';
      NO_DIR_CHECK='TRUE';
      ALLOW_CONNECT='TRUE';
    'VSS_P37':
      PIN_NUMBER='(0,0,0,0,0,0,0,0,0,0,0,0,0,0,0,0,0,0,0,0,0,0,0,0,0,0,0,0,P37,0~
,0,0,0,0,0,0,0,0,0,0)';
      PINUSE='POWER';
      NO_LOAD_CHECK='Both';
      NO_IO_CHECK='Both';
      NO_ASSERT_CHECK='TRUE';
      NO_DIR_CHECK='TRUE';
      ALLOW_CONNECT='TRUE';
    'VSS_P39':
      PIN_NUMBER='(0,0,0,0,0,0,0,0,0,0,0,0,0,0,0,0,0,0,0,0,0,0,0,0,0,0,0,0,P39,0~
,0,0,0,0,0,0,0,0,0,0)';
      PINUSE='POWER';
      NO_LOAD_CHECK='Both';
      NO_IO_CHECK='Both';
      NO_ASSERT_CHECK='TRUE';
      NO_DIR_CHECK='TRUE';
      ALLOW_CONNECT='TRUE';
    'VSS_P42':
      PIN_NUMBER='(0,0,0,0,0,0,0,0,0,0,0,0,0,0,0,0,0,0,0,0,0,0,0,0,0,0,0,0,P42,0~
,0,0,0,0,0,0,0,0,0,0)';
      PINUSE='POWER';
      NO_LOAD_CHECK='Both';
      NO_IO_CHECK='Both';
      NO_ASSERT_CHECK='TRUE';
      NO_DIR_CHECK='TRUE';
      ALLOW_CONNECT='TRUE';
    'VSS_P43':
      PIN_NUMBER='(0,0,0,0,0,0,0,0,0,0,0,0,0,0,0,0,0,0,0,0,0,0,0,0,0,0,0,0,P43,0~
,0,0,0,0,0,0,0,0,0,0)';
      PINUSE='POWER';
      NO_LOAD_CHECK='Both';
      NO_IO_CHECK='Both';
      NO_ASSERT_CHECK='TRUE';
      NO_DIR_CHECK='TRUE';
      ALLOW_CONNECT='TRUE';
    'VSS_P44':
      PIN_NUMBER='(0,0,0,0,0,0,0,0,0,0,0,0,0,0,0,0,0,0,0,0,0,0,0,0,0,0,0,0,P44,0~
,0,0,0,0,0,0,0,0,0,0)';
      PINUSE='POWER';
      NO_LOAD_CHECK='Both';
      NO_IO_CHECK='Both';
      NO_ASSERT_CHECK='TRUE';
      NO_DIR_CHECK='TRUE';
      ALLOW_CONNECT='TRUE';
    'VSS_P45':
      PIN_NUMBER='(0,0,0,0,0,0,0,0,0,0,0,0,0,0,0,0,0,0,0,0,0,0,0,0,0,0,0,0,P45,0~
,0,0,0,0,0,0,0,0,0,0)';
      PINUSE='POWER';
      NO_LOAD_CHECK='Both';
      NO_IO_CHECK='Both';
      NO_ASSERT_CHECK='TRUE';
      NO_DIR_CHECK='TRUE';
      ALLOW_CONNECT='TRUE';
    'VSS_P46':
      PIN_NUMBER='(0,0,0,0,0,0,0,0,0,0,0,0,0,0,0,0,0,0,0,0,0,0,0,0,0,0,0,0,P46,0~
,0,0,0,0,0,0,0,0,0,0)';
      PINUSE='POWER';
      NO_LOAD_CHECK='Both';
      NO_IO_CHECK='Both';
      NO_ASSERT_CHECK='TRUE';
      NO_DIR_CHECK='TRUE';
      ALLOW_CONNECT='TRUE';
    'VSS_P47':
      PIN_NUMBER='(0,0,0,0,0,0,0,0,0,0,0,0,0,0,0,0,0,0,0,0,0,0,0,0,0,0,0,0,P47,0~
,0,0,0,0,0,0,0,0,0,0)';
      PINUSE='POWER';
      NO_LOAD_CHECK='Both';
      NO_IO_CHECK='Both';
      NO_ASSERT_CHECK='TRUE';
      NO_DIR_CHECK='TRUE';
      ALLOW_CONNECT='TRUE';
    'VSS_P48':
      PIN_NUMBER='(0,0,0,0,0,0,0,0,0,0,0,0,0,0,0,0,0,0,0,0,0,0,0,0,0,0,0,0,P48,0~
,0,0,0,0,0,0,0,0,0,0)';
      PINUSE='POWER';
      NO_LOAD_CHECK='Both';
      NO_IO_CHECK='Both';
      NO_ASSERT_CHECK='TRUE';
      NO_DIR_CHECK='TRUE';
      ALLOW_CONNECT='TRUE';
    'VSS_P49':
      PIN_NUMBER='(0,0,0,0,0,0,0,0,0,0,0,0,0,0,0,0,0,0,0,0,0,0,0,0,0,0,0,0,P49,0~
,0,0,0,0,0,0,0,0,0,0)';
      PINUSE='POWER';
      NO_LOAD_CHECK='Both';
      NO_IO_CHECK='Both';
      NO_ASSERT_CHECK='TRUE';
      NO_DIR_CHECK='TRUE';
      ALLOW_CONNECT='TRUE';
    'VSS_P50':
      PIN_NUMBER='(0,0,0,0,0,0,0,0,0,0,0,0,0,0,0,0,0,0,0,0,0,0,0,0,0,0,0,0,P50,0~
,0,0,0,0,0,0,0,0,0,0)';
      PINUSE='POWER';
      NO_LOAD_CHECK='Both';
      NO_IO_CHECK='Both';
      NO_ASSERT_CHECK='TRUE';
      NO_DIR_CHECK='TRUE';
      ALLOW_CONNECT='TRUE';
    'VSS_P51':
      PIN_NUMBER='(0,0,0,0,0,0,0,0,0,0,0,0,0,0,0,0,0,0,0,0,0,0,0,0,0,0,0,0,P51,0~
,0,0,0,0,0,0,0,0,0,0)';
      PINUSE='POWER';
      NO_LOAD_CHECK='Both';
      NO_IO_CHECK='Both';
      NO_ASSERT_CHECK='TRUE';
      NO_DIR_CHECK='TRUE';
      ALLOW_CONNECT='TRUE';
    'VSS_P52':
      PIN_NUMBER='(0,0,0,0,0,0,0,0,0,0,0,0,0,0,0,0,0,0,0,0,0,0,0,0,0,0,0,0,P52,0~
,0,0,0,0,0,0,0,0,0,0)';
      PINUSE='POWER';
      NO_LOAD_CHECK='Both';
      NO_IO_CHECK='Both';
      NO_ASSERT_CHECK='TRUE';
      NO_DIR_CHECK='TRUE';
      ALLOW_CONNECT='TRUE';
    'VSS_P53':
      PIN_NUMBER='(0,0,0,0,0,0,0,0,0,0,0,0,0,0,0,0,0,0,0,0,0,0,0,0,0,0,0,0,P53,0~
,0,0,0,0,0,0,0,0,0,0)';
      PINUSE='POWER';
      NO_LOAD_CHECK='Both';
      NO_IO_CHECK='Both';
      NO_ASSERT_CHECK='TRUE';
      NO_DIR_CHECK='TRUE';
      ALLOW_CONNECT='TRUE';
    'VSS_P59':
      PIN_NUMBER='(0,0,0,0,0,0,0,0,0,0,0,0,0,0,0,0,0,0,0,0,0,0,0,0,0,0,0,0,P59,0~
,0,0,0,0,0,0,0,0,0,0)';
      PINUSE='POWER';
      NO_LOAD_CHECK='Both';
      NO_IO_CHECK='Both';
      NO_ASSERT_CHECK='TRUE';
      NO_DIR_CHECK='TRUE';
      ALLOW_CONNECT='TRUE';
    'VSS_P61':
      PIN_NUMBER='(0,0,0,0,0,0,0,0,0,0,0,0,0,0,0,0,0,0,0,0,0,0,0,0,0,0,0,0,P61,0~
,0,0,0,0,0,0,0,0,0,0)';
      PINUSE='POWER';
      NO_LOAD_CHECK='Both';
      NO_IO_CHECK='Both';
      NO_ASSERT_CHECK='TRUE';
      NO_DIR_CHECK='TRUE';
      ALLOW_CONNECT='TRUE';
    'VSS_P66':
      PIN_NUMBER='(0,0,0,0,0,0,0,0,0,0,0,0,0,0,0,0,0,0,0,0,0,0,0,0,0,0,0,0,P66,0~
,0,0,0,0,0,0,0,0,0,0)';
      PINUSE='POWER';
      NO_LOAD_CHECK='Both';
      NO_IO_CHECK='Both';
      NO_ASSERT_CHECK='TRUE';
      NO_DIR_CHECK='TRUE';
      ALLOW_CONNECT='TRUE';
    'VSS_P73':
      PIN_NUMBER='(0,0,0,0,0,0,0,0,0,0,0,0,0,0,0,0,0,0,0,0,0,0,0,0,0,0,0,0,P73,0~
,0,0,0,0,0,0,0,0,0,0)';
      PINUSE='POWER';
      NO_LOAD_CHECK='Both';
      NO_IO_CHECK='Both';
      NO_ASSERT_CHECK='TRUE';
      NO_DIR_CHECK='TRUE';
      ALLOW_CONNECT='TRUE';
    'VSS_R1':
      PIN_NUMBER='(0,0,0,0,0,0,0,0,0,0,0,0,0,0,0,0,0,0,0,0,0,0,0,0,0,0,0,0,R1,0,~
0,0,0,0,0,0,0,0,0,0)';
      PINUSE='POWER';
      NO_LOAD_CHECK='Both';
      NO_IO_CHECK='Both';
      NO_ASSERT_CHECK='TRUE';
      NO_DIR_CHECK='TRUE';
      ALLOW_CONNECT='TRUE';
    'VSS_R4':
      PIN_NUMBER='(0,0,0,0,0,0,0,0,0,0,0,0,0,0,0,0,0,0,0,0,0,0,0,0,0,0,0,0,R4,0,~
0,0,0,0,0,0,0,0,0,0)';
      PINUSE='POWER';
      NO_LOAD_CHECK='Both';
      NO_IO_CHECK='Both';
      NO_ASSERT_CHECK='TRUE';
      NO_DIR_CHECK='TRUE';
      ALLOW_CONNECT='TRUE';
    'VSS_R6':
      PIN_NUMBER='(0,0,0,0,0,0,0,0,0,0,0,0,0,0,0,0,0,0,0,0,0,0,0,0,0,0,0,0,R6,0,~
0,0,0,0,0,0,0,0,0,0)';
      PINUSE='POWER';
      NO_LOAD_CHECK='Both';
      NO_IO_CHECK='Both';
      NO_ASSERT_CHECK='TRUE';
      NO_DIR_CHECK='TRUE';
      ALLOW_CONNECT='TRUE';
    'VSS_R8':
      PIN_NUMBER='(0,0,0,0,0,0,0,0,0,0,0,0,0,0,0,0,0,0,0,0,0,0,0,0,0,0,0,0,R8,0,~
0,0,0,0,0,0,0,0,0,0)';
      PINUSE='POWER';
      NO_LOAD_CHECK='Both';
      NO_IO_CHECK='Both';
      NO_ASSERT_CHECK='TRUE';
      NO_DIR_CHECK='TRUE';
      ALLOW_CONNECT='TRUE';
    'VSS_R11':
      PIN_NUMBER='(0,0,0,0,0,0,0,0,0,0,0,0,0,0,0,0,0,0,0,0,0,0,0,0,0,0,0,0,R11,0~
,0,0,0,0,0,0,0,0,0,0)';
      PINUSE='POWER';
      NO_LOAD_CHECK='Both';
      NO_IO_CHECK='Both';
      NO_ASSERT_CHECK='TRUE';
      NO_DIR_CHECK='TRUE';
      ALLOW_CONNECT='TRUE';
    'VSS_R13':
      PIN_NUMBER='(0,0,0,0,0,0,0,0,0,0,0,0,0,0,0,0,0,0,0,0,0,0,0,0,0,0,0,0,R13,0~
,0,0,0,0,0,0,0,0,0,0)';
      PINUSE='POWER';
      NO_LOAD_CHECK='Both';
      NO_IO_CHECK='Both';
      NO_ASSERT_CHECK='TRUE';
      NO_DIR_CHECK='TRUE';
      ALLOW_CONNECT='TRUE';
    'VSS_R15':
      PIN_NUMBER='(0,0,0,0,0,0,0,0,0,0,0,0,0,0,0,0,0,0,0,0,0,0,0,0,0,0,0,0,R15,0~
,0,0,0,0,0,0,0,0,0,0)';
      PINUSE='POWER';
      NO_LOAD_CHECK='Both';
      NO_IO_CHECK='Both';
      NO_ASSERT_CHECK='TRUE';
      NO_DIR_CHECK='TRUE';
      ALLOW_CONNECT='TRUE';
    'VSS_R18':
      PIN_NUMBER='(0,0,0,0,0,0,0,0,0,0,0,0,0,0,0,0,0,0,0,0,0,0,0,0,0,0,0,0,R18,0~
,0,0,0,0,0,0,0,0,0,0)';
      PINUSE='POWER';
      NO_LOAD_CHECK='Both';
      NO_IO_CHECK='Both';
      NO_ASSERT_CHECK='TRUE';
      NO_DIR_CHECK='TRUE';
      ALLOW_CONNECT='TRUE';
    'VSS_R20':
      PIN_NUMBER='(0,0,0,0,0,0,0,0,0,0,0,0,0,0,0,0,0,0,0,0,0,0,0,0,0,0,0,0,R20,0~
,0,0,0,0,0,0,0,0,0,0)';
      PINUSE='POWER';
      NO_LOAD_CHECK='Both';
      NO_IO_CHECK='Both';
      NO_ASSERT_CHECK='TRUE';
      NO_DIR_CHECK='TRUE';
      ALLOW_CONNECT='TRUE';
    'VSS_R22':
      PIN_NUMBER='(0,0,0,0,0,0,0,0,0,0,0,0,0,0,0,0,0,0,0,0,0,0,0,0,0,0,0,0,R22,0~
,0,0,0,0,0,0,0,0,0,0)';
      PINUSE='POWER';
      NO_LOAD_CHECK='Both';
      NO_IO_CHECK='Both';
      NO_ASSERT_CHECK='TRUE';
      NO_DIR_CHECK='TRUE';
      ALLOW_CONNECT='TRUE';
    'VSS_R25':
      PIN_NUMBER='(0,0,0,0,0,0,0,0,0,0,0,0,0,0,0,0,0,0,0,0,0,0,0,0,0,0,0,0,R25,0~
,0,0,0,0,0,0,0,0,0,0)';
      PINUSE='POWER';
      NO_LOAD_CHECK='Both';
      NO_IO_CHECK='Both';
      NO_ASSERT_CHECK='TRUE';
      NO_DIR_CHECK='TRUE';
      ALLOW_CONNECT='TRUE';
    'VSS_R28':
      PIN_NUMBER='(0,0,0,0,0,0,0,0,0,0,0,0,0,0,0,0,0,0,0,0,0,0,0,0,0,0,0,0,R28,0~
,0,0,0,0,0,0,0,0,0,0)';
      PINUSE='POWER';
      NO_LOAD_CHECK='Both';
      NO_IO_CHECK='Both';
      NO_ASSERT_CHECK='TRUE';
      NO_DIR_CHECK='TRUE';
      ALLOW_CONNECT='TRUE';
    'VSS_R31':
      PIN_NUMBER='(0,0,0,0,0,0,0,0,0,0,0,0,0,0,0,0,0,0,0,0,0,0,0,0,0,0,0,0,R31,0~
,0,0,0,0,0,0,0,0,0,0)';
      PINUSE='POWER';
      NO_LOAD_CHECK='Both';
      NO_IO_CHECK='Both';
      NO_ASSERT_CHECK='TRUE';
      NO_DIR_CHECK='TRUE';
      ALLOW_CONNECT='TRUE';
    'VSS_R34':
      PIN_NUMBER='(0,0,0,0,0,0,0,0,0,0,0,0,0,0,0,0,0,0,0,0,0,0,0,0,0,0,0,0,R34,0~
,0,0,0,0,0,0,0,0,0,0)';
      PINUSE='POWER';
      NO_LOAD_CHECK='Both';
      NO_IO_CHECK='Both';
      NO_ASSERT_CHECK='TRUE';
      NO_DIR_CHECK='TRUE';
      ALLOW_CONNECT='TRUE';
    'VSS_R35':
      PIN_NUMBER='(0,0,0,0,0,0,0,0,0,0,0,0,0,0,0,0,0,0,0,0,0,0,0,0,0,0,0,0,R35,0~
,0,0,0,0,0,0,0,0,0,0)';
      PINUSE='POWER';
      NO_LOAD_CHECK='Both';
      NO_IO_CHECK='Both';
      NO_ASSERT_CHECK='TRUE';
      NO_DIR_CHECK='TRUE';
      ALLOW_CONNECT='TRUE';
    'VSS_R36':
      PIN_NUMBER='(0,0,0,0,0,0,0,0,0,0,0,0,0,0,0,0,0,0,0,0,0,0,0,0,0,0,0,0,R36,0~
,0,0,0,0,0,0,0,0,0,0)';
      PINUSE='POWER';
      NO_LOAD_CHECK='Both';
      NO_IO_CHECK='Both';
      NO_ASSERT_CHECK='TRUE';
      NO_DIR_CHECK='TRUE';
      ALLOW_CONNECT='TRUE';
    'VSS_R40':
      PIN_NUMBER='(0,0,0,0,0,0,0,0,0,0,0,0,0,0,0,0,0,0,0,0,0,0,0,0,0,0,0,0,R40,0~
,0,0,0,0,0,0,0,0,0,0)';
      PINUSE='POWER';
      NO_LOAD_CHECK='Both';
      NO_IO_CHECK='Both';
      NO_ASSERT_CHECK='TRUE';
      NO_DIR_CHECK='TRUE';
      ALLOW_CONNECT='TRUE';
    'VSS_R41':
      PIN_NUMBER='(0,0,0,0,0,0,0,0,0,0,0,0,0,0,0,0,0,0,0,0,0,0,0,0,0,0,0,0,R41,0~
,0,0,0,0,0,0,0,0,0,0)';
      PINUSE='POWER';
      NO_LOAD_CHECK='Both';
      NO_IO_CHECK='Both';
      NO_ASSERT_CHECK='TRUE';
      NO_DIR_CHECK='TRUE';
      ALLOW_CONNECT='TRUE';
    'VSS_R42':
      PIN_NUMBER='(0,0,0,0,0,0,0,0,0,0,0,0,0,0,0,0,0,0,0,0,0,0,0,0,0,0,0,0,R42,0~
,0,0,0,0,0,0,0,0,0,0)';
      PINUSE='POWER';
      NO_LOAD_CHECK='Both';
      NO_IO_CHECK='Both';
      NO_ASSERT_CHECK='TRUE';
      NO_DIR_CHECK='TRUE';
      ALLOW_CONNECT='TRUE';
    'VSS_R45':
      PIN_NUMBER='(0,0,0,0,0,0,0,0,0,0,0,0,0,0,0,0,0,0,0,0,0,0,0,0,0,0,0,0,R45,0~
,0,0,0,0,0,0,0,0,0,0)';
      PINUSE='POWER';
      NO_LOAD_CHECK='Both';
      NO_IO_CHECK='Both';
      NO_ASSERT_CHECK='TRUE';
      NO_DIR_CHECK='TRUE';
      ALLOW_CONNECT='TRUE';
    'VSS_AB68':
      PIN_NUMBER='(0,0,0,0,0,0,0,0,0,0,0,0,0,0,0,0,0,0,0,0,0,0,0,0,0,0,0,0,0,AB6~
8,0,0,0,0,0,0,0,0,0,0)';
      PINUSE='POWER';
      NO_LOAD_CHECK='Both';
      NO_IO_CHECK='Both';
      NO_ASSERT_CHECK='TRUE';
      NO_DIR_CHECK='TRUE';
      ALLOW_CONNECT='TRUE';
    'VSS_AB71':
      PIN_NUMBER='(0,0,0,0,0,0,0,0,0,0,0,0,0,0,0,0,0,0,0,0,0,0,0,0,0,0,0,0,0,AB7~
1,0,0,0,0,0,0,0,0,0,0)';
      PINUSE='POWER';
      NO_LOAD_CHECK='Both';
      NO_IO_CHECK='Both';
      NO_ASSERT_CHECK='TRUE';
      NO_DIR_CHECK='TRUE';
      ALLOW_CONNECT='TRUE';
    'VSS_AB73':
      PIN_NUMBER='(0,0,0,0,0,0,0,0,0,0,0,0,0,0,0,0,0,0,0,0,0,0,0,0,0,0,0,0,0,AB7~
3,0,0,0,0,0,0,0,0,0,0)';
      PINUSE='POWER';
      NO_LOAD_CHECK='Both';
      NO_IO_CHECK='Both';
      NO_ASSERT_CHECK='TRUE';
      NO_DIR_CHECK='TRUE';
      ALLOW_CONNECT='TRUE';
    'VSS_AC1':
      PIN_NUMBER='(0,0,0,0,0,0,0,0,0,0,0,0,0,0,0,0,0,0,0,0,0,0,0,0,0,0,0,0,0,AC1~
,0,0,0,0,0,0,0,0,0,0)';
      PINUSE='POWER';
      NO_LOAD_CHECK='Both';
      NO_IO_CHECK='Both';
      NO_ASSERT_CHECK='TRUE';
      NO_DIR_CHECK='TRUE';
      ALLOW_CONNECT='TRUE';
    'VSS_AC6':
      PIN_NUMBER='(0,0,0,0,0,0,0,0,0,0,0,0,0,0,0,0,0,0,0,0,0,0,0,0,0,0,0,0,0,AC6~
,0,0,0,0,0,0,0,0,0,0)';
      PINUSE='POWER';
      NO_LOAD_CHECK='Both';
      NO_IO_CHECK='Both';
      NO_ASSERT_CHECK='TRUE';
      NO_DIR_CHECK='TRUE';
      ALLOW_CONNECT='TRUE';
    'VSS_AC8':
      PIN_NUMBER='(0,0,0,0,0,0,0,0,0,0,0,0,0,0,0,0,0,0,0,0,0,0,0,0,0,0,0,0,0,AC8~
,0,0,0,0,0,0,0,0,0,0)';
      PINUSE='POWER';
      NO_LOAD_CHECK='Both';
      NO_IO_CHECK='Both';
      NO_ASSERT_CHECK='TRUE';
      NO_DIR_CHECK='TRUE';
      ALLOW_CONNECT='TRUE';
    'VSS_AC13':
      PIN_NUMBER='(0,0,0,0,0,0,0,0,0,0,0,0,0,0,0,0,0,0,0,0,0,0,0,0,0,0,0,0,0,AC1~
3,0,0,0,0,0,0,0,0,0,0)';
      PINUSE='POWER';
      NO_LOAD_CHECK='Both';
      NO_IO_CHECK='Both';
      NO_ASSERT_CHECK='TRUE';
      NO_DIR_CHECK='TRUE';
      ALLOW_CONNECT='TRUE';
    'VSS_AC15':
      PIN_NUMBER='(0,0,0,0,0,0,0,0,0,0,0,0,0,0,0,0,0,0,0,0,0,0,0,0,0,0,0,0,0,AC1~
5,0,0,0,0,0,0,0,0,0,0)';
      PINUSE='POWER';
      NO_LOAD_CHECK='Both';
      NO_IO_CHECK='Both';
      NO_ASSERT_CHECK='TRUE';
      NO_DIR_CHECK='TRUE';
      ALLOW_CONNECT='TRUE';
    'VSS_AC20':
      PIN_NUMBER='(0,0,0,0,0,0,0,0,0,0,0,0,0,0,0,0,0,0,0,0,0,0,0,0,0,0,0,0,0,AC2~
0,0,0,0,0,0,0,0,0,0,0)';
      PINUSE='POWER';
      NO_LOAD_CHECK='Both';
      NO_IO_CHECK='Both';
      NO_ASSERT_CHECK='TRUE';
      NO_DIR_CHECK='TRUE';
      ALLOW_CONNECT='TRUE';
    'VSS_AC22':
      PIN_NUMBER='(0,0,0,0,0,0,0,0,0,0,0,0,0,0,0,0,0,0,0,0,0,0,0,0,0,0,0,0,0,AC2~
2,0,0,0,0,0,0,0,0,0,0)';
      PINUSE='POWER';
      NO_LOAD_CHECK='Both';
      NO_IO_CHECK='Both';
      NO_ASSERT_CHECK='TRUE';
      NO_DIR_CHECK='TRUE';
      ALLOW_CONNECT='TRUE';
    'VSS_AC25':
      PIN_NUMBER='(0,0,0,0,0,0,0,0,0,0,0,0,0,0,0,0,0,0,0,0,0,0,0,0,0,0,0,0,0,AC2~
5,0,0,0,0,0,0,0,0,0,0)';
      PINUSE='POWER';
      NO_LOAD_CHECK='Both';
      NO_IO_CHECK='Both';
      NO_ASSERT_CHECK='TRUE';
      NO_DIR_CHECK='TRUE';
      ALLOW_CONNECT='TRUE';
    'VSS_AC28':
      PIN_NUMBER='(0,0,0,0,0,0,0,0,0,0,0,0,0,0,0,0,0,0,0,0,0,0,0,0,0,0,0,0,0,AC2~
8,0,0,0,0,0,0,0,0,0,0)';
      PINUSE='POWER';
      NO_LOAD_CHECK='Both';
      NO_IO_CHECK='Both';
      NO_ASSERT_CHECK='TRUE';
      NO_DIR_CHECK='TRUE';
      ALLOW_CONNECT='TRUE';
    'VSS_AC31':
      PIN_NUMBER='(0,0,0,0,0,0,0,0,0,0,0,0,0,0,0,0,0,0,0,0,0,0,0,0,0,0,0,0,0,AC3~
1,0,0,0,0,0,0,0,0,0,0)';
      PINUSE='POWER';
      NO_LOAD_CHECK='Both';
      NO_IO_CHECK='Both';
      NO_ASSERT_CHECK='TRUE';
      NO_DIR_CHECK='TRUE';
      ALLOW_CONNECT='TRUE';
    'VSS_AC34':
      PIN_NUMBER='(0,0,0,0,0,0,0,0,0,0,0,0,0,0,0,0,0,0,0,0,0,0,0,0,0,0,0,0,0,AC3~
4,0,0,0,0,0,0,0,0,0,0)';
      PINUSE='POWER';
      NO_LOAD_CHECK='Both';
      NO_IO_CHECK='Both';
      NO_ASSERT_CHECK='TRUE';
      NO_DIR_CHECK='TRUE';
      ALLOW_CONNECT='TRUE';
    'VSS_AC42':
      PIN_NUMBER='(0,0,0,0,0,0,0,0,0,0,0,0,0,0,0,0,0,0,0,0,0,0,0,0,0,0,0,0,0,AC4~
2,0,0,0,0,0,0,0,0,0,0)';
      PINUSE='POWER';
      NO_LOAD_CHECK='Both';
      NO_IO_CHECK='Both';
      NO_ASSERT_CHECK='TRUE';
      NO_DIR_CHECK='TRUE';
      ALLOW_CONNECT='TRUE';
    'VSS_AC45':
      PIN_NUMBER='(0,0,0,0,0,0,0,0,0,0,0,0,0,0,0,0,0,0,0,0,0,0,0,0,0,0,0,0,0,AC4~
5,0,0,0,0,0,0,0,0,0,0)';
      PINUSE='POWER';
      NO_LOAD_CHECK='Both';
      NO_IO_CHECK='Both';
      NO_ASSERT_CHECK='TRUE';
      NO_DIR_CHECK='TRUE';
      ALLOW_CONNECT='TRUE';
    'VSS_AC48':
      PIN_NUMBER='(0,0,0,0,0,0,0,0,0,0,0,0,0,0,0,0,0,0,0,0,0,0,0,0,0,0,0,0,0,AC4~
8,0,0,0,0,0,0,0,0,0,0)';
      PINUSE='POWER';
      NO_LOAD_CHECK='Both';
      NO_IO_CHECK='Both';
      NO_ASSERT_CHECK='TRUE';
      NO_DIR_CHECK='TRUE';
      ALLOW_CONNECT='TRUE';
    'VSS_AC51':
      PIN_NUMBER='(0,0,0,0,0,0,0,0,0,0,0,0,0,0,0,0,0,0,0,0,0,0,0,0,0,0,0,0,0,AC5~
1,0,0,0,0,0,0,0,0,0,0)';
      PINUSE='POWER';
      NO_LOAD_CHECK='Both';
      NO_IO_CHECK='Both';
      NO_ASSERT_CHECK='TRUE';
      NO_DIR_CHECK='TRUE';
      ALLOW_CONNECT='TRUE';
    'VSS_AC54':
      PIN_NUMBER='(0,0,0,0,0,0,0,0,0,0,0,0,0,0,0,0,0,0,0,0,0,0,0,0,0,0,0,0,0,AC5~
4,0,0,0,0,0,0,0,0,0,0)';
      PINUSE='POWER';
      NO_LOAD_CHECK='Both';
      NO_IO_CHECK='Both';
      NO_ASSERT_CHECK='TRUE';
      NO_DIR_CHECK='TRUE';
      ALLOW_CONNECT='TRUE';
    'VSS_AC56':
      PIN_NUMBER='(0,0,0,0,0,0,0,0,0,0,0,0,0,0,0,0,0,0,0,0,0,0,0,0,0,0,0,0,0,AC5~
6,0,0,0,0,0,0,0,0,0,0)';
      PINUSE='POWER';
      NO_LOAD_CHECK='Both';
      NO_IO_CHECK='Both';
      NO_ASSERT_CHECK='TRUE';
      NO_DIR_CHECK='TRUE';
      ALLOW_CONNECT='TRUE';
    'VSS_AC61':
      PIN_NUMBER='(0,0,0,0,0,0,0,0,0,0,0,0,0,0,0,0,0,0,0,0,0,0,0,0,0,0,0,0,0,AC6~
1,0,0,0,0,0,0,0,0,0,0)';
      PINUSE='POWER';
      NO_LOAD_CHECK='Both';
      NO_IO_CHECK='Both';
      NO_ASSERT_CHECK='TRUE';
      NO_DIR_CHECK='TRUE';
      ALLOW_CONNECT='TRUE';
    'VSS_AC63':
      PIN_NUMBER='(0,0,0,0,0,0,0,0,0,0,0,0,0,0,0,0,0,0,0,0,0,0,0,0,0,0,0,0,0,AC6~
3,0,0,0,0,0,0,0,0,0,0)';
      PINUSE='POWER';
      NO_LOAD_CHECK='Both';
      NO_IO_CHECK='Both';
      NO_ASSERT_CHECK='TRUE';
      NO_DIR_CHECK='TRUE';
      ALLOW_CONNECT='TRUE';
    'VSS_AC68':
      PIN_NUMBER='(0,0,0,0,0,0,0,0,0,0,0,0,0,0,0,0,0,0,0,0,0,0,0,0,0,0,0,0,0,AC6~
8,0,0,0,0,0,0,0,0,0,0)';
      PINUSE='POWER';
      NO_LOAD_CHECK='Both';
      NO_IO_CHECK='Both';
      NO_ASSERT_CHECK='TRUE';
      NO_DIR_CHECK='TRUE';
      ALLOW_CONNECT='TRUE';
    'VSS_AC70':
      PIN_NUMBER='(0,0,0,0,0,0,0,0,0,0,0,0,0,0,0,0,0,0,0,0,0,0,0,0,0,0,0,0,0,AC7~
0,0,0,0,0,0,0,0,0,0,0)';
      PINUSE='POWER';
      NO_LOAD_CHECK='Both';
      NO_IO_CHECK='Both';
      NO_ASSERT_CHECK='TRUE';
      NO_DIR_CHECK='TRUE';
      ALLOW_CONNECT='TRUE';
    'VSS_AC75':
      PIN_NUMBER='(0,0,0,0,0,0,0,0,0,0,0,0,0,0,0,0,0,0,0,0,0,0,0,0,0,0,0,0,0,AC7~
5,0,0,0,0,0,0,0,0,0,0)';
      PINUSE='POWER';
      NO_LOAD_CHECK='Both';
      NO_IO_CHECK='Both';
      NO_ASSERT_CHECK='TRUE';
      NO_DIR_CHECK='TRUE';
      ALLOW_CONNECT='TRUE';
    'VSS_AD3':
      PIN_NUMBER='(0,0,0,0,0,0,0,0,0,0,0,0,0,0,0,0,0,0,0,0,0,0,0,0,0,0,0,0,0,AD3~
,0,0,0,0,0,0,0,0,0,0)';
      PINUSE='POWER';
      NO_LOAD_CHECK='Both';
      NO_IO_CHECK='Both';
      NO_ASSERT_CHECK='TRUE';
      NO_DIR_CHECK='TRUE';
      ALLOW_CONNECT='TRUE';
    'VSS_AD5':
      PIN_NUMBER='(0,0,0,0,0,0,0,0,0,0,0,0,0,0,0,0,0,0,0,0,0,0,0,0,0,0,0,0,0,AD5~
,0,0,0,0,0,0,0,0,0,0)';
      PINUSE='POWER';
      NO_LOAD_CHECK='Both';
      NO_IO_CHECK='Both';
      NO_ASSERT_CHECK='TRUE';
      NO_DIR_CHECK='TRUE';
      ALLOW_CONNECT='TRUE';
    'VSS_AD8':
      PIN_NUMBER='(0,0,0,0,0,0,0,0,0,0,0,0,0,0,0,0,0,0,0,0,0,0,0,0,0,0,0,0,0,AD8~
,0,0,0,0,0,0,0,0,0,0)';
      PINUSE='POWER';
      NO_LOAD_CHECK='Both';
      NO_IO_CHECK='Both';
      NO_ASSERT_CHECK='TRUE';
      NO_DIR_CHECK='TRUE';
      ALLOW_CONNECT='TRUE';
    'VSS_AD10':
      PIN_NUMBER='(0,0,0,0,0,0,0,0,0,0,0,0,0,0,0,0,0,0,0,0,0,0,0,0,0,0,0,0,0,AD1~
0,0,0,0,0,0,0,0,0,0,0)';
      PINUSE='POWER';
      NO_LOAD_CHECK='Both';
      NO_IO_CHECK='Both';
      NO_ASSERT_CHECK='TRUE';
      NO_DIR_CHECK='TRUE';
      ALLOW_CONNECT='TRUE';
    'VSS_AD12':
      PIN_NUMBER='(0,0,0,0,0,0,0,0,0,0,0,0,0,0,0,0,0,0,0,0,0,0,0,0,0,0,0,0,0,AD1~
2,0,0,0,0,0,0,0,0,0,0)';
      PINUSE='POWER';
      NO_LOAD_CHECK='Both';
      NO_IO_CHECK='Both';
      NO_ASSERT_CHECK='TRUE';
      NO_DIR_CHECK='TRUE';
      ALLOW_CONNECT='TRUE';
    'VSS_AD15':
      PIN_NUMBER='(0,0,0,0,0,0,0,0,0,0,0,0,0,0,0,0,0,0,0,0,0,0,0,0,0,0,0,0,0,AD1~
5,0,0,0,0,0,0,0,0,0,0)';
      PINUSE='POWER';
      NO_LOAD_CHECK='Both';
      NO_IO_CHECK='Both';
      NO_ASSERT_CHECK='TRUE';
      NO_DIR_CHECK='TRUE';
      ALLOW_CONNECT='TRUE';
    'VSS_AD17':
      PIN_NUMBER='(0,0,0,0,0,0,0,0,0,0,0,0,0,0,0,0,0,0,0,0,0,0,0,0,0,0,0,0,0,AD1~
7,0,0,0,0,0,0,0,0,0,0)';
      PINUSE='POWER';
      NO_LOAD_CHECK='Both';
      NO_IO_CHECK='Both';
      NO_ASSERT_CHECK='TRUE';
      NO_DIR_CHECK='TRUE';
      ALLOW_CONNECT='TRUE';
    'VSS_AD19':
      PIN_NUMBER='(0,0,0,0,0,0,0,0,0,0,0,0,0,0,0,0,0,0,0,0,0,0,0,0,0,0,0,0,0,AD1~
9,0,0,0,0,0,0,0,0,0,0)';
      PINUSE='POWER';
      NO_LOAD_CHECK='Both';
      NO_IO_CHECK='Both';
      NO_ASSERT_CHECK='TRUE';
      NO_DIR_CHECK='TRUE';
      ALLOW_CONNECT='TRUE';
    'VSS_AD23':
      PIN_NUMBER='(0,0,0,0,0,0,0,0,0,0,0,0,0,0,0,0,0,0,0,0,0,0,0,0,0,0,0,0,0,AD2~
3,0,0,0,0,0,0,0,0,0,0)';
      PINUSE='POWER';
      NO_LOAD_CHECK='Both';
      NO_IO_CHECK='Both';
      NO_ASSERT_CHECK='TRUE';
      NO_DIR_CHECK='TRUE';
      ALLOW_CONNECT='TRUE';
    'VSS_AD24':
      PIN_NUMBER='(0,0,0,0,0,0,0,0,0,0,0,0,0,0,0,0,0,0,0,0,0,0,0,0,0,0,0,0,0,AD2~
4,0,0,0,0,0,0,0,0,0,0)';
      PINUSE='POWER';
      NO_LOAD_CHECK='Both';
      NO_IO_CHECK='Both';
      NO_ASSERT_CHECK='TRUE';
      NO_DIR_CHECK='TRUE';
      ALLOW_CONNECT='TRUE';
    'VSS_AD25':
      PIN_NUMBER='(0,0,0,0,0,0,0,0,0,0,0,0,0,0,0,0,0,0,0,0,0,0,0,0,0,0,0,0,0,AD2~
5,0,0,0,0,0,0,0,0,0,0)';
      PINUSE='POWER';
      NO_LOAD_CHECK='Both';
      NO_IO_CHECK='Both';
      NO_ASSERT_CHECK='TRUE';
      NO_DIR_CHECK='TRUE';
      ALLOW_CONNECT='TRUE';
    'VSS_AD26':
      PIN_NUMBER='(0,0,0,0,0,0,0,0,0,0,0,0,0,0,0,0,0,0,0,0,0,0,0,0,0,0,0,0,0,AD2~
6,0,0,0,0,0,0,0,0,0,0)';
      PINUSE='POWER';
      NO_LOAD_CHECK='Both';
      NO_IO_CHECK='Both';
      NO_ASSERT_CHECK='TRUE';
      NO_DIR_CHECK='TRUE';
      ALLOW_CONNECT='TRUE';
    'VSS_AD27':
      PIN_NUMBER='(0,0,0,0,0,0,0,0,0,0,0,0,0,0,0,0,0,0,0,0,0,0,0,0,0,0,0,0,0,AD2~
7,0,0,0,0,0,0,0,0,0,0)';
      PINUSE='POWER';
      NO_LOAD_CHECK='Both';
      NO_IO_CHECK='Both';
      NO_ASSERT_CHECK='TRUE';
      NO_DIR_CHECK='TRUE';
      ALLOW_CONNECT='TRUE';
    'VSS_AD28':
      PIN_NUMBER='(0,0,0,0,0,0,0,0,0,0,0,0,0,0,0,0,0,0,0,0,0,0,0,0,0,0,0,0,0,AD2~
8,0,0,0,0,0,0,0,0,0,0)';
      PINUSE='POWER';
      NO_LOAD_CHECK='Both';
      NO_IO_CHECK='Both';
      NO_ASSERT_CHECK='TRUE';
      NO_DIR_CHECK='TRUE';
      ALLOW_CONNECT='TRUE';
    'VSS_AD29':
      PIN_NUMBER='(0,0,0,0,0,0,0,0,0,0,0,0,0,0,0,0,0,0,0,0,0,0,0,0,0,0,0,0,0,AD2~
9,0,0,0,0,0,0,0,0,0,0)';
      PINUSE='POWER';
      NO_LOAD_CHECK='Both';
      NO_IO_CHECK='Both';
      NO_ASSERT_CHECK='TRUE';
      NO_DIR_CHECK='TRUE';
      ALLOW_CONNECT='TRUE';
    'VSS_AD30':
      PIN_NUMBER='(0,0,0,0,0,0,0,0,0,0,0,0,0,0,0,0,0,0,0,0,0,0,0,0,0,0,0,0,0,AD3~
0,0,0,0,0,0,0,0,0,0,0)';
      PINUSE='POWER';
      NO_LOAD_CHECK='Both';
      NO_IO_CHECK='Both';
      NO_ASSERT_CHECK='TRUE';
      NO_DIR_CHECK='TRUE';
      ALLOW_CONNECT='TRUE';
    'VSS_AD32':
      PIN_NUMBER='(0,0,0,0,0,0,0,0,0,0,0,0,0,0,0,0,0,0,0,0,0,0,0,0,0,0,0,0,0,AD3~
2,0,0,0,0,0,0,0,0,0,0)';
      PINUSE='POWER';
      NO_LOAD_CHECK='Both';
      NO_IO_CHECK='Both';
      NO_ASSERT_CHECK='TRUE';
      NO_DIR_CHECK='TRUE';
      ALLOW_CONNECT='TRUE';
    'VSS_AD33':
      PIN_NUMBER='(0,0,0,0,0,0,0,0,0,0,0,0,0,0,0,0,0,0,0,0,0,0,0,0,0,0,0,0,0,AD3~
3,0,0,0,0,0,0,0,0,0,0)';
      PINUSE='POWER';
      NO_LOAD_CHECK='Both';
      NO_IO_CHECK='Both';
      NO_ASSERT_CHECK='TRUE';
      NO_DIR_CHECK='TRUE';
      ALLOW_CONNECT='TRUE';
    'VSS_AD34':
      PIN_NUMBER='(0,0,0,0,0,0,0,0,0,0,0,0,0,0,0,0,0,0,0,0,0,0,0,0,0,0,0,0,0,AD3~
4,0,0,0,0,0,0,0,0,0,0)';
      PINUSE='POWER';
      NO_LOAD_CHECK='Both';
      NO_IO_CHECK='Both';
      NO_ASSERT_CHECK='TRUE';
      NO_DIR_CHECK='TRUE';
      ALLOW_CONNECT='TRUE';
    'VSS_AD37':
      PIN_NUMBER='(0,0,0,0,0,0,0,0,0,0,0,0,0,0,0,0,0,0,0,0,0,0,0,0,0,0,0,0,0,AD3~
7,0,0,0,0,0,0,0,0,0,0)';
      PINUSE='POWER';
      NO_LOAD_CHECK='Both';
      NO_IO_CHECK='Both';
      NO_ASSERT_CHECK='TRUE';
      NO_DIR_CHECK='TRUE';
      ALLOW_CONNECT='TRUE';
    'VSS_AD39':
      PIN_NUMBER='(0,0,0,0,0,0,0,0,0,0,0,0,0,0,0,0,0,0,0,0,0,0,0,0,0,0,0,0,0,AD3~
9,0,0,0,0,0,0,0,0,0,0)';
      PINUSE='POWER';
      NO_LOAD_CHECK='Both';
      NO_IO_CHECK='Both';
      NO_ASSERT_CHECK='TRUE';
      NO_DIR_CHECK='TRUE';
      ALLOW_CONNECT='TRUE';
    'VSS_AD42':
      PIN_NUMBER='(0,0,0,0,0,0,0,0,0,0,0,0,0,0,0,0,0,0,0,0,0,0,0,0,0,0,0,0,0,AD4~
2,0,0,0,0,0,0,0,0,0,0)';
      PINUSE='POWER';
      NO_LOAD_CHECK='Both';
      NO_IO_CHECK='Both';
      NO_ASSERT_CHECK='TRUE';
      NO_DIR_CHECK='TRUE';
      ALLOW_CONNECT='TRUE';
    'VSS_AD43':
      PIN_NUMBER='(0,0,0,0,0,0,0,0,0,0,0,0,0,0,0,0,0,0,0,0,0,0,0,0,0,0,0,0,0,AD4~
3,0,0,0,0,0,0,0,0,0,0)';
      PINUSE='POWER';
      NO_LOAD_CHECK='Both';
      NO_IO_CHECK='Both';
      NO_ASSERT_CHECK='TRUE';
      NO_DIR_CHECK='TRUE';
      ALLOW_CONNECT='TRUE';
    'VSS_AD44':
      PIN_NUMBER='(0,0,0,0,0,0,0,0,0,0,0,0,0,0,0,0,0,0,0,0,0,0,0,0,0,0,0,0,0,AD4~
4,0,0,0,0,0,0,0,0,0,0)';
      PINUSE='POWER';
      NO_LOAD_CHECK='Both';
      NO_IO_CHECK='Both';
      NO_ASSERT_CHECK='TRUE';
      NO_DIR_CHECK='TRUE';
      ALLOW_CONNECT='TRUE';
    'VSS_AD45':
      PIN_NUMBER='(0,0,0,0,0,0,0,0,0,0,0,0,0,0,0,0,0,0,0,0,0,0,0,0,0,0,0,0,0,AD4~
5,0,0,0,0,0,0,0,0,0,0)';
      PINUSE='POWER';
      NO_LOAD_CHECK='Both';
      NO_IO_CHECK='Both';
      NO_ASSERT_CHECK='TRUE';
      NO_DIR_CHECK='TRUE';
      ALLOW_CONNECT='TRUE';
    'VSS_AD46':
      PIN_NUMBER='(0,0,0,0,0,0,0,0,0,0,0,0,0,0,0,0,0,0,0,0,0,0,0,0,0,0,0,0,0,AD4~
6,0,0,0,0,0,0,0,0,0,0)';
      PINUSE='POWER';
      NO_LOAD_CHECK='Both';
      NO_IO_CHECK='Both';
      NO_ASSERT_CHECK='TRUE';
      NO_DIR_CHECK='TRUE';
      ALLOW_CONNECT='TRUE';
    'VSS_AD47':
      PIN_NUMBER='(0,0,0,0,0,0,0,0,0,0,0,0,0,0,0,0,0,0,0,0,0,0,0,0,0,0,0,0,0,AD4~
7,0,0,0,0,0,0,0,0,0,0)';
      PINUSE='POWER';
      NO_LOAD_CHECK='Both';
      NO_IO_CHECK='Both';
      NO_ASSERT_CHECK='TRUE';
      NO_DIR_CHECK='TRUE';
      ALLOW_CONNECT='TRUE';
    'VSS_AD48':
      PIN_NUMBER='(0,0,0,0,0,0,0,0,0,0,0,0,0,0,0,0,0,0,0,0,0,0,0,0,0,0,0,0,0,AD4~
8,0,0,0,0,0,0,0,0,0,0)';
      PINUSE='POWER';
      NO_LOAD_CHECK='Both';
      NO_IO_CHECK='Both';
      NO_ASSERT_CHECK='TRUE';
      NO_DIR_CHECK='TRUE';
      ALLOW_CONNECT='TRUE';
    'VSS_T66':
      PIN_NUMBER='(0,0,0,0,0,0,0,0,0,0,0,0,0,0,0,0,0,0,0,0,0,0,0,0,0,0,0,0,0,T66~
,0,0,0,0,0,0,0,0,0,0)';
      PINUSE='POWER';
      NO_LOAD_CHECK='Both';
      NO_IO_CHECK='Both';
      NO_ASSERT_CHECK='TRUE';
      NO_DIR_CHECK='TRUE';
      ALLOW_CONNECT='TRUE';
    'VSS_T68':
      PIN_NUMBER='(0,0,0,0,0,0,0,0,0,0,0,0,0,0,0,0,0,0,0,0,0,0,0,0,0,0,0,0,0,T68~
,0,0,0,0,0,0,0,0,0,0)';
      PINUSE='POWER';
      NO_LOAD_CHECK='Both';
      NO_IO_CHECK='Both';
      NO_ASSERT_CHECK='TRUE';
      NO_DIR_CHECK='TRUE';
      ALLOW_CONNECT='TRUE';
    'VSS_T71':
      PIN_NUMBER='(0,0,0,0,0,0,0,0,0,0,0,0,0,0,0,0,0,0,0,0,0,0,0,0,0,0,0,0,0,T71~
,0,0,0,0,0,0,0,0,0,0)';
      PINUSE='POWER';
      NO_LOAD_CHECK='Both';
      NO_IO_CHECK='Both';
      NO_ASSERT_CHECK='TRUE';
      NO_DIR_CHECK='TRUE';
      ALLOW_CONNECT='TRUE';
    'VSS_T73':
      PIN_NUMBER='(0,0,0,0,0,0,0,0,0,0,0,0,0,0,0,0,0,0,0,0,0,0,0,0,0,0,0,0,0,T73~
,0,0,0,0,0,0,0,0,0,0)';
      PINUSE='POWER';
      NO_LOAD_CHECK='Both';
      NO_IO_CHECK='Both';
      NO_ASSERT_CHECK='TRUE';
      NO_DIR_CHECK='TRUE';
      ALLOW_CONNECT='TRUE';
    'VSS_U1':
      PIN_NUMBER='(0,0,0,0,0,0,0,0,0,0,0,0,0,0,0,0,0,0,0,0,0,0,0,0,0,0,0,0,0,U1,~
0,0,0,0,0,0,0,0,0,0)';
      PINUSE='POWER';
      NO_LOAD_CHECK='Both';
      NO_IO_CHECK='Both';
      NO_ASSERT_CHECK='TRUE';
      NO_DIR_CHECK='TRUE';
      ALLOW_CONNECT='TRUE';
    'VSS_U6':
      PIN_NUMBER='(0,0,0,0,0,0,0,0,0,0,0,0,0,0,0,0,0,0,0,0,0,0,0,0,0,0,0,0,0,U6,~
0,0,0,0,0,0,0,0,0,0)';
      PINUSE='POWER';
      NO_LOAD_CHECK='Both';
      NO_IO_CHECK='Both';
      NO_ASSERT_CHECK='TRUE';
      NO_DIR_CHECK='TRUE';
      ALLOW_CONNECT='TRUE';
    'VSS_U8':
      PIN_NUMBER='(0,0,0,0,0,0,0,0,0,0,0,0,0,0,0,0,0,0,0,0,0,0,0,0,0,0,0,0,0,U8,~
0,0,0,0,0,0,0,0,0,0)';
      PINUSE='POWER';
      NO_LOAD_CHECK='Both';
      NO_IO_CHECK='Both';
      NO_ASSERT_CHECK='TRUE';
      NO_DIR_CHECK='TRUE';
      ALLOW_CONNECT='TRUE';
    'VSS_U13':
      PIN_NUMBER='(0,0,0,0,0,0,0,0,0,0,0,0,0,0,0,0,0,0,0,0,0,0,0,0,0,0,0,0,0,U13~
,0,0,0,0,0,0,0,0,0,0)';
      PINUSE='POWER';
      NO_LOAD_CHECK='Both';
      NO_IO_CHECK='Both';
      NO_ASSERT_CHECK='TRUE';
      NO_DIR_CHECK='TRUE';
      ALLOW_CONNECT='TRUE';
    'VSS_U15':
      PIN_NUMBER='(0,0,0,0,0,0,0,0,0,0,0,0,0,0,0,0,0,0,0,0,0,0,0,0,0,0,0,0,0,U15~
,0,0,0,0,0,0,0,0,0,0)';
      PINUSE='POWER';
      NO_LOAD_CHECK='Both';
      NO_IO_CHECK='Both';
      NO_ASSERT_CHECK='TRUE';
      NO_DIR_CHECK='TRUE';
      ALLOW_CONNECT='TRUE';
    'VSS_U20':
      PIN_NUMBER='(0,0,0,0,0,0,0,0,0,0,0,0,0,0,0,0,0,0,0,0,0,0,0,0,0,0,0,0,0,U20~
,0,0,0,0,0,0,0,0,0,0)';
      PINUSE='POWER';
      NO_LOAD_CHECK='Both';
      NO_IO_CHECK='Both';
      NO_ASSERT_CHECK='TRUE';
      NO_DIR_CHECK='TRUE';
      ALLOW_CONNECT='TRUE';
    'VSS_U22':
      PIN_NUMBER='(0,0,0,0,0,0,0,0,0,0,0,0,0,0,0,0,0,0,0,0,0,0,0,0,0,0,0,0,0,U22~
,0,0,0,0,0,0,0,0,0,0)';
      PINUSE='POWER';
      NO_LOAD_CHECK='Both';
      NO_IO_CHECK='Both';
      NO_ASSERT_CHECK='TRUE';
      NO_DIR_CHECK='TRUE';
      ALLOW_CONNECT='TRUE';
    'VSS_U25':
      PIN_NUMBER='(0,0,0,0,0,0,0,0,0,0,0,0,0,0,0,0,0,0,0,0,0,0,0,0,0,0,0,0,0,U25~
,0,0,0,0,0,0,0,0,0,0)';
      PINUSE='POWER';
      NO_LOAD_CHECK='Both';
      NO_IO_CHECK='Both';
      NO_ASSERT_CHECK='TRUE';
      NO_DIR_CHECK='TRUE';
      ALLOW_CONNECT='TRUE';
    'VSS_U28':
      PIN_NUMBER='(0,0,0,0,0,0,0,0,0,0,0,0,0,0,0,0,0,0,0,0,0,0,0,0,0,0,0,0,0,U28~
,0,0,0,0,0,0,0,0,0,0)';
      PINUSE='POWER';
      NO_LOAD_CHECK='Both';
      NO_IO_CHECK='Both';
      NO_ASSERT_CHECK='TRUE';
      NO_DIR_CHECK='TRUE';
      ALLOW_CONNECT='TRUE';
    'VSS_U31':
      PIN_NUMBER='(0,0,0,0,0,0,0,0,0,0,0,0,0,0,0,0,0,0,0,0,0,0,0,0,0,0,0,0,0,U31~
,0,0,0,0,0,0,0,0,0,0)';
      PINUSE='POWER';
      NO_LOAD_CHECK='Both';
      NO_IO_CHECK='Both';
      NO_ASSERT_CHECK='TRUE';
      NO_DIR_CHECK='TRUE';
      ALLOW_CONNECT='TRUE';
    'VSS_U34':
      PIN_NUMBER='(0,0,0,0,0,0,0,0,0,0,0,0,0,0,0,0,0,0,0,0,0,0,0,0,0,0,0,0,0,U34~
,0,0,0,0,0,0,0,0,0,0)';
      PINUSE='POWER';
      NO_LOAD_CHECK='Both';
      NO_IO_CHECK='Both';
      NO_ASSERT_CHECK='TRUE';
      NO_DIR_CHECK='TRUE';
      ALLOW_CONNECT='TRUE';
    'VSS_U42':
      PIN_NUMBER='(0,0,0,0,0,0,0,0,0,0,0,0,0,0,0,0,0,0,0,0,0,0,0,0,0,0,0,0,0,U42~
,0,0,0,0,0,0,0,0,0,0)';
      PINUSE='POWER';
      NO_LOAD_CHECK='Both';
      NO_IO_CHECK='Both';
      NO_ASSERT_CHECK='TRUE';
      NO_DIR_CHECK='TRUE';
      ALLOW_CONNECT='TRUE';
    'VSS_U45':
      PIN_NUMBER='(0,0,0,0,0,0,0,0,0,0,0,0,0,0,0,0,0,0,0,0,0,0,0,0,0,0,0,0,0,U45~
,0,0,0,0,0,0,0,0,0,0)';
      PINUSE='POWER';
      NO_LOAD_CHECK='Both';
      NO_IO_CHECK='Both';
      NO_ASSERT_CHECK='TRUE';
      NO_DIR_CHECK='TRUE';
      ALLOW_CONNECT='TRUE';
    'VSS_U48':
      PIN_NUMBER='(0,0,0,0,0,0,0,0,0,0,0,0,0,0,0,0,0,0,0,0,0,0,0,0,0,0,0,0,0,U48~
,0,0,0,0,0,0,0,0,0,0)';
      PINUSE='POWER';
      NO_LOAD_CHECK='Both';
      NO_IO_CHECK='Both';
      NO_ASSERT_CHECK='TRUE';
      NO_DIR_CHECK='TRUE';
      ALLOW_CONNECT='TRUE';
    'VSS_U51':
      PIN_NUMBER='(0,0,0,0,0,0,0,0,0,0,0,0,0,0,0,0,0,0,0,0,0,0,0,0,0,0,0,0,0,U51~
,0,0,0,0,0,0,0,0,0,0)';
      PINUSE='POWER';
      NO_LOAD_CHECK='Both';
      NO_IO_CHECK='Both';
      NO_ASSERT_CHECK='TRUE';
      NO_DIR_CHECK='TRUE';
      ALLOW_CONNECT='TRUE';
    'VSS_U54':
      PIN_NUMBER='(0,0,0,0,0,0,0,0,0,0,0,0,0,0,0,0,0,0,0,0,0,0,0,0,0,0,0,0,0,U54~
,0,0,0,0,0,0,0,0,0,0)';
      PINUSE='POWER';
      NO_LOAD_CHECK='Both';
      NO_IO_CHECK='Both';
      NO_ASSERT_CHECK='TRUE';
      NO_DIR_CHECK='TRUE';
      ALLOW_CONNECT='TRUE';
    'VSS_U56':
      PIN_NUMBER='(0,0,0,0,0,0,0,0,0,0,0,0,0,0,0,0,0,0,0,0,0,0,0,0,0,0,0,0,0,U56~
,0,0,0,0,0,0,0,0,0,0)';
      PINUSE='POWER';
      NO_LOAD_CHECK='Both';
      NO_IO_CHECK='Both';
      NO_ASSERT_CHECK='TRUE';
      NO_DIR_CHECK='TRUE';
      ALLOW_CONNECT='TRUE';
    'VSS_U61':
      PIN_NUMBER='(0,0,0,0,0,0,0,0,0,0,0,0,0,0,0,0,0,0,0,0,0,0,0,0,0,0,0,0,0,U61~
,0,0,0,0,0,0,0,0,0,0)';
      PINUSE='POWER';
      NO_LOAD_CHECK='Both';
      NO_IO_CHECK='Both';
      NO_ASSERT_CHECK='TRUE';
      NO_DIR_CHECK='TRUE';
      ALLOW_CONNECT='TRUE';
    'VSS_U63':
      PIN_NUMBER='(0,0,0,0,0,0,0,0,0,0,0,0,0,0,0,0,0,0,0,0,0,0,0,0,0,0,0,0,0,U63~
,0,0,0,0,0,0,0,0,0,0)';
      PINUSE='POWER';
      NO_LOAD_CHECK='Both';
      NO_IO_CHECK='Both';
      NO_ASSERT_CHECK='TRUE';
      NO_DIR_CHECK='TRUE';
      ALLOW_CONNECT='TRUE';
    'VSS_U68':
      PIN_NUMBER='(0,0,0,0,0,0,0,0,0,0,0,0,0,0,0,0,0,0,0,0,0,0,0,0,0,0,0,0,0,U68~
,0,0,0,0,0,0,0,0,0,0)';
      PINUSE='POWER';
      NO_LOAD_CHECK='Both';
      NO_IO_CHECK='Both';
      NO_ASSERT_CHECK='TRUE';
      NO_DIR_CHECK='TRUE';
      ALLOW_CONNECT='TRUE';
    'VSS_U70':
      PIN_NUMBER='(0,0,0,0,0,0,0,0,0,0,0,0,0,0,0,0,0,0,0,0,0,0,0,0,0,0,0,0,0,U70~
,0,0,0,0,0,0,0,0,0,0)';
      PINUSE='POWER';
      NO_LOAD_CHECK='Both';
      NO_IO_CHECK='Both';
      NO_ASSERT_CHECK='TRUE';
      NO_DIR_CHECK='TRUE';
      ALLOW_CONNECT='TRUE';
    'VSS_U75':
      PIN_NUMBER='(0,0,0,0,0,0,0,0,0,0,0,0,0,0,0,0,0,0,0,0,0,0,0,0,0,0,0,0,0,U75~
,0,0,0,0,0,0,0,0,0,0)';
      PINUSE='POWER';
      NO_LOAD_CHECK='Both';
      NO_IO_CHECK='Both';
      NO_ASSERT_CHECK='TRUE';
      NO_DIR_CHECK='TRUE';
      ALLOW_CONNECT='TRUE';
    'VSS_V3':
      PIN_NUMBER='(0,0,0,0,0,0,0,0,0,0,0,0,0,0,0,0,0,0,0,0,0,0,0,0,0,0,0,0,0,V3,~
0,0,0,0,0,0,0,0,0,0)';
      PINUSE='POWER';
      NO_LOAD_CHECK='Both';
      NO_IO_CHECK='Both';
      NO_ASSERT_CHECK='TRUE';
      NO_DIR_CHECK='TRUE';
      ALLOW_CONNECT='TRUE';
    'VSS_V5':
      PIN_NUMBER='(0,0,0,0,0,0,0,0,0,0,0,0,0,0,0,0,0,0,0,0,0,0,0,0,0,0,0,0,0,V5,~
0,0,0,0,0,0,0,0,0,0)';
      PINUSE='POWER';
      NO_LOAD_CHECK='Both';
      NO_IO_CHECK='Both';
      NO_ASSERT_CHECK='TRUE';
      NO_DIR_CHECK='TRUE';
      ALLOW_CONNECT='TRUE';
    'VSS_V8':
      PIN_NUMBER='(0,0,0,0,0,0,0,0,0,0,0,0,0,0,0,0,0,0,0,0,0,0,0,0,0,0,0,0,0,V8,~
0,0,0,0,0,0,0,0,0,0)';
      PINUSE='POWER';
      NO_LOAD_CHECK='Both';
      NO_IO_CHECK='Both';
      NO_ASSERT_CHECK='TRUE';
      NO_DIR_CHECK='TRUE';
      ALLOW_CONNECT='TRUE';
    'VSS_V10':
      PIN_NUMBER='(0,0,0,0,0,0,0,0,0,0,0,0,0,0,0,0,0,0,0,0,0,0,0,0,0,0,0,0,0,V10~
,0,0,0,0,0,0,0,0,0,0)';
      PINUSE='POWER';
      NO_LOAD_CHECK='Both';
      NO_IO_CHECK='Both';
      NO_ASSERT_CHECK='TRUE';
      NO_DIR_CHECK='TRUE';
      ALLOW_CONNECT='TRUE';
    'VSS_V12':
      PIN_NUMBER='(0,0,0,0,0,0,0,0,0,0,0,0,0,0,0,0,0,0,0,0,0,0,0,0,0,0,0,0,0,V12~
,0,0,0,0,0,0,0,0,0,0)';
      PINUSE='POWER';
      NO_LOAD_CHECK='Both';
      NO_IO_CHECK='Both';
      NO_ASSERT_CHECK='TRUE';
      NO_DIR_CHECK='TRUE';
      ALLOW_CONNECT='TRUE';
    'VSS_V15':
      PIN_NUMBER='(0,0,0,0,0,0,0,0,0,0,0,0,0,0,0,0,0,0,0,0,0,0,0,0,0,0,0,0,0,V15~
,0,0,0,0,0,0,0,0,0,0)';
      PINUSE='POWER';
      NO_LOAD_CHECK='Both';
      NO_IO_CHECK='Both';
      NO_ASSERT_CHECK='TRUE';
      NO_DIR_CHECK='TRUE';
      ALLOW_CONNECT='TRUE';
    'VSS_V17':
      PIN_NUMBER='(0,0,0,0,0,0,0,0,0,0,0,0,0,0,0,0,0,0,0,0,0,0,0,0,0,0,0,0,0,V17~
,0,0,0,0,0,0,0,0,0,0)';
      PINUSE='POWER';
      NO_LOAD_CHECK='Both';
      NO_IO_CHECK='Both';
      NO_ASSERT_CHECK='TRUE';
      NO_DIR_CHECK='TRUE';
      ALLOW_CONNECT='TRUE';
    'VSS_V19':
      PIN_NUMBER='(0,0,0,0,0,0,0,0,0,0,0,0,0,0,0,0,0,0,0,0,0,0,0,0,0,0,0,0,0,V19~
,0,0,0,0,0,0,0,0,0,0)';
      PINUSE='POWER';
      NO_LOAD_CHECK='Both';
      NO_IO_CHECK='Both';
      NO_ASSERT_CHECK='TRUE';
      NO_DIR_CHECK='TRUE';
      ALLOW_CONNECT='TRUE';
    'VSS_V23':
      PIN_NUMBER='(0,0,0,0,0,0,0,0,0,0,0,0,0,0,0,0,0,0,0,0,0,0,0,0,0,0,0,0,0,V23~
,0,0,0,0,0,0,0,0,0,0)';
      PINUSE='POWER';
      NO_LOAD_CHECK='Both';
      NO_IO_CHECK='Both';
      NO_ASSERT_CHECK='TRUE';
      NO_DIR_CHECK='TRUE';
      ALLOW_CONNECT='TRUE';
    'VSS_V24':
      PIN_NUMBER='(0,0,0,0,0,0,0,0,0,0,0,0,0,0,0,0,0,0,0,0,0,0,0,0,0,0,0,0,0,V24~
,0,0,0,0,0,0,0,0,0,0)';
      PINUSE='POWER';
      NO_LOAD_CHECK='Both';
      NO_IO_CHECK='Both';
      NO_ASSERT_CHECK='TRUE';
      NO_DIR_CHECK='TRUE';
      ALLOW_CONNECT='TRUE';
    'VSS_V25':
      PIN_NUMBER='(0,0,0,0,0,0,0,0,0,0,0,0,0,0,0,0,0,0,0,0,0,0,0,0,0,0,0,0,0,V25~
,0,0,0,0,0,0,0,0,0,0)';
      PINUSE='POWER';
      NO_LOAD_CHECK='Both';
      NO_IO_CHECK='Both';
      NO_ASSERT_CHECK='TRUE';
      NO_DIR_CHECK='TRUE';
      ALLOW_CONNECT='TRUE';
    'VSS_V26':
      PIN_NUMBER='(0,0,0,0,0,0,0,0,0,0,0,0,0,0,0,0,0,0,0,0,0,0,0,0,0,0,0,0,0,V26~
,0,0,0,0,0,0,0,0,0,0)';
      PINUSE='POWER';
      NO_LOAD_CHECK='Both';
      NO_IO_CHECK='Both';
      NO_ASSERT_CHECK='TRUE';
      NO_DIR_CHECK='TRUE';
      ALLOW_CONNECT='TRUE';
    'VSS_V28':
      PIN_NUMBER='(0,0,0,0,0,0,0,0,0,0,0,0,0,0,0,0,0,0,0,0,0,0,0,0,0,0,0,0,0,V28~
,0,0,0,0,0,0,0,0,0,0)';
      PINUSE='POWER';
      NO_LOAD_CHECK='Both';
      NO_IO_CHECK='Both';
      NO_ASSERT_CHECK='TRUE';
      NO_DIR_CHECK='TRUE';
      ALLOW_CONNECT='TRUE';
    'VSS_V29':
      PIN_NUMBER='(0,0,0,0,0,0,0,0,0,0,0,0,0,0,0,0,0,0,0,0,0,0,0,0,0,0,0,0,0,V29~
,0,0,0,0,0,0,0,0,0,0)';
      PINUSE='POWER';
      NO_LOAD_CHECK='Both';
      NO_IO_CHECK='Both';
      NO_ASSERT_CHECK='TRUE';
      NO_DIR_CHECK='TRUE';
      ALLOW_CONNECT='TRUE';
    'VSS_V30':
      PIN_NUMBER='(0,0,0,0,0,0,0,0,0,0,0,0,0,0,0,0,0,0,0,0,0,0,0,0,0,0,0,0,0,V30~
,0,0,0,0,0,0,0,0,0,0)';
      PINUSE='POWER';
      NO_LOAD_CHECK='Both';
      NO_IO_CHECK='Both';
      NO_ASSERT_CHECK='TRUE';
      NO_DIR_CHECK='TRUE';
      ALLOW_CONNECT='TRUE';
    'VSS_V31':
      PIN_NUMBER='(0,0,0,0,0,0,0,0,0,0,0,0,0,0,0,0,0,0,0,0,0,0,0,0,0,0,0,0,0,V31~
,0,0,0,0,0,0,0,0,0,0)';
      PINUSE='POWER';
      NO_LOAD_CHECK='Both';
      NO_IO_CHECK='Both';
      NO_ASSERT_CHECK='TRUE';
      NO_DIR_CHECK='TRUE';
      ALLOW_CONNECT='TRUE';
    'VSS_V32':
      PIN_NUMBER='(0,0,0,0,0,0,0,0,0,0,0,0,0,0,0,0,0,0,0,0,0,0,0,0,0,0,0,0,0,V32~
,0,0,0,0,0,0,0,0,0,0)';
      PINUSE='POWER';
      NO_LOAD_CHECK='Both';
      NO_IO_CHECK='Both';
      NO_ASSERT_CHECK='TRUE';
      NO_DIR_CHECK='TRUE';
      ALLOW_CONNECT='TRUE';
    'VSS_V33':
      PIN_NUMBER='(0,0,0,0,0,0,0,0,0,0,0,0,0,0,0,0,0,0,0,0,0,0,0,0,0,0,0,0,0,V33~
,0,0,0,0,0,0,0,0,0,0)';
      PINUSE='POWER';
      NO_LOAD_CHECK='Both';
      NO_IO_CHECK='Both';
      NO_ASSERT_CHECK='TRUE';
      NO_DIR_CHECK='TRUE';
      ALLOW_CONNECT='TRUE';
    'VSS_V34':
      PIN_NUMBER='(0,0,0,0,0,0,0,0,0,0,0,0,0,0,0,0,0,0,0,0,0,0,0,0,0,0,0,0,0,V34~
,0,0,0,0,0,0,0,0,0,0)';
      PINUSE='POWER';
      NO_LOAD_CHECK='Both';
      NO_IO_CHECK='Both';
      NO_ASSERT_CHECK='TRUE';
      NO_DIR_CHECK='TRUE';
      ALLOW_CONNECT='TRUE';
    'VSS_V37':
      PIN_NUMBER='(0,0,0,0,0,0,0,0,0,0,0,0,0,0,0,0,0,0,0,0,0,0,0,0,0,0,0,0,0,V37~
,0,0,0,0,0,0,0,0,0,0)';
      PINUSE='POWER';
      NO_LOAD_CHECK='Both';
      NO_IO_CHECK='Both';
      NO_ASSERT_CHECK='TRUE';
      NO_DIR_CHECK='TRUE';
      ALLOW_CONNECT='TRUE';
    'VSS_V39':
      PIN_NUMBER='(0,0,0,0,0,0,0,0,0,0,0,0,0,0,0,0,0,0,0,0,0,0,0,0,0,0,0,0,0,V39~
,0,0,0,0,0,0,0,0,0,0)';
      PINUSE='POWER';
      NO_LOAD_CHECK='Both';
      NO_IO_CHECK='Both';
      NO_ASSERT_CHECK='TRUE';
      NO_DIR_CHECK='TRUE';
      ALLOW_CONNECT='TRUE';
    'VSS_V42':
      PIN_NUMBER='(0,0,0,0,0,0,0,0,0,0,0,0,0,0,0,0,0,0,0,0,0,0,0,0,0,0,0,0,0,V42~
,0,0,0,0,0,0,0,0,0,0)';
      PINUSE='POWER';
      NO_LOAD_CHECK='Both';
      NO_IO_CHECK='Both';
      NO_ASSERT_CHECK='TRUE';
      NO_DIR_CHECK='TRUE';
      ALLOW_CONNECT='TRUE';
    'VSS_V43':
      PIN_NUMBER='(0,0,0,0,0,0,0,0,0,0,0,0,0,0,0,0,0,0,0,0,0,0,0,0,0,0,0,0,0,V43~
,0,0,0,0,0,0,0,0,0,0)';
      PINUSE='POWER';
      NO_LOAD_CHECK='Both';
      NO_IO_CHECK='Both';
      NO_ASSERT_CHECK='TRUE';
      NO_DIR_CHECK='TRUE';
      ALLOW_CONNECT='TRUE';
    'VSS_V44':
      PIN_NUMBER='(0,0,0,0,0,0,0,0,0,0,0,0,0,0,0,0,0,0,0,0,0,0,0,0,0,0,0,0,0,V44~
,0,0,0,0,0,0,0,0,0,0)';
      PINUSE='POWER';
      NO_LOAD_CHECK='Both';
      NO_IO_CHECK='Both';
      NO_ASSERT_CHECK='TRUE';
      NO_DIR_CHECK='TRUE';
      ALLOW_CONNECT='TRUE';
    'VSS_V45':
      PIN_NUMBER='(0,0,0,0,0,0,0,0,0,0,0,0,0,0,0,0,0,0,0,0,0,0,0,0,0,0,0,0,0,V45~
,0,0,0,0,0,0,0,0,0,0)';
      PINUSE='POWER';
      NO_LOAD_CHECK='Both';
      NO_IO_CHECK='Both';
      NO_ASSERT_CHECK='TRUE';
      NO_DIR_CHECK='TRUE';
      ALLOW_CONNECT='TRUE';
    'VSS_V46':
      PIN_NUMBER='(0,0,0,0,0,0,0,0,0,0,0,0,0,0,0,0,0,0,0,0,0,0,0,0,0,0,0,0,0,V46~
,0,0,0,0,0,0,0,0,0,0)';
      PINUSE='POWER';
      NO_LOAD_CHECK='Both';
      NO_IO_CHECK='Both';
      NO_ASSERT_CHECK='TRUE';
      NO_DIR_CHECK='TRUE';
      ALLOW_CONNECT='TRUE';
    'VSS_V47':
      PIN_NUMBER='(0,0,0,0,0,0,0,0,0,0,0,0,0,0,0,0,0,0,0,0,0,0,0,0,0,0,0,0,0,V47~
,0,0,0,0,0,0,0,0,0,0)';
      PINUSE='POWER';
      NO_LOAD_CHECK='Both';
      NO_IO_CHECK='Both';
      NO_ASSERT_CHECK='TRUE';
      NO_DIR_CHECK='TRUE';
      ALLOW_CONNECT='TRUE';
    'VSS_V48':
      PIN_NUMBER='(0,0,0,0,0,0,0,0,0,0,0,0,0,0,0,0,0,0,0,0,0,0,0,0,0,0,0,0,0,V48~
,0,0,0,0,0,0,0,0,0,0)';
      PINUSE='POWER';
      NO_LOAD_CHECK='Both';
      NO_IO_CHECK='Both';
      NO_ASSERT_CHECK='TRUE';
      NO_DIR_CHECK='TRUE';
      ALLOW_CONNECT='TRUE';
    'VSS_V49':
      PIN_NUMBER='(0,0,0,0,0,0,0,0,0,0,0,0,0,0,0,0,0,0,0,0,0,0,0,0,0,0,0,0,0,V49~
,0,0,0,0,0,0,0,0,0,0)';
      PINUSE='POWER';
      NO_LOAD_CHECK='Both';
      NO_IO_CHECK='Both';
      NO_ASSERT_CHECK='TRUE';
      NO_DIR_CHECK='TRUE';
      ALLOW_CONNECT='TRUE';
    'VSS_V50':
      PIN_NUMBER='(0,0,0,0,0,0,0,0,0,0,0,0,0,0,0,0,0,0,0,0,0,0,0,0,0,0,0,0,0,V50~
,0,0,0,0,0,0,0,0,0,0)';
      PINUSE='POWER';
      NO_LOAD_CHECK='Both';
      NO_IO_CHECK='Both';
      NO_ASSERT_CHECK='TRUE';
      NO_DIR_CHECK='TRUE';
      ALLOW_CONNECT='TRUE';
    'VSS_V51':
      PIN_NUMBER='(0,0,0,0,0,0,0,0,0,0,0,0,0,0,0,0,0,0,0,0,0,0,0,0,0,0,0,0,0,V51~
,0,0,0,0,0,0,0,0,0,0)';
      PINUSE='POWER';
      NO_LOAD_CHECK='Both';
      NO_IO_CHECK='Both';
      NO_ASSERT_CHECK='TRUE';
      NO_DIR_CHECK='TRUE';
      ALLOW_CONNECT='TRUE';
    'VSS_V52':
      PIN_NUMBER='(0,0,0,0,0,0,0,0,0,0,0,0,0,0,0,0,0,0,0,0,0,0,0,0,0,0,0,0,0,V52~
,0,0,0,0,0,0,0,0,0,0)';
      PINUSE='POWER';
      NO_LOAD_CHECK='Both';
      NO_IO_CHECK='Both';
      NO_ASSERT_CHECK='TRUE';
      NO_DIR_CHECK='TRUE';
      ALLOW_CONNECT='TRUE';
    'VSS_V53':
      PIN_NUMBER='(0,0,0,0,0,0,0,0,0,0,0,0,0,0,0,0,0,0,0,0,0,0,0,0,0,0,0,0,0,V53~
,0,0,0,0,0,0,0,0,0,0)';
      PINUSE='POWER';
      NO_LOAD_CHECK='Both';
      NO_IO_CHECK='Both';
      NO_ASSERT_CHECK='TRUE';
      NO_DIR_CHECK='TRUE';
      ALLOW_CONNECT='TRUE';
    'VSS_V57':
      PIN_NUMBER='(0,0,0,0,0,0,0,0,0,0,0,0,0,0,0,0,0,0,0,0,0,0,0,0,0,0,0,0,0,V57~
,0,0,0,0,0,0,0,0,0,0)';
      PINUSE='POWER';
      NO_LOAD_CHECK='Both';
      NO_IO_CHECK='Both';
      NO_ASSERT_CHECK='TRUE';
      NO_DIR_CHECK='TRUE';
      ALLOW_CONNECT='TRUE';
    'VSS_V59':
      PIN_NUMBER='(0,0,0,0,0,0,0,0,0,0,0,0,0,0,0,0,0,0,0,0,0,0,0,0,0,0,0,0,0,V59~
,0,0,0,0,0,0,0,0,0,0)';
      PINUSE='POWER';
      NO_LOAD_CHECK='Both';
      NO_IO_CHECK='Both';
      NO_ASSERT_CHECK='TRUE';
      NO_DIR_CHECK='TRUE';
      ALLOW_CONNECT='TRUE';
    'VSS_V61':
      PIN_NUMBER='(0,0,0,0,0,0,0,0,0,0,0,0,0,0,0,0,0,0,0,0,0,0,0,0,0,0,0,0,0,V61~
,0,0,0,0,0,0,0,0,0,0)';
      PINUSE='POWER';
      NO_LOAD_CHECK='Both';
      NO_IO_CHECK='Both';
      NO_ASSERT_CHECK='TRUE';
      NO_DIR_CHECK='TRUE';
      ALLOW_CONNECT='TRUE';
    'VSS_V64':
      PIN_NUMBER='(0,0,0,0,0,0,0,0,0,0,0,0,0,0,0,0,0,0,0,0,0,0,0,0,0,0,0,0,0,V64~
,0,0,0,0,0,0,0,0,0,0)';
      PINUSE='POWER';
      NO_LOAD_CHECK='Both';
      NO_IO_CHECK='Both';
      NO_ASSERT_CHECK='TRUE';
      NO_DIR_CHECK='TRUE';
      ALLOW_CONNECT='TRUE';
    'VSS_V66':
      PIN_NUMBER='(0,0,0,0,0,0,0,0,0,0,0,0,0,0,0,0,0,0,0,0,0,0,0,0,0,0,0,0,0,V66~
,0,0,0,0,0,0,0,0,0,0)';
      PINUSE='POWER';
      NO_LOAD_CHECK='Both';
      NO_IO_CHECK='Both';
      NO_ASSERT_CHECK='TRUE';
      NO_DIR_CHECK='TRUE';
      ALLOW_CONNECT='TRUE';
    'VSS_V71':
      PIN_NUMBER='(0,0,0,0,0,0,0,0,0,0,0,0,0,0,0,0,0,0,0,0,0,0,0,0,0,0,0,0,0,V71~
,0,0,0,0,0,0,0,0,0,0)';
      PINUSE='POWER';
      NO_LOAD_CHECK='Both';
      NO_IO_CHECK='Both';
      NO_ASSERT_CHECK='TRUE';
      NO_DIR_CHECK='TRUE';
      ALLOW_CONNECT='TRUE';
    'VSS_V73':
      PIN_NUMBER='(0,0,0,0,0,0,0,0,0,0,0,0,0,0,0,0,0,0,0,0,0,0,0,0,0,0,0,0,0,V73~
,0,0,0,0,0,0,0,0,0,0)';
      PINUSE='POWER';
      NO_LOAD_CHECK='Both';
      NO_IO_CHECK='Both';
      NO_ASSERT_CHECK='TRUE';
      NO_DIR_CHECK='TRUE';
      ALLOW_CONNECT='TRUE';
    'VSS_W1':
      PIN_NUMBER='(0,0,0,0,0,0,0,0,0,0,0,0,0,0,0,0,0,0,0,0,0,0,0,0,0,0,0,0,0,W1,~
0,0,0,0,0,0,0,0,0,0)';
      PINUSE='POWER';
      NO_LOAD_CHECK='Both';
      NO_IO_CHECK='Both';
      NO_ASSERT_CHECK='TRUE';
      NO_DIR_CHECK='TRUE';
      ALLOW_CONNECT='TRUE';
    'VSS_W4':
      PIN_NUMBER='(0,0,0,0,0,0,0,0,0,0,0,0,0,0,0,0,0,0,0,0,0,0,0,0,0,0,0,0,0,W4,~
0,0,0,0,0,0,0,0,0,0)';
      PINUSE='POWER';
      NO_LOAD_CHECK='Both';
      NO_IO_CHECK='Both';
      NO_ASSERT_CHECK='TRUE';
      NO_DIR_CHECK='TRUE';
      ALLOW_CONNECT='TRUE';
    'VSS_W6':
      PIN_NUMBER='(0,0,0,0,0,0,0,0,0,0,0,0,0,0,0,0,0,0,0,0,0,0,0,0,0,0,0,0,0,W6,~
0,0,0,0,0,0,0,0,0,0)';
      PINUSE='POWER';
      NO_LOAD_CHECK='Both';
      NO_IO_CHECK='Both';
      NO_ASSERT_CHECK='TRUE';
      NO_DIR_CHECK='TRUE';
      ALLOW_CONNECT='TRUE';
    'VSS_W8':
      PIN_NUMBER='(0,0,0,0,0,0,0,0,0,0,0,0,0,0,0,0,0,0,0,0,0,0,0,0,0,0,0,0,0,W8,~
0,0,0,0,0,0,0,0,0,0)';
      PINUSE='POWER';
      NO_LOAD_CHECK='Both';
      NO_IO_CHECK='Both';
      NO_ASSERT_CHECK='TRUE';
      NO_DIR_CHECK='TRUE';
      ALLOW_CONNECT='TRUE';
    'VSS_W11':
      PIN_NUMBER='(0,0,0,0,0,0,0,0,0,0,0,0,0,0,0,0,0,0,0,0,0,0,0,0,0,0,0,0,0,W11~
,0,0,0,0,0,0,0,0,0,0)';
      PINUSE='POWER';
      NO_LOAD_CHECK='Both';
      NO_IO_CHECK='Both';
      NO_ASSERT_CHECK='TRUE';
      NO_DIR_CHECK='TRUE';
      ALLOW_CONNECT='TRUE';
    'VSS_W13':
      PIN_NUMBER='(0,0,0,0,0,0,0,0,0,0,0,0,0,0,0,0,0,0,0,0,0,0,0,0,0,0,0,0,0,W13~
,0,0,0,0,0,0,0,0,0,0)';
      PINUSE='POWER';
      NO_LOAD_CHECK='Both';
      NO_IO_CHECK='Both';
      NO_ASSERT_CHECK='TRUE';
      NO_DIR_CHECK='TRUE';
      ALLOW_CONNECT='TRUE';
    'VSS_W15':
      PIN_NUMBER='(0,0,0,0,0,0,0,0,0,0,0,0,0,0,0,0,0,0,0,0,0,0,0,0,0,0,0,0,0,W15~
,0,0,0,0,0,0,0,0,0,0)';
      PINUSE='POWER';
      NO_LOAD_CHECK='Both';
      NO_IO_CHECK='Both';
      NO_ASSERT_CHECK='TRUE';
      NO_DIR_CHECK='TRUE';
      ALLOW_CONNECT='TRUE';
    'VSS_W18':
      PIN_NUMBER='(0,0,0,0,0,0,0,0,0,0,0,0,0,0,0,0,0,0,0,0,0,0,0,0,0,0,0,0,0,W18~
,0,0,0,0,0,0,0,0,0,0)';
      PINUSE='POWER';
      NO_LOAD_CHECK='Both';
      NO_IO_CHECK='Both';
      NO_ASSERT_CHECK='TRUE';
      NO_DIR_CHECK='TRUE';
      ALLOW_CONNECT='TRUE';
    'VSS_W20':
      PIN_NUMBER='(0,0,0,0,0,0,0,0,0,0,0,0,0,0,0,0,0,0,0,0,0,0,0,0,0,0,0,0,0,W20~
,0,0,0,0,0,0,0,0,0,0)';
      PINUSE='POWER';
      NO_LOAD_CHECK='Both';
      NO_IO_CHECK='Both';
      NO_ASSERT_CHECK='TRUE';
      NO_DIR_CHECK='TRUE';
      ALLOW_CONNECT='TRUE';
    'VSS_W22':
      PIN_NUMBER='(0,0,0,0,0,0,0,0,0,0,0,0,0,0,0,0,0,0,0,0,0,0,0,0,0,0,0,0,0,W22~
,0,0,0,0,0,0,0,0,0,0)';
      PINUSE='POWER';
      NO_LOAD_CHECK='Both';
      NO_IO_CHECK='Both';
      NO_ASSERT_CHECK='TRUE';
      NO_DIR_CHECK='TRUE';
      ALLOW_CONNECT='TRUE';
    'VSS_W25':
      PIN_NUMBER='(0,0,0,0,0,0,0,0,0,0,0,0,0,0,0,0,0,0,0,0,0,0,0,0,0,0,0,0,0,W25~
,0,0,0,0,0,0,0,0,0,0)';
      PINUSE='POWER';
      NO_LOAD_CHECK='Both';
      NO_IO_CHECK='Both';
      NO_ASSERT_CHECK='TRUE';
      NO_DIR_CHECK='TRUE';
      ALLOW_CONNECT='TRUE';
    'VSS_W28':
      PIN_NUMBER='(0,0,0,0,0,0,0,0,0,0,0,0,0,0,0,0,0,0,0,0,0,0,0,0,0,0,0,0,0,W28~
,0,0,0,0,0,0,0,0,0,0)';
      PINUSE='POWER';
      NO_LOAD_CHECK='Both';
      NO_IO_CHECK='Both';
      NO_ASSERT_CHECK='TRUE';
      NO_DIR_CHECK='TRUE';
      ALLOW_CONNECT='TRUE';
    'VSS_W34':
      PIN_NUMBER='(0,0,0,0,0,0,0,0,0,0,0,0,0,0,0,0,0,0,0,0,0,0,0,0,0,0,0,0,0,W34~
,0,0,0,0,0,0,0,0,0,0)';
      PINUSE='POWER';
      NO_LOAD_CHECK='Both';
      NO_IO_CHECK='Both';
      NO_ASSERT_CHECK='TRUE';
      NO_DIR_CHECK='TRUE';
      ALLOW_CONNECT='TRUE';
    'VSS_W35':
      PIN_NUMBER='(0,0,0,0,0,0,0,0,0,0,0,0,0,0,0,0,0,0,0,0,0,0,0,0,0,0,0,0,0,W35~
,0,0,0,0,0,0,0,0,0,0)';
      PINUSE='POWER';
      NO_LOAD_CHECK='Both';
      NO_IO_CHECK='Both';
      NO_ASSERT_CHECK='TRUE';
      NO_DIR_CHECK='TRUE';
      ALLOW_CONNECT='TRUE';
    'VSS_W36':
      PIN_NUMBER='(0,0,0,0,0,0,0,0,0,0,0,0,0,0,0,0,0,0,0,0,0,0,0,0,0,0,0,0,0,W36~
,0,0,0,0,0,0,0,0,0,0)';
      PINUSE='POWER';
      NO_LOAD_CHECK='Both';
      NO_IO_CHECK='Both';
      NO_ASSERT_CHECK='TRUE';
      NO_DIR_CHECK='TRUE';
      ALLOW_CONNECT='TRUE';
    'VSS_W40':
      PIN_NUMBER='(0,0,0,0,0,0,0,0,0,0,0,0,0,0,0,0,0,0,0,0,0,0,0,0,0,0,0,0,0,W40~
,0,0,0,0,0,0,0,0,0,0)';
      PINUSE='POWER';
      NO_LOAD_CHECK='Both';
      NO_IO_CHECK='Both';
      NO_ASSERT_CHECK='TRUE';
      NO_DIR_CHECK='TRUE';
      ALLOW_CONNECT='TRUE';
    'VSS_W41':
      PIN_NUMBER='(0,0,0,0,0,0,0,0,0,0,0,0,0,0,0,0,0,0,0,0,0,0,0,0,0,0,0,0,0,W41~
,0,0,0,0,0,0,0,0,0,0)';
      PINUSE='POWER';
      NO_LOAD_CHECK='Both';
      NO_IO_CHECK='Both';
      NO_ASSERT_CHECK='TRUE';
      NO_DIR_CHECK='TRUE';
      ALLOW_CONNECT='TRUE';
    'VSS_W42':
      PIN_NUMBER='(0,0,0,0,0,0,0,0,0,0,0,0,0,0,0,0,0,0,0,0,0,0,0,0,0,0,0,0,0,W42~
,0,0,0,0,0,0,0,0,0,0)';
      PINUSE='POWER';
      NO_LOAD_CHECK='Both';
      NO_IO_CHECK='Both';
      NO_ASSERT_CHECK='TRUE';
      NO_DIR_CHECK='TRUE';
      ALLOW_CONNECT='TRUE';
    'VSS_W45':
      PIN_NUMBER='(0,0,0,0,0,0,0,0,0,0,0,0,0,0,0,0,0,0,0,0,0,0,0,0,0,0,0,0,0,W45~
,0,0,0,0,0,0,0,0,0,0)';
      PINUSE='POWER';
      NO_LOAD_CHECK='Both';
      NO_IO_CHECK='Both';
      NO_ASSERT_CHECK='TRUE';
      NO_DIR_CHECK='TRUE';
      ALLOW_CONNECT='TRUE';
    'VSS_W48':
      PIN_NUMBER='(0,0,0,0,0,0,0,0,0,0,0,0,0,0,0,0,0,0,0,0,0,0,0,0,0,0,0,0,0,W48~
,0,0,0,0,0,0,0,0,0,0)';
      PINUSE='POWER';
      NO_LOAD_CHECK='Both';
      NO_IO_CHECK='Both';
      NO_ASSERT_CHECK='TRUE';
      NO_DIR_CHECK='TRUE';
      ALLOW_CONNECT='TRUE';
    'VSS_W51':
      PIN_NUMBER='(0,0,0,0,0,0,0,0,0,0,0,0,0,0,0,0,0,0,0,0,0,0,0,0,0,0,0,0,0,W51~
,0,0,0,0,0,0,0,0,0,0)';
      PINUSE='POWER';
      NO_LOAD_CHECK='Both';
      NO_IO_CHECK='Both';
      NO_ASSERT_CHECK='TRUE';
      NO_DIR_CHECK='TRUE';
      ALLOW_CONNECT='TRUE';
    'VSS_W54':
      PIN_NUMBER='(0,0,0,0,0,0,0,0,0,0,0,0,0,0,0,0,0,0,0,0,0,0,0,0,0,0,0,0,0,W54~
,0,0,0,0,0,0,0,0,0,0)';
      PINUSE='POWER';
      NO_LOAD_CHECK='Both';
      NO_IO_CHECK='Both';
      NO_ASSERT_CHECK='TRUE';
      NO_DIR_CHECK='TRUE';
      ALLOW_CONNECT='TRUE';
    'VSS_W56':
      PIN_NUMBER='(0,0,0,0,0,0,0,0,0,0,0,0,0,0,0,0,0,0,0,0,0,0,0,0,0,0,0,0,0,W56~
,0,0,0,0,0,0,0,0,0,0)';
      PINUSE='POWER';
      NO_LOAD_CHECK='Both';
      NO_IO_CHECK='Both';
      NO_ASSERT_CHECK='TRUE';
      NO_DIR_CHECK='TRUE';
      ALLOW_CONNECT='TRUE';
    'VSS_W58':
      PIN_NUMBER='(0,0,0,0,0,0,0,0,0,0,0,0,0,0,0,0,0,0,0,0,0,0,0,0,0,0,0,0,0,W58~
,0,0,0,0,0,0,0,0,0,0)';
      PINUSE='POWER';
      NO_LOAD_CHECK='Both';
      NO_IO_CHECK='Both';
      NO_ASSERT_CHECK='TRUE';
      NO_DIR_CHECK='TRUE';
      ALLOW_CONNECT='TRUE';
    'VSS_W61':
      PIN_NUMBER='(0,0,0,0,0,0,0,0,0,0,0,0,0,0,0,0,0,0,0,0,0,0,0,0,0,0,0,0,0,W61~
,0,0,0,0,0,0,0,0,0,0)';
      PINUSE='POWER';
      NO_LOAD_CHECK='Both';
      NO_IO_CHECK='Both';
      NO_ASSERT_CHECK='TRUE';
      NO_DIR_CHECK='TRUE';
      ALLOW_CONNECT='TRUE';
    'VSS_W63':
      PIN_NUMBER='(0,0,0,0,0,0,0,0,0,0,0,0,0,0,0,0,0,0,0,0,0,0,0,0,0,0,0,0,0,W63~
,0,0,0,0,0,0,0,0,0,0)';
      PINUSE='POWER';
      NO_LOAD_CHECK='Both';
      NO_IO_CHECK='Both';
      NO_ASSERT_CHECK='TRUE';
      NO_DIR_CHECK='TRUE';
      ALLOW_CONNECT='TRUE';
    'VSS_W65':
      PIN_NUMBER='(0,0,0,0,0,0,0,0,0,0,0,0,0,0,0,0,0,0,0,0,0,0,0,0,0,0,0,0,0,W65~
,0,0,0,0,0,0,0,0,0,0)';
      PINUSE='POWER';
      NO_LOAD_CHECK='Both';
      NO_IO_CHECK='Both';
      NO_ASSERT_CHECK='TRUE';
      NO_DIR_CHECK='TRUE';
      ALLOW_CONNECT='TRUE';
    'VSS_W68':
      PIN_NUMBER='(0,0,0,0,0,0,0,0,0,0,0,0,0,0,0,0,0,0,0,0,0,0,0,0,0,0,0,0,0,W68~
,0,0,0,0,0,0,0,0,0,0)';
      PINUSE='POWER';
      NO_LOAD_CHECK='Both';
      NO_IO_CHECK='Both';
      NO_ASSERT_CHECK='TRUE';
      NO_DIR_CHECK='TRUE';
      ALLOW_CONNECT='TRUE';
    'VSS_W70':
      PIN_NUMBER='(0,0,0,0,0,0,0,0,0,0,0,0,0,0,0,0,0,0,0,0,0,0,0,0,0,0,0,0,0,W70~
,0,0,0,0,0,0,0,0,0,0)';
      PINUSE='POWER';
      NO_LOAD_CHECK='Both';
      NO_IO_CHECK='Both';
      NO_ASSERT_CHECK='TRUE';
      NO_DIR_CHECK='TRUE';
      ALLOW_CONNECT='TRUE';
    'VSS_W72':
      PIN_NUMBER='(0,0,0,0,0,0,0,0,0,0,0,0,0,0,0,0,0,0,0,0,0,0,0,0,0,0,0,0,0,W72~
,0,0,0,0,0,0,0,0,0,0)';
      PINUSE='POWER';
      NO_LOAD_CHECK='Both';
      NO_IO_CHECK='Both';
      NO_ASSERT_CHECK='TRUE';
      NO_DIR_CHECK='TRUE';
      ALLOW_CONNECT='TRUE';
    'VSS_W75':
      PIN_NUMBER='(0,0,0,0,0,0,0,0,0,0,0,0,0,0,0,0,0,0,0,0,0,0,0,0,0,0,0,0,0,W75~
,0,0,0,0,0,0,0,0,0,0)';
      PINUSE='POWER';
      NO_LOAD_CHECK='Both';
      NO_IO_CHECK='Both';
      NO_ASSERT_CHECK='TRUE';
      NO_DIR_CHECK='TRUE';
      ALLOW_CONNECT='TRUE';
    'VSS_Y3':
      PIN_NUMBER='(0,0,0,0,0,0,0,0,0,0,0,0,0,0,0,0,0,0,0,0,0,0,0,0,0,0,0,0,0,Y3,~
0,0,0,0,0,0,0,0,0,0)';
      PINUSE='POWER';
      NO_LOAD_CHECK='Both';
      NO_IO_CHECK='Both';
      NO_ASSERT_CHECK='TRUE';
      NO_DIR_CHECK='TRUE';
      ALLOW_CONNECT='TRUE';
    'VSS_Y8':
      PIN_NUMBER='(0,0,0,0,0,0,0,0,0,0,0,0,0,0,0,0,0,0,0,0,0,0,0,0,0,0,0,0,0,Y8,~
0,0,0,0,0,0,0,0,0,0)';
      PINUSE='POWER';
      NO_LOAD_CHECK='Both';
      NO_IO_CHECK='Both';
      NO_ASSERT_CHECK='TRUE';
      NO_DIR_CHECK='TRUE';
      ALLOW_CONNECT='TRUE';
    'VSS_Y10':
      PIN_NUMBER='(0,0,0,0,0,0,0,0,0,0,0,0,0,0,0,0,0,0,0,0,0,0,0,0,0,0,0,0,0,Y10~
,0,0,0,0,0,0,0,0,0,0)';
      PINUSE='POWER';
      NO_LOAD_CHECK='Both';
      NO_IO_CHECK='Both';
      NO_ASSERT_CHECK='TRUE';
      NO_DIR_CHECK='TRUE';
      ALLOW_CONNECT='TRUE';
    'VSS_Y15':
      PIN_NUMBER='(0,0,0,0,0,0,0,0,0,0,0,0,0,0,0,0,0,0,0,0,0,0,0,0,0,0,0,0,0,Y15~
,0,0,0,0,0,0,0,0,0,0)';
      PINUSE='POWER';
      NO_LOAD_CHECK='Both';
      NO_IO_CHECK='Both';
      NO_ASSERT_CHECK='TRUE';
      NO_DIR_CHECK='TRUE';
      ALLOW_CONNECT='TRUE';
    'VSS_Y17':
      PIN_NUMBER='(0,0,0,0,0,0,0,0,0,0,0,0,0,0,0,0,0,0,0,0,0,0,0,0,0,0,0,0,0,Y17~
,0,0,0,0,0,0,0,0,0,0)';
      PINUSE='POWER';
      NO_LOAD_CHECK='Both';
      NO_IO_CHECK='Both';
      NO_ASSERT_CHECK='TRUE';
      NO_DIR_CHECK='TRUE';
      ALLOW_CONNECT='TRUE';
    'VSS_Y22':
      PIN_NUMBER='(0,0,0,0,0,0,0,0,0,0,0,0,0,0,0,0,0,0,0,0,0,0,0,0,0,0,0,0,0,Y22~
,0,0,0,0,0,0,0,0,0,0)';
      PINUSE='POWER';
      NO_LOAD_CHECK='Both';
      NO_IO_CHECK='Both';
      NO_ASSERT_CHECK='TRUE';
      NO_DIR_CHECK='TRUE';
      ALLOW_CONNECT='TRUE';
    'VSS_Y23':
      PIN_NUMBER='(0,0,0,0,0,0,0,0,0,0,0,0,0,0,0,0,0,0,0,0,0,0,0,0,0,0,0,0,0,Y23~
,0,0,0,0,0,0,0,0,0,0)';
      PINUSE='POWER';
      NO_LOAD_CHECK='Both';
      NO_IO_CHECK='Both';
      NO_ASSERT_CHECK='TRUE';
      NO_DIR_CHECK='TRUE';
      ALLOW_CONNECT='TRUE';
    'VSS_Y24':
      PIN_NUMBER='(0,0,0,0,0,0,0,0,0,0,0,0,0,0,0,0,0,0,0,0,0,0,0,0,0,0,0,0,0,Y24~
,0,0,0,0,0,0,0,0,0,0)';
      PINUSE='POWER';
      NO_LOAD_CHECK='Both';
      NO_IO_CHECK='Both';
      NO_ASSERT_CHECK='TRUE';
      NO_DIR_CHECK='TRUE';
      ALLOW_CONNECT='TRUE';
    'VSS_Y25':
      PIN_NUMBER='(0,0,0,0,0,0,0,0,0,0,0,0,0,0,0,0,0,0,0,0,0,0,0,0,0,0,0,0,0,Y25~
,0,0,0,0,0,0,0,0,0,0)';
      PINUSE='POWER';
      NO_LOAD_CHECK='Both';
      NO_IO_CHECK='Both';
      NO_ASSERT_CHECK='TRUE';
      NO_DIR_CHECK='TRUE';
      ALLOW_CONNECT='TRUE';
    'VSS_Y26':
      PIN_NUMBER='(0,0,0,0,0,0,0,0,0,0,0,0,0,0,0,0,0,0,0,0,0,0,0,0,0,0,0,0,0,Y26~
,0,0,0,0,0,0,0,0,0,0)';
      PINUSE='POWER';
      NO_LOAD_CHECK='Both';
      NO_IO_CHECK='Both';
      NO_ASSERT_CHECK='TRUE';
      NO_DIR_CHECK='TRUE';
      ALLOW_CONNECT='TRUE';
    'VSS_Y27':
      PIN_NUMBER='(0,0,0,0,0,0,0,0,0,0,0,0,0,0,0,0,0,0,0,0,0,0,0,0,0,0,0,0,0,Y27~
,0,0,0,0,0,0,0,0,0,0)';
      PINUSE='POWER';
      NO_LOAD_CHECK='Both';
      NO_IO_CHECK='Both';
      NO_ASSERT_CHECK='TRUE';
      NO_DIR_CHECK='TRUE';
      ALLOW_CONNECT='TRUE';
    'VSS_Y28':
      PIN_NUMBER='(0,0,0,0,0,0,0,0,0,0,0,0,0,0,0,0,0,0,0,0,0,0,0,0,0,0,0,0,0,Y28~
,0,0,0,0,0,0,0,0,0,0)';
      PINUSE='POWER';
      NO_LOAD_CHECK='Both';
      NO_IO_CHECK='Both';
      NO_ASSERT_CHECK='TRUE';
      NO_DIR_CHECK='TRUE';
      ALLOW_CONNECT='TRUE';
    'VSS_Y31':
      PIN_NUMBER='(0,0,0,0,0,0,0,0,0,0,0,0,0,0,0,0,0,0,0,0,0,0,0,0,0,0,0,0,0,Y31~
,0,0,0,0,0,0,0,0,0,0)';
      PINUSE='POWER';
      NO_LOAD_CHECK='Both';
      NO_IO_CHECK='Both';
      NO_ASSERT_CHECK='TRUE';
      NO_DIR_CHECK='TRUE';
      ALLOW_CONNECT='TRUE';
    'VSS_Y32':
      PIN_NUMBER='(0,0,0,0,0,0,0,0,0,0,0,0,0,0,0,0,0,0,0,0,0,0,0,0,0,0,0,0,0,Y32~
,0,0,0,0,0,0,0,0,0,0)';
      PINUSE='POWER';
      NO_LOAD_CHECK='Both';
      NO_IO_CHECK='Both';
      NO_ASSERT_CHECK='TRUE';
      NO_DIR_CHECK='TRUE';
      ALLOW_CONNECT='TRUE';
    'VSS_Y33':
      PIN_NUMBER='(0,0,0,0,0,0,0,0,0,0,0,0,0,0,0,0,0,0,0,0,0,0,0,0,0,0,0,0,0,Y33~
,0,0,0,0,0,0,0,0,0,0)';
      PINUSE='POWER';
      NO_LOAD_CHECK='Both';
      NO_IO_CHECK='Both';
      NO_ASSERT_CHECK='TRUE';
      NO_DIR_CHECK='TRUE';
      ALLOW_CONNECT='TRUE';
    'VSS_Y34':
      PIN_NUMBER='(0,0,0,0,0,0,0,0,0,0,0,0,0,0,0,0,0,0,0,0,0,0,0,0,0,0,0,0,0,Y34~
,0,0,0,0,0,0,0,0,0,0)';
      PINUSE='POWER';
      NO_LOAD_CHECK='Both';
      NO_IO_CHECK='Both';
      NO_ASSERT_CHECK='TRUE';
      NO_DIR_CHECK='TRUE';
      ALLOW_CONNECT='TRUE';
    'VSS_Y37':
      PIN_NUMBER='(0,0,0,0,0,0,0,0,0,0,0,0,0,0,0,0,0,0,0,0,0,0,0,0,0,0,0,0,0,Y37~
,0,0,0,0,0,0,0,0,0,0)';
      PINUSE='POWER';
      NO_LOAD_CHECK='Both';
      NO_IO_CHECK='Both';
      NO_ASSERT_CHECK='TRUE';
      NO_DIR_CHECK='TRUE';
      ALLOW_CONNECT='TRUE';
    'VSS_Y39':
      PIN_NUMBER='(0,0,0,0,0,0,0,0,0,0,0,0,0,0,0,0,0,0,0,0,0,0,0,0,0,0,0,0,0,Y39~
,0,0,0,0,0,0,0,0,0,0)';
      PINUSE='POWER';
      NO_LOAD_CHECK='Both';
      NO_IO_CHECK='Both';
      NO_ASSERT_CHECK='TRUE';
      NO_DIR_CHECK='TRUE';
      ALLOW_CONNECT='TRUE';
    'VSS_Y42':
      PIN_NUMBER='(0,0,0,0,0,0,0,0,0,0,0,0,0,0,0,0,0,0,0,0,0,0,0,0,0,0,0,0,0,Y42~
,0,0,0,0,0,0,0,0,0,0)';
      PINUSE='POWER';
      NO_LOAD_CHECK='Both';
      NO_IO_CHECK='Both';
      NO_ASSERT_CHECK='TRUE';
      NO_DIR_CHECK='TRUE';
      ALLOW_CONNECT='TRUE';
    'VSS_Y43':
      PIN_NUMBER='(0,0,0,0,0,0,0,0,0,0,0,0,0,0,0,0,0,0,0,0,0,0,0,0,0,0,0,0,0,Y43~
,0,0,0,0,0,0,0,0,0,0)';
      PINUSE='POWER';
      NO_LOAD_CHECK='Both';
      NO_IO_CHECK='Both';
      NO_ASSERT_CHECK='TRUE';
      NO_DIR_CHECK='TRUE';
      ALLOW_CONNECT='TRUE';
    'VSS_Y44':
      PIN_NUMBER='(0,0,0,0,0,0,0,0,0,0,0,0,0,0,0,0,0,0,0,0,0,0,0,0,0,0,0,0,0,Y44~
,0,0,0,0,0,0,0,0,0,0)';
      PINUSE='POWER';
      NO_LOAD_CHECK='Both';
      NO_IO_CHECK='Both';
      NO_ASSERT_CHECK='TRUE';
      NO_DIR_CHECK='TRUE';
      ALLOW_CONNECT='TRUE';
    'VSS_Y45':
      PIN_NUMBER='(0,0,0,0,0,0,0,0,0,0,0,0,0,0,0,0,0,0,0,0,0,0,0,0,0,0,0,0,0,Y45~
,0,0,0,0,0,0,0,0,0,0)';
      PINUSE='POWER';
      NO_LOAD_CHECK='Both';
      NO_IO_CHECK='Both';
      NO_ASSERT_CHECK='TRUE';
      NO_DIR_CHECK='TRUE';
      ALLOW_CONNECT='TRUE';
    'VSS_Y48':
      PIN_NUMBER='(0,0,0,0,0,0,0,0,0,0,0,0,0,0,0,0,0,0,0,0,0,0,0,0,0,0,0,0,0,Y48~
,0,0,0,0,0,0,0,0,0,0)';
      PINUSE='POWER';
      NO_LOAD_CHECK='Both';
      NO_IO_CHECK='Both';
      NO_ASSERT_CHECK='TRUE';
      NO_DIR_CHECK='TRUE';
      ALLOW_CONNECT='TRUE';
    'VSS_Y49':
      PIN_NUMBER='(0,0,0,0,0,0,0,0,0,0,0,0,0,0,0,0,0,0,0,0,0,0,0,0,0,0,0,0,0,Y49~
,0,0,0,0,0,0,0,0,0,0)';
      PINUSE='POWER';
      NO_LOAD_CHECK='Both';
      NO_IO_CHECK='Both';
      NO_ASSERT_CHECK='TRUE';
      NO_DIR_CHECK='TRUE';
      ALLOW_CONNECT='TRUE';
    'VSS_Y50':
      PIN_NUMBER='(0,0,0,0,0,0,0,0,0,0,0,0,0,0,0,0,0,0,0,0,0,0,0,0,0,0,0,0,0,Y50~
,0,0,0,0,0,0,0,0,0,0)';
      PINUSE='POWER';
      NO_LOAD_CHECK='Both';
      NO_IO_CHECK='Both';
      NO_ASSERT_CHECK='TRUE';
      NO_DIR_CHECK='TRUE';
      ALLOW_CONNECT='TRUE';
    'VSS_Y51':
      PIN_NUMBER='(0,0,0,0,0,0,0,0,0,0,0,0,0,0,0,0,0,0,0,0,0,0,0,0,0,0,0,0,0,Y51~
,0,0,0,0,0,0,0,0,0,0)';
      PINUSE='POWER';
      NO_LOAD_CHECK='Both';
      NO_IO_CHECK='Both';
      NO_ASSERT_CHECK='TRUE';
      NO_DIR_CHECK='TRUE';
      ALLOW_CONNECT='TRUE';
    'VSS_Y52':
      PIN_NUMBER='(0,0,0,0,0,0,0,0,0,0,0,0,0,0,0,0,0,0,0,0,0,0,0,0,0,0,0,0,0,Y52~
,0,0,0,0,0,0,0,0,0,0)';
      PINUSE='POWER';
      NO_LOAD_CHECK='Both';
      NO_IO_CHECK='Both';
      NO_ASSERT_CHECK='TRUE';
      NO_DIR_CHECK='TRUE';
      ALLOW_CONNECT='TRUE';
    'VSS_Y53':
      PIN_NUMBER='(0,0,0,0,0,0,0,0,0,0,0,0,0,0,0,0,0,0,0,0,0,0,0,0,0,0,0,0,0,Y53~
,0,0,0,0,0,0,0,0,0,0)';
      PINUSE='POWER';
      NO_LOAD_CHECK='Both';
      NO_IO_CHECK='Both';
      NO_ASSERT_CHECK='TRUE';
      NO_DIR_CHECK='TRUE';
      ALLOW_CONNECT='TRUE';
    'VSS_Y54':
      PIN_NUMBER='(0,0,0,0,0,0,0,0,0,0,0,0,0,0,0,0,0,0,0,0,0,0,0,0,0,0,0,0,0,Y54~
,0,0,0,0,0,0,0,0,0,0)';
      PINUSE='POWER';
      NO_LOAD_CHECK='Both';
      NO_IO_CHECK='Both';
      NO_ASSERT_CHECK='TRUE';
      NO_DIR_CHECK='TRUE';
      ALLOW_CONNECT='TRUE';
    'VSS_Y59':
      PIN_NUMBER='(0,0,0,0,0,0,0,0,0,0,0,0,0,0,0,0,0,0,0,0,0,0,0,0,0,0,0,0,0,Y59~
,0,0,0,0,0,0,0,0,0,0)';
      PINUSE='POWER';
      NO_LOAD_CHECK='Both';
      NO_IO_CHECK='Both';
      NO_ASSERT_CHECK='TRUE';
      NO_DIR_CHECK='TRUE';
      ALLOW_CONNECT='TRUE';
    'VSS_Y61':
      PIN_NUMBER='(0,0,0,0,0,0,0,0,0,0,0,0,0,0,0,0,0,0,0,0,0,0,0,0,0,0,0,0,0,Y61~
,0,0,0,0,0,0,0,0,0,0)';
      PINUSE='POWER';
      NO_LOAD_CHECK='Both';
      NO_IO_CHECK='Both';
      NO_ASSERT_CHECK='TRUE';
      NO_DIR_CHECK='TRUE';
      ALLOW_CONNECT='TRUE';
    'VSS_Y66':
      PIN_NUMBER='(0,0,0,0,0,0,0,0,0,0,0,0,0,0,0,0,0,0,0,0,0,0,0,0,0,0,0,0,0,Y66~
,0,0,0,0,0,0,0,0,0,0)';
      PINUSE='POWER';
      NO_LOAD_CHECK='Both';
      NO_IO_CHECK='Both';
      NO_ASSERT_CHECK='TRUE';
      NO_DIR_CHECK='TRUE';
      ALLOW_CONNECT='TRUE';
    'VSS_Y68':
      PIN_NUMBER='(0,0,0,0,0,0,0,0,0,0,0,0,0,0,0,0,0,0,0,0,0,0,0,0,0,0,0,0,0,Y68~
,0,0,0,0,0,0,0,0,0,0)';
      PINUSE='POWER';
      NO_LOAD_CHECK='Both';
      NO_IO_CHECK='Both';
      NO_ASSERT_CHECK='TRUE';
      NO_DIR_CHECK='TRUE';
      ALLOW_CONNECT='TRUE';
    'VSS_Y73':
      PIN_NUMBER='(0,0,0,0,0,0,0,0,0,0,0,0,0,0,0,0,0,0,0,0,0,0,0,0,0,0,0,0,0,Y73~
,0,0,0,0,0,0,0,0,0,0)';
      PINUSE='POWER';
      NO_LOAD_CHECK='Both';
      NO_IO_CHECK='Both';
      NO_ASSERT_CHECK='TRUE';
      NO_DIR_CHECK='TRUE';
      ALLOW_CONNECT='TRUE';
    'VSS_AA1':
      PIN_NUMBER='(0,0,0,0,0,0,0,0,0,0,0,0,0,0,0,0,0,0,0,0,0,0,0,0,0,0,0,0,0,AA1~
,0,0,0,0,0,0,0,0,0,0)';
      PINUSE='POWER';
      NO_LOAD_CHECK='Both';
      NO_IO_CHECK='Both';
      NO_ASSERT_CHECK='TRUE';
      NO_DIR_CHECK='TRUE';
      ALLOW_CONNECT='TRUE';
    'VSS_AA4':
      PIN_NUMBER='(0,0,0,0,0,0,0,0,0,0,0,0,0,0,0,0,0,0,0,0,0,0,0,0,0,0,0,0,0,AA4~
,0,0,0,0,0,0,0,0,0,0)';
      PINUSE='POWER';
      NO_LOAD_CHECK='Both';
      NO_IO_CHECK='Both';
      NO_ASSERT_CHECK='TRUE';
      NO_DIR_CHECK='TRUE';
      ALLOW_CONNECT='TRUE';
    'VSS_AA6':
      PIN_NUMBER='(0,0,0,0,0,0,0,0,0,0,0,0,0,0,0,0,0,0,0,0,0,0,0,0,0,0,0,0,0,AA6~
,0,0,0,0,0,0,0,0,0,0)';
      PINUSE='POWER';
      NO_LOAD_CHECK='Both';
      NO_IO_CHECK='Both';
      NO_ASSERT_CHECK='TRUE';
      NO_DIR_CHECK='TRUE';
      ALLOW_CONNECT='TRUE';
    'VSS_AA8':
      PIN_NUMBER='(0,0,0,0,0,0,0,0,0,0,0,0,0,0,0,0,0,0,0,0,0,0,0,0,0,0,0,0,0,AA8~
,0,0,0,0,0,0,0,0,0,0)';
      PINUSE='POWER';
      NO_LOAD_CHECK='Both';
      NO_IO_CHECK='Both';
      NO_ASSERT_CHECK='TRUE';
      NO_DIR_CHECK='TRUE';
      ALLOW_CONNECT='TRUE';
    'VSS_AA11':
      PIN_NUMBER='(0,0,0,0,0,0,0,0,0,0,0,0,0,0,0,0,0,0,0,0,0,0,0,0,0,0,0,0,0,AA1~
1,0,0,0,0,0,0,0,0,0,0)';
      PINUSE='POWER';
      NO_LOAD_CHECK='Both';
      NO_IO_CHECK='Both';
      NO_ASSERT_CHECK='TRUE';
      NO_DIR_CHECK='TRUE';
      ALLOW_CONNECT='TRUE';
    'VSS_AA13':
      PIN_NUMBER='(0,0,0,0,0,0,0,0,0,0,0,0,0,0,0,0,0,0,0,0,0,0,0,0,0,0,0,0,0,AA1~
3,0,0,0,0,0,0,0,0,0,0)';
      PINUSE='POWER';
      NO_LOAD_CHECK='Both';
      NO_IO_CHECK='Both';
      NO_ASSERT_CHECK='TRUE';
      NO_DIR_CHECK='TRUE';
      ALLOW_CONNECT='TRUE';
    'VSS_AA15':
      PIN_NUMBER='(0,0,0,0,0,0,0,0,0,0,0,0,0,0,0,0,0,0,0,0,0,0,0,0,0,0,0,0,0,AA1~
5,0,0,0,0,0,0,0,0,0,0)';
      PINUSE='POWER';
      NO_LOAD_CHECK='Both';
      NO_IO_CHECK='Both';
      NO_ASSERT_CHECK='TRUE';
      NO_DIR_CHECK='TRUE';
      ALLOW_CONNECT='TRUE';
    'VSS_AA18':
      PIN_NUMBER='(0,0,0,0,0,0,0,0,0,0,0,0,0,0,0,0,0,0,0,0,0,0,0,0,0,0,0,0,0,AA1~
8,0,0,0,0,0,0,0,0,0,0)';
      PINUSE='POWER';
      NO_LOAD_CHECK='Both';
      NO_IO_CHECK='Both';
      NO_ASSERT_CHECK='TRUE';
      NO_DIR_CHECK='TRUE';
      ALLOW_CONNECT='TRUE';
    'VSS_AA20':
      PIN_NUMBER='(0,0,0,0,0,0,0,0,0,0,0,0,0,0,0,0,0,0,0,0,0,0,0,0,0,0,0,0,0,AA2~
0,0,0,0,0,0,0,0,0,0,0)';
      PINUSE='POWER';
      NO_LOAD_CHECK='Both';
      NO_IO_CHECK='Both';
      NO_ASSERT_CHECK='TRUE';
      NO_DIR_CHECK='TRUE';
      ALLOW_CONNECT='TRUE';
    'VSS_AA31':
      PIN_NUMBER='(0,0,0,0,0,0,0,0,0,0,0,0,0,0,0,0,0,0,0,0,0,0,0,0,0,0,0,0,0,AA3~
1,0,0,0,0,0,0,0,0,0,0)';
      PINUSE='POWER';
      NO_LOAD_CHECK='Both';
      NO_IO_CHECK='Both';
      NO_ASSERT_CHECK='TRUE';
      NO_DIR_CHECK='TRUE';
      ALLOW_CONNECT='TRUE';
    'VSS_AA34':
      PIN_NUMBER='(0,0,0,0,0,0,0,0,0,0,0,0,0,0,0,0,0,0,0,0,0,0,0,0,0,0,0,0,0,AA3~
4,0,0,0,0,0,0,0,0,0,0)';
      PINUSE='POWER';
      NO_LOAD_CHECK='Both';
      NO_IO_CHECK='Both';
      NO_ASSERT_CHECK='TRUE';
      NO_DIR_CHECK='TRUE';
      ALLOW_CONNECT='TRUE';
    'VSS_AA35':
      PIN_NUMBER='(0,0,0,0,0,0,0,0,0,0,0,0,0,0,0,0,0,0,0,0,0,0,0,0,0,0,0,0,0,AA3~
5,0,0,0,0,0,0,0,0,0,0)';
      PINUSE='POWER';
      NO_LOAD_CHECK='Both';
      NO_IO_CHECK='Both';
      NO_ASSERT_CHECK='TRUE';
      NO_DIR_CHECK='TRUE';
      ALLOW_CONNECT='TRUE';
    'VSS_AA36':
      PIN_NUMBER='(0,0,0,0,0,0,0,0,0,0,0,0,0,0,0,0,0,0,0,0,0,0,0,0,0,0,0,0,0,AA3~
6,0,0,0,0,0,0,0,0,0,0)';
      PINUSE='POWER';
      NO_LOAD_CHECK='Both';
      NO_IO_CHECK='Both';
      NO_ASSERT_CHECK='TRUE';
      NO_DIR_CHECK='TRUE';
      ALLOW_CONNECT='TRUE';
    'VSS_AA40':
      PIN_NUMBER='(0,0,0,0,0,0,0,0,0,0,0,0,0,0,0,0,0,0,0,0,0,0,0,0,0,0,0,0,0,AA4~
0,0,0,0,0,0,0,0,0,0,0)';
      PINUSE='POWER';
      NO_LOAD_CHECK='Both';
      NO_IO_CHECK='Both';
      NO_ASSERT_CHECK='TRUE';
      NO_DIR_CHECK='TRUE';
      ALLOW_CONNECT='TRUE';
    'VSS_AA41':
      PIN_NUMBER='(0,0,0,0,0,0,0,0,0,0,0,0,0,0,0,0,0,0,0,0,0,0,0,0,0,0,0,0,0,AA4~
1,0,0,0,0,0,0,0,0,0,0)';
      PINUSE='POWER';
      NO_LOAD_CHECK='Both';
      NO_IO_CHECK='Both';
      NO_ASSERT_CHECK='TRUE';
      NO_DIR_CHECK='TRUE';
      ALLOW_CONNECT='TRUE';
    'VSS_AA45':
      PIN_NUMBER='(0,0,0,0,0,0,0,0,0,0,0,0,0,0,0,0,0,0,0,0,0,0,0,0,0,0,0,0,0,AA4~
5,0,0,0,0,0,0,0,0,0,0)';
      PINUSE='POWER';
      NO_LOAD_CHECK='Both';
      NO_IO_CHECK='Both';
      NO_ASSERT_CHECK='TRUE';
      NO_DIR_CHECK='TRUE';
      ALLOW_CONNECT='TRUE';
    'VSS_AA56':
      PIN_NUMBER='(0,0,0,0,0,0,0,0,0,0,0,0,0,0,0,0,0,0,0,0,0,0,0,0,0,0,0,0,0,AA5~
6,0,0,0,0,0,0,0,0,0,0)';
      PINUSE='POWER';
      NO_LOAD_CHECK='Both';
      NO_IO_CHECK='Both';
      NO_ASSERT_CHECK='TRUE';
      NO_DIR_CHECK='TRUE';
      ALLOW_CONNECT='TRUE';
    'VSS_AA58':
      PIN_NUMBER='(0,0,0,0,0,0,0,0,0,0,0,0,0,0,0,0,0,0,0,0,0,0,0,0,0,0,0,0,0,AA5~
8,0,0,0,0,0,0,0,0,0,0)';
      PINUSE='POWER';
      NO_LOAD_CHECK='Both';
      NO_IO_CHECK='Both';
      NO_ASSERT_CHECK='TRUE';
      NO_DIR_CHECK='TRUE';
      ALLOW_CONNECT='TRUE';
    'VSS_AA61':
      PIN_NUMBER='(0,0,0,0,0,0,0,0,0,0,0,0,0,0,0,0,0,0,0,0,0,0,0,0,0,0,0,0,0,AA6~
1,0,0,0,0,0,0,0,0,0,0)';
      PINUSE='POWER';
      NO_LOAD_CHECK='Both';
      NO_IO_CHECK='Both';
      NO_ASSERT_CHECK='TRUE';
      NO_DIR_CHECK='TRUE';
      ALLOW_CONNECT='TRUE';
    'VSS_AA63':
      PIN_NUMBER='(0,0,0,0,0,0,0,0,0,0,0,0,0,0,0,0,0,0,0,0,0,0,0,0,0,0,0,0,0,AA6~
3,0,0,0,0,0,0,0,0,0,0)';
      PINUSE='POWER';
      NO_LOAD_CHECK='Both';
      NO_IO_CHECK='Both';
      NO_ASSERT_CHECK='TRUE';
      NO_DIR_CHECK='TRUE';
      ALLOW_CONNECT='TRUE';
    'VSS_AA65':
      PIN_NUMBER='(0,0,0,0,0,0,0,0,0,0,0,0,0,0,0,0,0,0,0,0,0,0,0,0,0,0,0,0,0,AA6~
5,0,0,0,0,0,0,0,0,0,0)';
      PINUSE='POWER';
      NO_LOAD_CHECK='Both';
      NO_IO_CHECK='Both';
      NO_ASSERT_CHECK='TRUE';
      NO_DIR_CHECK='TRUE';
      ALLOW_CONNECT='TRUE';
    'VSS_AA68':
      PIN_NUMBER='(0,0,0,0,0,0,0,0,0,0,0,0,0,0,0,0,0,0,0,0,0,0,0,0,0,0,0,0,0,AA6~
8,0,0,0,0,0,0,0,0,0,0)';
      PINUSE='POWER';
      NO_LOAD_CHECK='Both';
      NO_IO_CHECK='Both';
      NO_ASSERT_CHECK='TRUE';
      NO_DIR_CHECK='TRUE';
      ALLOW_CONNECT='TRUE';
    'VSS_AA70':
      PIN_NUMBER='(0,0,0,0,0,0,0,0,0,0,0,0,0,0,0,0,0,0,0,0,0,0,0,0,0,0,0,0,0,AA7~
0,0,0,0,0,0,0,0,0,0,0)';
      PINUSE='POWER';
      NO_LOAD_CHECK='Both';
      NO_IO_CHECK='Both';
      NO_ASSERT_CHECK='TRUE';
      NO_DIR_CHECK='TRUE';
      ALLOW_CONNECT='TRUE';
    'VSS_AA75':
      PIN_NUMBER='(0,0,0,0,0,0,0,0,0,0,0,0,0,0,0,0,0,0,0,0,0,0,0,0,0,0,0,0,0,AA7~
5,0,0,0,0,0,0,0,0,0,0)';
      PINUSE='POWER';
      NO_LOAD_CHECK='Both';
      NO_IO_CHECK='Both';
      NO_ASSERT_CHECK='TRUE';
      NO_DIR_CHECK='TRUE';
      ALLOW_CONNECT='TRUE';
    'VSS_AB3':
      PIN_NUMBER='(0,0,0,0,0,0,0,0,0,0,0,0,0,0,0,0,0,0,0,0,0,0,0,0,0,0,0,0,0,AB3~
,0,0,0,0,0,0,0,0,0,0)';
      PINUSE='POWER';
      NO_LOAD_CHECK='Both';
      NO_IO_CHECK='Both';
      NO_ASSERT_CHECK='TRUE';
      NO_DIR_CHECK='TRUE';
      ALLOW_CONNECT='TRUE';
    'VSS_AB5':
      PIN_NUMBER='(0,0,0,0,0,0,0,0,0,0,0,0,0,0,0,0,0,0,0,0,0,0,0,0,0,0,0,0,0,AB5~
,0,0,0,0,0,0,0,0,0,0)';
      PINUSE='POWER';
      NO_LOAD_CHECK='Both';
      NO_IO_CHECK='Both';
      NO_ASSERT_CHECK='TRUE';
      NO_DIR_CHECK='TRUE';
      ALLOW_CONNECT='TRUE';
    'VSS_AB8':
      PIN_NUMBER='(0,0,0,0,0,0,0,0,0,0,0,0,0,0,0,0,0,0,0,0,0,0,0,0,0,0,0,0,0,AB8~
,0,0,0,0,0,0,0,0,0,0)';
      PINUSE='POWER';
      NO_LOAD_CHECK='Both';
      NO_IO_CHECK='Both';
      NO_ASSERT_CHECK='TRUE';
      NO_DIR_CHECK='TRUE';
      ALLOW_CONNECT='TRUE';
    'VSS_AB10':
      PIN_NUMBER='(0,0,0,0,0,0,0,0,0,0,0,0,0,0,0,0,0,0,0,0,0,0,0,0,0,0,0,0,0,AB1~
0,0,0,0,0,0,0,0,0,0,0)';
      PINUSE='POWER';
      NO_LOAD_CHECK='Both';
      NO_IO_CHECK='Both';
      NO_ASSERT_CHECK='TRUE';
      NO_DIR_CHECK='TRUE';
      ALLOW_CONNECT='TRUE';
    'VSS_AB12':
      PIN_NUMBER='(0,0,0,0,0,0,0,0,0,0,0,0,0,0,0,0,0,0,0,0,0,0,0,0,0,0,0,0,0,AB1~
2,0,0,0,0,0,0,0,0,0,0)';
      PINUSE='POWER';
      NO_LOAD_CHECK='Both';
      NO_IO_CHECK='Both';
      NO_ASSERT_CHECK='TRUE';
      NO_DIR_CHECK='TRUE';
      ALLOW_CONNECT='TRUE';
    'VSS_AB15':
      PIN_NUMBER='(0,0,0,0,0,0,0,0,0,0,0,0,0,0,0,0,0,0,0,0,0,0,0,0,0,0,0,0,0,AB1~
5,0,0,0,0,0,0,0,0,0,0)';
      PINUSE='POWER';
      NO_LOAD_CHECK='Both';
      NO_IO_CHECK='Both';
      NO_ASSERT_CHECK='TRUE';
      NO_DIR_CHECK='TRUE';
      ALLOW_CONNECT='TRUE';
    'VSS_AB17':
      PIN_NUMBER='(0,0,0,0,0,0,0,0,0,0,0,0,0,0,0,0,0,0,0,0,0,0,0,0,0,0,0,0,0,AB1~
7,0,0,0,0,0,0,0,0,0,0)';
      PINUSE='POWER';
      NO_LOAD_CHECK='Both';
      NO_IO_CHECK='Both';
      NO_ASSERT_CHECK='TRUE';
      NO_DIR_CHECK='TRUE';
      ALLOW_CONNECT='TRUE';
    'VSS_AB19':
      PIN_NUMBER='(0,0,0,0,0,0,0,0,0,0,0,0,0,0,0,0,0,0,0,0,0,0,0,0,0,0,0,0,0,AB1~
9,0,0,0,0,0,0,0,0,0,0)';
      PINUSE='POWER';
      NO_LOAD_CHECK='Both';
      NO_IO_CHECK='Both';
      NO_ASSERT_CHECK='TRUE';
      NO_DIR_CHECK='TRUE';
      ALLOW_CONNECT='TRUE';
    'VSS_AB22':
      PIN_NUMBER='(0,0,0,0,0,0,0,0,0,0,0,0,0,0,0,0,0,0,0,0,0,0,0,0,0,0,0,0,0,AB2~
2,0,0,0,0,0,0,0,0,0,0)';
      PINUSE='POWER';
      NO_LOAD_CHECK='Both';
      NO_IO_CHECK='Both';
      NO_ASSERT_CHECK='TRUE';
      NO_DIR_CHECK='TRUE';
      ALLOW_CONNECT='TRUE';
    'VSS_AB25':
      PIN_NUMBER='(0,0,0,0,0,0,0,0,0,0,0,0,0,0,0,0,0,0,0,0,0,0,0,0,0,0,0,0,0,AB2~
5,0,0,0,0,0,0,0,0,0,0)';
      PINUSE='POWER';
      NO_LOAD_CHECK='Both';
      NO_IO_CHECK='Both';
      NO_ASSERT_CHECK='TRUE';
      NO_DIR_CHECK='TRUE';
      ALLOW_CONNECT='TRUE';
    'VSS_AB28':
      PIN_NUMBER='(0,0,0,0,0,0,0,0,0,0,0,0,0,0,0,0,0,0,0,0,0,0,0,0,0,0,0,0,0,AB2~
8,0,0,0,0,0,0,0,0,0,0)';
      PINUSE='POWER';
      NO_LOAD_CHECK='Both';
      NO_IO_CHECK='Both';
      NO_ASSERT_CHECK='TRUE';
      NO_DIR_CHECK='TRUE';
      ALLOW_CONNECT='TRUE';
    'VSS_AB31':
      PIN_NUMBER='(0,0,0,0,0,0,0,0,0,0,0,0,0,0,0,0,0,0,0,0,0,0,0,0,0,0,0,0,0,AB3~
1,0,0,0,0,0,0,0,0,0,0)';
      PINUSE='POWER';
      NO_LOAD_CHECK='Both';
      NO_IO_CHECK='Both';
      NO_ASSERT_CHECK='TRUE';
      NO_DIR_CHECK='TRUE';
      ALLOW_CONNECT='TRUE';
    'VSS_AB34':
      PIN_NUMBER='(0,0,0,0,0,0,0,0,0,0,0,0,0,0,0,0,0,0,0,0,0,0,0,0,0,0,0,0,0,AB3~
4,0,0,0,0,0,0,0,0,0,0)';
      PINUSE='POWER';
      NO_LOAD_CHECK='Both';
      NO_IO_CHECK='Both';
      NO_ASSERT_CHECK='TRUE';
      NO_DIR_CHECK='TRUE';
      ALLOW_CONNECT='TRUE';
    'VSS_AB37':
      PIN_NUMBER='(0,0,0,0,0,0,0,0,0,0,0,0,0,0,0,0,0,0,0,0,0,0,0,0,0,0,0,0,0,AB3~
7,0,0,0,0,0,0,0,0,0,0)';
      PINUSE='POWER';
      NO_LOAD_CHECK='Both';
      NO_IO_CHECK='Both';
      NO_ASSERT_CHECK='TRUE';
      NO_DIR_CHECK='TRUE';
      ALLOW_CONNECT='TRUE';
    'VSS_AB39':
      PIN_NUMBER='(0,0,0,0,0,0,0,0,0,0,0,0,0,0,0,0,0,0,0,0,0,0,0,0,0,0,0,0,0,AB3~
9,0,0,0,0,0,0,0,0,0,0)';
      PINUSE='POWER';
      NO_LOAD_CHECK='Both';
      NO_IO_CHECK='Both';
      NO_ASSERT_CHECK='TRUE';
      NO_DIR_CHECK='TRUE';
      ALLOW_CONNECT='TRUE';
    'VSS_AB42':
      PIN_NUMBER='(0,0,0,0,0,0,0,0,0,0,0,0,0,0,0,0,0,0,0,0,0,0,0,0,0,0,0,0,0,AB4~
2,0,0,0,0,0,0,0,0,0,0)';
      PINUSE='POWER';
      NO_LOAD_CHECK='Both';
      NO_IO_CHECK='Both';
      NO_ASSERT_CHECK='TRUE';
      NO_DIR_CHECK='TRUE';
      ALLOW_CONNECT='TRUE';
    'VSS_AB45':
      PIN_NUMBER='(0,0,0,0,0,0,0,0,0,0,0,0,0,0,0,0,0,0,0,0,0,0,0,0,0,0,0,0,0,AB4~
5,0,0,0,0,0,0,0,0,0,0)';
      PINUSE='POWER';
      NO_LOAD_CHECK='Both';
      NO_IO_CHECK='Both';
      NO_ASSERT_CHECK='TRUE';
      NO_DIR_CHECK='TRUE';
      ALLOW_CONNECT='TRUE';
    'VSS_AB48':
      PIN_NUMBER='(0,0,0,0,0,0,0,0,0,0,0,0,0,0,0,0,0,0,0,0,0,0,0,0,0,0,0,0,0,AB4~
8,0,0,0,0,0,0,0,0,0,0)';
      PINUSE='POWER';
      NO_LOAD_CHECK='Both';
      NO_IO_CHECK='Both';
      NO_ASSERT_CHECK='TRUE';
      NO_DIR_CHECK='TRUE';
      ALLOW_CONNECT='TRUE';
    'VSS_AB51':
      PIN_NUMBER='(0,0,0,0,0,0,0,0,0,0,0,0,0,0,0,0,0,0,0,0,0,0,0,0,0,0,0,0,0,AB5~
1,0,0,0,0,0,0,0,0,0,0)';
      PINUSE='POWER';
      NO_LOAD_CHECK='Both';
      NO_IO_CHECK='Both';
      NO_ASSERT_CHECK='TRUE';
      NO_DIR_CHECK='TRUE';
      ALLOW_CONNECT='TRUE';
    'VSS_AB54':
      PIN_NUMBER='(0,0,0,0,0,0,0,0,0,0,0,0,0,0,0,0,0,0,0,0,0,0,0,0,0,0,0,0,0,AB5~
4,0,0,0,0,0,0,0,0,0,0)';
      PINUSE='POWER';
      NO_LOAD_CHECK='Both';
      NO_IO_CHECK='Both';
      NO_ASSERT_CHECK='TRUE';
      NO_DIR_CHECK='TRUE';
      ALLOW_CONNECT='TRUE';
    'VSS_AB57':
      PIN_NUMBER='(0,0,0,0,0,0,0,0,0,0,0,0,0,0,0,0,0,0,0,0,0,0,0,0,0,0,0,0,0,AB5~
7,0,0,0,0,0,0,0,0,0,0)';
      PINUSE='POWER';
      NO_LOAD_CHECK='Both';
      NO_IO_CHECK='Both';
      NO_ASSERT_CHECK='TRUE';
      NO_DIR_CHECK='TRUE';
      ALLOW_CONNECT='TRUE';
    'VSS_AB59':
      PIN_NUMBER='(0,0,0,0,0,0,0,0,0,0,0,0,0,0,0,0,0,0,0,0,0,0,0,0,0,0,0,0,0,AB5~
9,0,0,0,0,0,0,0,0,0,0)';
      PINUSE='POWER';
      NO_LOAD_CHECK='Both';
      NO_IO_CHECK='Both';
      NO_ASSERT_CHECK='TRUE';
      NO_DIR_CHECK='TRUE';
      ALLOW_CONNECT='TRUE';
    'VSS_AB61':
      PIN_NUMBER='(0,0,0,0,0,0,0,0,0,0,0,0,0,0,0,0,0,0,0,0,0,0,0,0,0,0,0,0,0,AB6~
1,0,0,0,0,0,0,0,0,0,0)';
      PINUSE='POWER';
      NO_LOAD_CHECK='Both';
      NO_IO_CHECK='Both';
      NO_ASSERT_CHECK='TRUE';
      NO_DIR_CHECK='TRUE';
      ALLOW_CONNECT='TRUE';
    'VSS_AB64':
      PIN_NUMBER='(0,0,0,0,0,0,0,0,0,0,0,0,0,0,0,0,0,0,0,0,0,0,0,0,0,0,0,0,0,AB6~
4,0,0,0,0,0,0,0,0,0,0)';
      PINUSE='POWER';
      NO_LOAD_CHECK='Both';
      NO_IO_CHECK='Both';
      NO_ASSERT_CHECK='TRUE';
      NO_DIR_CHECK='TRUE';
      ALLOW_CONNECT='TRUE';
    'VSS_AB66':
      PIN_NUMBER='(0,0,0,0,0,0,0,0,0,0,0,0,0,0,0,0,0,0,0,0,0,0,0,0,0,0,0,0,0,AB6~
6,0,0,0,0,0,0,0,0,0,0)';
      PINUSE='POWER';
      NO_LOAD_CHECK='Both';
      NO_IO_CHECK='Both';
      NO_ASSERT_CHECK='TRUE';
      NO_DIR_CHECK='TRUE';
      ALLOW_CONNECT='TRUE';
    'VSS_AK10':
      PIN_NUMBER='(0,0,0,0,0,0,0,0,0,0,0,0,0,0,0,0,0,0,0,0,0,0,0,0,0,0,0,0,0,0,A~
K10,0,0,0,0,0,0,0,0,0)';
      PINUSE='POWER';
      NO_LOAD_CHECK='Both';
      NO_IO_CHECK='Both';
      NO_ASSERT_CHECK='TRUE';
      NO_DIR_CHECK='TRUE';
      ALLOW_CONNECT='TRUE';
    'VSS_AK12':
      PIN_NUMBER='(0,0,0,0,0,0,0,0,0,0,0,0,0,0,0,0,0,0,0,0,0,0,0,0,0,0,0,0,0,0,A~
K12,0,0,0,0,0,0,0,0,0)';
      PINUSE='POWER';
      NO_LOAD_CHECK='Both';
      NO_IO_CHECK='Both';
      NO_ASSERT_CHECK='TRUE';
      NO_DIR_CHECK='TRUE';
      ALLOW_CONNECT='TRUE';
    'VSS_AK15':
      PIN_NUMBER='(0,0,0,0,0,0,0,0,0,0,0,0,0,0,0,0,0,0,0,0,0,0,0,0,0,0,0,0,0,0,A~
K15,0,0,0,0,0,0,0,0,0)';
      PINUSE='POWER';
      NO_LOAD_CHECK='Both';
      NO_IO_CHECK='Both';
      NO_ASSERT_CHECK='TRUE';
      NO_DIR_CHECK='TRUE';
      ALLOW_CONNECT='TRUE';
    'VSS_AK17':
      PIN_NUMBER='(0,0,0,0,0,0,0,0,0,0,0,0,0,0,0,0,0,0,0,0,0,0,0,0,0,0,0,0,0,0,A~
K17,0,0,0,0,0,0,0,0,0)';
      PINUSE='POWER';
      NO_LOAD_CHECK='Both';
      NO_IO_CHECK='Both';
      NO_ASSERT_CHECK='TRUE';
      NO_DIR_CHECK='TRUE';
      ALLOW_CONNECT='TRUE';
    'VSS_AK19':
      PIN_NUMBER='(0,0,0,0,0,0,0,0,0,0,0,0,0,0,0,0,0,0,0,0,0,0,0,0,0,0,0,0,0,0,A~
K19,0,0,0,0,0,0,0,0,0)';
      PINUSE='POWER';
      NO_LOAD_CHECK='Both';
      NO_IO_CHECK='Both';
      NO_ASSERT_CHECK='TRUE';
      NO_DIR_CHECK='TRUE';
      ALLOW_CONNECT='TRUE';
    'VSS_AK22':
      PIN_NUMBER='(0,0,0,0,0,0,0,0,0,0,0,0,0,0,0,0,0,0,0,0,0,0,0,0,0,0,0,0,0,0,A~
K22,0,0,0,0,0,0,0,0,0)';
      PINUSE='POWER';
      NO_LOAD_CHECK='Both';
      NO_IO_CHECK='Both';
      NO_ASSERT_CHECK='TRUE';
      NO_DIR_CHECK='TRUE';
      ALLOW_CONNECT='TRUE';
    'VSS_AK25':
      PIN_NUMBER='(0,0,0,0,0,0,0,0,0,0,0,0,0,0,0,0,0,0,0,0,0,0,0,0,0,0,0,0,0,0,A~
K25,0,0,0,0,0,0,0,0,0)';
      PINUSE='POWER';
      NO_LOAD_CHECK='Both';
      NO_IO_CHECK='Both';
      NO_ASSERT_CHECK='TRUE';
      NO_DIR_CHECK='TRUE';
      ALLOW_CONNECT='TRUE';
    'VSS_AK28':
      PIN_NUMBER='(0,0,0,0,0,0,0,0,0,0,0,0,0,0,0,0,0,0,0,0,0,0,0,0,0,0,0,0,0,0,A~
K28,0,0,0,0,0,0,0,0,0)';
      PINUSE='POWER';
      NO_LOAD_CHECK='Both';
      NO_IO_CHECK='Both';
      NO_ASSERT_CHECK='TRUE';
      NO_DIR_CHECK='TRUE';
      ALLOW_CONNECT='TRUE';
    'VSS_AK31':
      PIN_NUMBER='(0,0,0,0,0,0,0,0,0,0,0,0,0,0,0,0,0,0,0,0,0,0,0,0,0,0,0,0,0,0,A~
K31,0,0,0,0,0,0,0,0,0)';
      PINUSE='POWER';
      NO_LOAD_CHECK='Both';
      NO_IO_CHECK='Both';
      NO_ASSERT_CHECK='TRUE';
      NO_DIR_CHECK='TRUE';
      ALLOW_CONNECT='TRUE';
    'VSS_AK34':
      PIN_NUMBER='(0,0,0,0,0,0,0,0,0,0,0,0,0,0,0,0,0,0,0,0,0,0,0,0,0,0,0,0,0,0,A~
K34,0,0,0,0,0,0,0,0,0)';
      PINUSE='POWER';
      NO_LOAD_CHECK='Both';
      NO_IO_CHECK='Both';
      NO_ASSERT_CHECK='TRUE';
      NO_DIR_CHECK='TRUE';
      ALLOW_CONNECT='TRUE';
    'VSS_AK37':
      PIN_NUMBER='(0,0,0,0,0,0,0,0,0,0,0,0,0,0,0,0,0,0,0,0,0,0,0,0,0,0,0,0,0,0,A~
K37,0,0,0,0,0,0,0,0,0)';
      PINUSE='POWER';
      NO_LOAD_CHECK='Both';
      NO_IO_CHECK='Both';
      NO_ASSERT_CHECK='TRUE';
      NO_DIR_CHECK='TRUE';
      ALLOW_CONNECT='TRUE';
    'VSS_AK39':
      PIN_NUMBER='(0,0,0,0,0,0,0,0,0,0,0,0,0,0,0,0,0,0,0,0,0,0,0,0,0,0,0,0,0,0,A~
K39,0,0,0,0,0,0,0,0,0)';
      PINUSE='POWER';
      NO_LOAD_CHECK='Both';
      NO_IO_CHECK='Both';
      NO_ASSERT_CHECK='TRUE';
      NO_DIR_CHECK='TRUE';
      ALLOW_CONNECT='TRUE';
    'VSS_AK42':
      PIN_NUMBER='(0,0,0,0,0,0,0,0,0,0,0,0,0,0,0,0,0,0,0,0,0,0,0,0,0,0,0,0,0,0,A~
K42,0,0,0,0,0,0,0,0,0)';
      PINUSE='POWER';
      NO_LOAD_CHECK='Both';
      NO_IO_CHECK='Both';
      NO_ASSERT_CHECK='TRUE';
      NO_DIR_CHECK='TRUE';
      ALLOW_CONNECT='TRUE';
    'VSS_AK45':
      PIN_NUMBER='(0,0,0,0,0,0,0,0,0,0,0,0,0,0,0,0,0,0,0,0,0,0,0,0,0,0,0,0,0,0,A~
K45,0,0,0,0,0,0,0,0,0)';
      PINUSE='POWER';
      NO_LOAD_CHECK='Both';
      NO_IO_CHECK='Both';
      NO_ASSERT_CHECK='TRUE';
      NO_DIR_CHECK='TRUE';
      ALLOW_CONNECT='TRUE';
    'VSS_AK48':
      PIN_NUMBER='(0,0,0,0,0,0,0,0,0,0,0,0,0,0,0,0,0,0,0,0,0,0,0,0,0,0,0,0,0,0,A~
K48,0,0,0,0,0,0,0,0,0)';
      PINUSE='POWER';
      NO_LOAD_CHECK='Both';
      NO_IO_CHECK='Both';
      NO_ASSERT_CHECK='TRUE';
      NO_DIR_CHECK='TRUE';
      ALLOW_CONNECT='TRUE';
    'VSS_AK51':
      PIN_NUMBER='(0,0,0,0,0,0,0,0,0,0,0,0,0,0,0,0,0,0,0,0,0,0,0,0,0,0,0,0,0,0,A~
K51,0,0,0,0,0,0,0,0,0)';
      PINUSE='POWER';
      NO_LOAD_CHECK='Both';
      NO_IO_CHECK='Both';
      NO_ASSERT_CHECK='TRUE';
      NO_DIR_CHECK='TRUE';
      ALLOW_CONNECT='TRUE';
    'VSS_AK54':
      PIN_NUMBER='(0,0,0,0,0,0,0,0,0,0,0,0,0,0,0,0,0,0,0,0,0,0,0,0,0,0,0,0,0,0,A~
K54,0,0,0,0,0,0,0,0,0)';
      PINUSE='POWER';
      NO_LOAD_CHECK='Both';
      NO_IO_CHECK='Both';
      NO_ASSERT_CHECK='TRUE';
      NO_DIR_CHECK='TRUE';
      ALLOW_CONNECT='TRUE';
    'VSS_AK57':
      PIN_NUMBER='(0,0,0,0,0,0,0,0,0,0,0,0,0,0,0,0,0,0,0,0,0,0,0,0,0,0,0,0,0,0,A~
K57,0,0,0,0,0,0,0,0,0)';
      PINUSE='POWER';
      NO_LOAD_CHECK='Both';
      NO_IO_CHECK='Both';
      NO_ASSERT_CHECK='TRUE';
      NO_DIR_CHECK='TRUE';
      ALLOW_CONNECT='TRUE';
    'VSS_AK59':
      PIN_NUMBER='(0,0,0,0,0,0,0,0,0,0,0,0,0,0,0,0,0,0,0,0,0,0,0,0,0,0,0,0,0,0,A~
K59,0,0,0,0,0,0,0,0,0)';
      PINUSE='POWER';
      NO_LOAD_CHECK='Both';
      NO_IO_CHECK='Both';
      NO_ASSERT_CHECK='TRUE';
      NO_DIR_CHECK='TRUE';
      ALLOW_CONNECT='TRUE';
    'VSS_AK61':
      PIN_NUMBER='(0,0,0,0,0,0,0,0,0,0,0,0,0,0,0,0,0,0,0,0,0,0,0,0,0,0,0,0,0,0,A~
K61,0,0,0,0,0,0,0,0,0)';
      PINUSE='POWER';
      NO_LOAD_CHECK='Both';
      NO_IO_CHECK='Both';
      NO_ASSERT_CHECK='TRUE';
      NO_DIR_CHECK='TRUE';
      ALLOW_CONNECT='TRUE';
    'VSS_AK64':
      PIN_NUMBER='(0,0,0,0,0,0,0,0,0,0,0,0,0,0,0,0,0,0,0,0,0,0,0,0,0,0,0,0,0,0,A~
K64,0,0,0,0,0,0,0,0,0)';
      PINUSE='POWER';
      NO_LOAD_CHECK='Both';
      NO_IO_CHECK='Both';
      NO_ASSERT_CHECK='TRUE';
      NO_DIR_CHECK='TRUE';
      ALLOW_CONNECT='TRUE';
    'VSS_AK66':
      PIN_NUMBER='(0,0,0,0,0,0,0,0,0,0,0,0,0,0,0,0,0,0,0,0,0,0,0,0,0,0,0,0,0,0,A~
K66,0,0,0,0,0,0,0,0,0)';
      PINUSE='POWER';
      NO_LOAD_CHECK='Both';
      NO_IO_CHECK='Both';
      NO_ASSERT_CHECK='TRUE';
      NO_DIR_CHECK='TRUE';
      ALLOW_CONNECT='TRUE';
    'VSS_AK68':
      PIN_NUMBER='(0,0,0,0,0,0,0,0,0,0,0,0,0,0,0,0,0,0,0,0,0,0,0,0,0,0,0,0,0,0,A~
K68,0,0,0,0,0,0,0,0,0)';
      PINUSE='POWER';
      NO_LOAD_CHECK='Both';
      NO_IO_CHECK='Both';
      NO_ASSERT_CHECK='TRUE';
      NO_DIR_CHECK='TRUE';
      ALLOW_CONNECT='TRUE';
    'VSS_AK71':
      PIN_NUMBER='(0,0,0,0,0,0,0,0,0,0,0,0,0,0,0,0,0,0,0,0,0,0,0,0,0,0,0,0,0,0,A~
K71,0,0,0,0,0,0,0,0,0)';
      PINUSE='POWER';
      NO_LOAD_CHECK='Both';
      NO_IO_CHECK='Both';
      NO_ASSERT_CHECK='TRUE';
      NO_DIR_CHECK='TRUE';
      ALLOW_CONNECT='TRUE';
    'VSS_AK73':
      PIN_NUMBER='(0,0,0,0,0,0,0,0,0,0,0,0,0,0,0,0,0,0,0,0,0,0,0,0,0,0,0,0,0,0,A~
K73,0,0,0,0,0,0,0,0,0)';
      PINUSE='POWER';
      NO_LOAD_CHECK='Both';
      NO_IO_CHECK='Both';
      NO_ASSERT_CHECK='TRUE';
      NO_DIR_CHECK='TRUE';
      ALLOW_CONNECT='TRUE';
    'VSS_AL1':
      PIN_NUMBER='(0,0,0,0,0,0,0,0,0,0,0,0,0,0,0,0,0,0,0,0,0,0,0,0,0,0,0,0,0,0,A~
L1,0,0,0,0,0,0,0,0,0)';
      PINUSE='POWER';
      NO_LOAD_CHECK='Both';
      NO_IO_CHECK='Both';
      NO_ASSERT_CHECK='TRUE';
      NO_DIR_CHECK='TRUE';
      ALLOW_CONNECT='TRUE';
    'VSS_AL4':
      PIN_NUMBER='(0,0,0,0,0,0,0,0,0,0,0,0,0,0,0,0,0,0,0,0,0,0,0,0,0,0,0,0,0,0,A~
L4,0,0,0,0,0,0,0,0,0)';
      PINUSE='POWER';
      NO_LOAD_CHECK='Both';
      NO_IO_CHECK='Both';
      NO_ASSERT_CHECK='TRUE';
      NO_DIR_CHECK='TRUE';
      ALLOW_CONNECT='TRUE';
    'VSS_AL6':
      PIN_NUMBER='(0,0,0,0,0,0,0,0,0,0,0,0,0,0,0,0,0,0,0,0,0,0,0,0,0,0,0,0,0,0,A~
L6,0,0,0,0,0,0,0,0,0)';
      PINUSE='POWER';
      NO_LOAD_CHECK='Both';
      NO_IO_CHECK='Both';
      NO_ASSERT_CHECK='TRUE';
      NO_DIR_CHECK='TRUE';
      ALLOW_CONNECT='TRUE';
    'VSS_AL8':
      PIN_NUMBER='(0,0,0,0,0,0,0,0,0,0,0,0,0,0,0,0,0,0,0,0,0,0,0,0,0,0,0,0,0,0,A~
L8,0,0,0,0,0,0,0,0,0)';
      PINUSE='POWER';
      NO_LOAD_CHECK='Both';
      NO_IO_CHECK='Both';
      NO_ASSERT_CHECK='TRUE';
      NO_DIR_CHECK='TRUE';
      ALLOW_CONNECT='TRUE';
    'VSS_AL11':
      PIN_NUMBER='(0,0,0,0,0,0,0,0,0,0,0,0,0,0,0,0,0,0,0,0,0,0,0,0,0,0,0,0,0,0,A~
L11,0,0,0,0,0,0,0,0,0)';
      PINUSE='POWER';
      NO_LOAD_CHECK='Both';
      NO_IO_CHECK='Both';
      NO_ASSERT_CHECK='TRUE';
      NO_DIR_CHECK='TRUE';
      ALLOW_CONNECT='TRUE';
    'VSS_AL13':
      PIN_NUMBER='(0,0,0,0,0,0,0,0,0,0,0,0,0,0,0,0,0,0,0,0,0,0,0,0,0,0,0,0,0,0,A~
L13,0,0,0,0,0,0,0,0,0)';
      PINUSE='POWER';
      NO_LOAD_CHECK='Both';
      NO_IO_CHECK='Both';
      NO_ASSERT_CHECK='TRUE';
      NO_DIR_CHECK='TRUE';
      ALLOW_CONNECT='TRUE';
    'VSS_AL15':
      PIN_NUMBER='(0,0,0,0,0,0,0,0,0,0,0,0,0,0,0,0,0,0,0,0,0,0,0,0,0,0,0,0,0,0,A~
L15,0,0,0,0,0,0,0,0,0)';
      PINUSE='POWER';
      NO_LOAD_CHECK='Both';
      NO_IO_CHECK='Both';
      NO_ASSERT_CHECK='TRUE';
      NO_DIR_CHECK='TRUE';
      ALLOW_CONNECT='TRUE';
    'VSS_AL18':
      PIN_NUMBER='(0,0,0,0,0,0,0,0,0,0,0,0,0,0,0,0,0,0,0,0,0,0,0,0,0,0,0,0,0,0,A~
L18,0,0,0,0,0,0,0,0,0)';
      PINUSE='POWER';
      NO_LOAD_CHECK='Both';
      NO_IO_CHECK='Both';
      NO_ASSERT_CHECK='TRUE';
      NO_DIR_CHECK='TRUE';
      ALLOW_CONNECT='TRUE';
    'VSS_AL20':
      PIN_NUMBER='(0,0,0,0,0,0,0,0,0,0,0,0,0,0,0,0,0,0,0,0,0,0,0,0,0,0,0,0,0,0,A~
L20,0,0,0,0,0,0,0,0,0)';
      PINUSE='POWER';
      NO_LOAD_CHECK='Both';
      NO_IO_CHECK='Both';
      NO_ASSERT_CHECK='TRUE';
      NO_DIR_CHECK='TRUE';
      ALLOW_CONNECT='TRUE';
    'VSS_AL22':
      PIN_NUMBER='(0,0,0,0,0,0,0,0,0,0,0,0,0,0,0,0,0,0,0,0,0,0,0,0,0,0,0,0,0,0,A~
L22,0,0,0,0,0,0,0,0,0)';
      PINUSE='POWER';
      NO_LOAD_CHECK='Both';
      NO_IO_CHECK='Both';
      NO_ASSERT_CHECK='TRUE';
      NO_DIR_CHECK='TRUE';
      ALLOW_CONNECT='TRUE';
    'VSS_AL25':
      PIN_NUMBER='(0,0,0,0,0,0,0,0,0,0,0,0,0,0,0,0,0,0,0,0,0,0,0,0,0,0,0,0,0,0,A~
L25,0,0,0,0,0,0,0,0,0)';
      PINUSE='POWER';
      NO_LOAD_CHECK='Both';
      NO_IO_CHECK='Both';
      NO_ASSERT_CHECK='TRUE';
      NO_DIR_CHECK='TRUE';
      ALLOW_CONNECT='TRUE';
    'VSS_AL28':
      PIN_NUMBER='(0,0,0,0,0,0,0,0,0,0,0,0,0,0,0,0,0,0,0,0,0,0,0,0,0,0,0,0,0,0,A~
L28,0,0,0,0,0,0,0,0,0)';
      PINUSE='POWER';
      NO_LOAD_CHECK='Both';
      NO_IO_CHECK='Both';
      NO_ASSERT_CHECK='TRUE';
      NO_DIR_CHECK='TRUE';
      ALLOW_CONNECT='TRUE';
    'VSS_AL31':
      PIN_NUMBER='(0,0,0,0,0,0,0,0,0,0,0,0,0,0,0,0,0,0,0,0,0,0,0,0,0,0,0,0,0,0,A~
L31,0,0,0,0,0,0,0,0,0)';
      PINUSE='POWER';
      NO_LOAD_CHECK='Both';
      NO_IO_CHECK='Both';
      NO_ASSERT_CHECK='TRUE';
      NO_DIR_CHECK='TRUE';
      ALLOW_CONNECT='TRUE';
    'VSS_AL34':
      PIN_NUMBER='(0,0,0,0,0,0,0,0,0,0,0,0,0,0,0,0,0,0,0,0,0,0,0,0,0,0,0,0,0,0,A~
L34,0,0,0,0,0,0,0,0,0)';
      PINUSE='POWER';
      NO_LOAD_CHECK='Both';
      NO_IO_CHECK='Both';
      NO_ASSERT_CHECK='TRUE';
      NO_DIR_CHECK='TRUE';
      ALLOW_CONNECT='TRUE';
    'VSS_AL42':
      PIN_NUMBER='(0,0,0,0,0,0,0,0,0,0,0,0,0,0,0,0,0,0,0,0,0,0,0,0,0,0,0,0,0,0,A~
L42,0,0,0,0,0,0,0,0,0)';
      PINUSE='POWER';
      NO_LOAD_CHECK='Both';
      NO_IO_CHECK='Both';
      NO_ASSERT_CHECK='TRUE';
      NO_DIR_CHECK='TRUE';
      ALLOW_CONNECT='TRUE';
    'VSS_AL45':
      PIN_NUMBER='(0,0,0,0,0,0,0,0,0,0,0,0,0,0,0,0,0,0,0,0,0,0,0,0,0,0,0,0,0,0,A~
L45,0,0,0,0,0,0,0,0,0)';
      PINUSE='POWER';
      NO_LOAD_CHECK='Both';
      NO_IO_CHECK='Both';
      NO_ASSERT_CHECK='TRUE';
      NO_DIR_CHECK='TRUE';
      ALLOW_CONNECT='TRUE';
    'VSS_AL48':
      PIN_NUMBER='(0,0,0,0,0,0,0,0,0,0,0,0,0,0,0,0,0,0,0,0,0,0,0,0,0,0,0,0,0,0,A~
L48,0,0,0,0,0,0,0,0,0)';
      PINUSE='POWER';
      NO_LOAD_CHECK='Both';
      NO_IO_CHECK='Both';
      NO_ASSERT_CHECK='TRUE';
      NO_DIR_CHECK='TRUE';
      ALLOW_CONNECT='TRUE';
    'VSS_AL51':
      PIN_NUMBER='(0,0,0,0,0,0,0,0,0,0,0,0,0,0,0,0,0,0,0,0,0,0,0,0,0,0,0,0,0,0,A~
L51,0,0,0,0,0,0,0,0,0)';
      PINUSE='POWER';
      NO_LOAD_CHECK='Both';
      NO_IO_CHECK='Both';
      NO_ASSERT_CHECK='TRUE';
      NO_DIR_CHECK='TRUE';
      ALLOW_CONNECT='TRUE';
    'VSS_AL54':
      PIN_NUMBER='(0,0,0,0,0,0,0,0,0,0,0,0,0,0,0,0,0,0,0,0,0,0,0,0,0,0,0,0,0,0,A~
L54,0,0,0,0,0,0,0,0,0)';
      PINUSE='POWER';
      NO_LOAD_CHECK='Both';
      NO_IO_CHECK='Both';
      NO_ASSERT_CHECK='TRUE';
      NO_DIR_CHECK='TRUE';
      ALLOW_CONNECT='TRUE';
    'VSS_AL56':
      PIN_NUMBER='(0,0,0,0,0,0,0,0,0,0,0,0,0,0,0,0,0,0,0,0,0,0,0,0,0,0,0,0,0,0,A~
L56,0,0,0,0,0,0,0,0,0)';
      PINUSE='POWER';
      NO_LOAD_CHECK='Both';
      NO_IO_CHECK='Both';
      NO_ASSERT_CHECK='TRUE';
      NO_DIR_CHECK='TRUE';
      ALLOW_CONNECT='TRUE';
    'VSS_AL58':
      PIN_NUMBER='(0,0,0,0,0,0,0,0,0,0,0,0,0,0,0,0,0,0,0,0,0,0,0,0,0,0,0,0,0,0,A~
L58,0,0,0,0,0,0,0,0,0)';
      PINUSE='POWER';
      NO_LOAD_CHECK='Both';
      NO_IO_CHECK='Both';
      NO_ASSERT_CHECK='TRUE';
      NO_DIR_CHECK='TRUE';
      ALLOW_CONNECT='TRUE';
    'VSS_AL61':
      PIN_NUMBER='(0,0,0,0,0,0,0,0,0,0,0,0,0,0,0,0,0,0,0,0,0,0,0,0,0,0,0,0,0,0,A~
L61,0,0,0,0,0,0,0,0,0)';
      PINUSE='POWER';
      NO_LOAD_CHECK='Both';
      NO_IO_CHECK='Both';
      NO_ASSERT_CHECK='TRUE';
      NO_DIR_CHECK='TRUE';
      ALLOW_CONNECT='TRUE';
    'VSS_AL63':
      PIN_NUMBER='(0,0,0,0,0,0,0,0,0,0,0,0,0,0,0,0,0,0,0,0,0,0,0,0,0,0,0,0,0,0,A~
L63,0,0,0,0,0,0,0,0,0)';
      PINUSE='POWER';
      NO_LOAD_CHECK='Both';
      NO_IO_CHECK='Both';
      NO_ASSERT_CHECK='TRUE';
      NO_DIR_CHECK='TRUE';
      ALLOW_CONNECT='TRUE';
    'VSS_AL65':
      PIN_NUMBER='(0,0,0,0,0,0,0,0,0,0,0,0,0,0,0,0,0,0,0,0,0,0,0,0,0,0,0,0,0,0,A~
L65,0,0,0,0,0,0,0,0,0)';
      PINUSE='POWER';
      NO_LOAD_CHECK='Both';
      NO_IO_CHECK='Both';
      NO_ASSERT_CHECK='TRUE';
      NO_DIR_CHECK='TRUE';
      ALLOW_CONNECT='TRUE';
    'VSS_AL68':
      PIN_NUMBER='(0,0,0,0,0,0,0,0,0,0,0,0,0,0,0,0,0,0,0,0,0,0,0,0,0,0,0,0,0,0,A~
L68,0,0,0,0,0,0,0,0,0)';
      PINUSE='POWER';
      NO_LOAD_CHECK='Both';
      NO_IO_CHECK='Both';
      NO_ASSERT_CHECK='TRUE';
      NO_DIR_CHECK='TRUE';
      ALLOW_CONNECT='TRUE';
    'VSS_AL70':
      PIN_NUMBER='(0,0,0,0,0,0,0,0,0,0,0,0,0,0,0,0,0,0,0,0,0,0,0,0,0,0,0,0,0,0,A~
L70,0,0,0,0,0,0,0,0,0)';
      PINUSE='POWER';
      NO_LOAD_CHECK='Both';
      NO_IO_CHECK='Both';
      NO_ASSERT_CHECK='TRUE';
      NO_DIR_CHECK='TRUE';
      ALLOW_CONNECT='TRUE';
    'VSS_AL72':
      PIN_NUMBER='(0,0,0,0,0,0,0,0,0,0,0,0,0,0,0,0,0,0,0,0,0,0,0,0,0,0,0,0,0,0,A~
L72,0,0,0,0,0,0,0,0,0)';
      PINUSE='POWER';
      NO_LOAD_CHECK='Both';
      NO_IO_CHECK='Both';
      NO_ASSERT_CHECK='TRUE';
      NO_DIR_CHECK='TRUE';
      ALLOW_CONNECT='TRUE';
    'VSS_AL75':
      PIN_NUMBER='(0,0,0,0,0,0,0,0,0,0,0,0,0,0,0,0,0,0,0,0,0,0,0,0,0,0,0,0,0,0,A~
L75,0,0,0,0,0,0,0,0,0)';
      PINUSE='POWER';
      NO_LOAD_CHECK='Both';
      NO_IO_CHECK='Both';
      NO_ASSERT_CHECK='TRUE';
      NO_DIR_CHECK='TRUE';
      ALLOW_CONNECT='TRUE';
    'VSS_AM3':
      PIN_NUMBER='(0,0,0,0,0,0,0,0,0,0,0,0,0,0,0,0,0,0,0,0,0,0,0,0,0,0,0,0,0,0,A~
M3,0,0,0,0,0,0,0,0,0)';
      PINUSE='POWER';
      NO_LOAD_CHECK='Both';
      NO_IO_CHECK='Both';
      NO_ASSERT_CHECK='TRUE';
      NO_DIR_CHECK='TRUE';
      ALLOW_CONNECT='TRUE';
    'VSS_AM8':
      PIN_NUMBER='(0,0,0,0,0,0,0,0,0,0,0,0,0,0,0,0,0,0,0,0,0,0,0,0,0,0,0,0,0,0,A~
M8,0,0,0,0,0,0,0,0,0)';
      PINUSE='POWER';
      NO_LOAD_CHECK='Both';
      NO_IO_CHECK='Both';
      NO_ASSERT_CHECK='TRUE';
      NO_DIR_CHECK='TRUE';
      ALLOW_CONNECT='TRUE';
    'VSS_AM10':
      PIN_NUMBER='(0,0,0,0,0,0,0,0,0,0,0,0,0,0,0,0,0,0,0,0,0,0,0,0,0,0,0,0,0,0,A~
M10,0,0,0,0,0,0,0,0,0)';
      PINUSE='POWER';
      NO_LOAD_CHECK='Both';
      NO_IO_CHECK='Both';
      NO_ASSERT_CHECK='TRUE';
      NO_DIR_CHECK='TRUE';
      ALLOW_CONNECT='TRUE';
    'VSS_AM15':
      PIN_NUMBER='(0,0,0,0,0,0,0,0,0,0,0,0,0,0,0,0,0,0,0,0,0,0,0,0,0,0,0,0,0,0,A~
M15,0,0,0,0,0,0,0,0,0)';
      PINUSE='POWER';
      NO_LOAD_CHECK='Both';
      NO_IO_CHECK='Both';
      NO_ASSERT_CHECK='TRUE';
      NO_DIR_CHECK='TRUE';
      ALLOW_CONNECT='TRUE';
    'VSS_AM17':
      PIN_NUMBER='(0,0,0,0,0,0,0,0,0,0,0,0,0,0,0,0,0,0,0,0,0,0,0,0,0,0,0,0,0,0,A~
M17,0,0,0,0,0,0,0,0,0)';
      PINUSE='POWER';
      NO_LOAD_CHECK='Both';
      NO_IO_CHECK='Both';
      NO_ASSERT_CHECK='TRUE';
      NO_DIR_CHECK='TRUE';
      ALLOW_CONNECT='TRUE';
    'VSS_AM23':
      PIN_NUMBER='(0,0,0,0,0,0,0,0,0,0,0,0,0,0,0,0,0,0,0,0,0,0,0,0,0,0,0,0,0,0,A~
M23,0,0,0,0,0,0,0,0,0)';
      PINUSE='POWER';
      NO_LOAD_CHECK='Both';
      NO_IO_CHECK='Both';
      NO_ASSERT_CHECK='TRUE';
      NO_DIR_CHECK='TRUE';
      ALLOW_CONNECT='TRUE';
    'VSS_AM24':
      PIN_NUMBER='(0,0,0,0,0,0,0,0,0,0,0,0,0,0,0,0,0,0,0,0,0,0,0,0,0,0,0,0,0,0,A~
M24,0,0,0,0,0,0,0,0,0)';
      PINUSE='POWER';
      NO_LOAD_CHECK='Both';
      NO_IO_CHECK='Both';
      NO_ASSERT_CHECK='TRUE';
      NO_DIR_CHECK='TRUE';
      ALLOW_CONNECT='TRUE';
    'VSS_AM25':
      PIN_NUMBER='(0,0,0,0,0,0,0,0,0,0,0,0,0,0,0,0,0,0,0,0,0,0,0,0,0,0,0,0,0,0,A~
M25,0,0,0,0,0,0,0,0,0)';
      PINUSE='POWER';
      NO_LOAD_CHECK='Both';
      NO_IO_CHECK='Both';
      NO_ASSERT_CHECK='TRUE';
      NO_DIR_CHECK='TRUE';
      ALLOW_CONNECT='TRUE';
    'VSS_AM26':
      PIN_NUMBER='(0,0,0,0,0,0,0,0,0,0,0,0,0,0,0,0,0,0,0,0,0,0,0,0,0,0,0,0,0,0,A~
M26,0,0,0,0,0,0,0,0,0)';
      PINUSE='POWER';
      NO_LOAD_CHECK='Both';
      NO_IO_CHECK='Both';
      NO_ASSERT_CHECK='TRUE';
      NO_DIR_CHECK='TRUE';
      ALLOW_CONNECT='TRUE';
    'VSS_AM27':
      PIN_NUMBER='(0,0,0,0,0,0,0,0,0,0,0,0,0,0,0,0,0,0,0,0,0,0,0,0,0,0,0,0,0,0,A~
M27,0,0,0,0,0,0,0,0,0)';
      PINUSE='POWER';
      NO_LOAD_CHECK='Both';
      NO_IO_CHECK='Both';
      NO_ASSERT_CHECK='TRUE';
      NO_DIR_CHECK='TRUE';
      ALLOW_CONNECT='TRUE';
    'VSS_AM28':
      PIN_NUMBER='(0,0,0,0,0,0,0,0,0,0,0,0,0,0,0,0,0,0,0,0,0,0,0,0,0,0,0,0,0,0,A~
M28,0,0,0,0,0,0,0,0,0)';
      PINUSE='POWER';
      NO_LOAD_CHECK='Both';
      NO_IO_CHECK='Both';
      NO_ASSERT_CHECK='TRUE';
      NO_DIR_CHECK='TRUE';
      ALLOW_CONNECT='TRUE';
    'VSS_AM29':
      PIN_NUMBER='(0,0,0,0,0,0,0,0,0,0,0,0,0,0,0,0,0,0,0,0,0,0,0,0,0,0,0,0,0,0,A~
M29,0,0,0,0,0,0,0,0,0)';
      PINUSE='POWER';
      NO_LOAD_CHECK='Both';
      NO_IO_CHECK='Both';
      NO_ASSERT_CHECK='TRUE';
      NO_DIR_CHECK='TRUE';
      ALLOW_CONNECT='TRUE';
    'VSS_AM30':
      PIN_NUMBER='(0,0,0,0,0,0,0,0,0,0,0,0,0,0,0,0,0,0,0,0,0,0,0,0,0,0,0,0,0,0,A~
M30,0,0,0,0,0,0,0,0,0)';
      PINUSE='POWER';
      NO_LOAD_CHECK='Both';
      NO_IO_CHECK='Both';
      NO_ASSERT_CHECK='TRUE';
      NO_DIR_CHECK='TRUE';
      ALLOW_CONNECT='TRUE';
    'VSS_AM31':
      PIN_NUMBER='(0,0,0,0,0,0,0,0,0,0,0,0,0,0,0,0,0,0,0,0,0,0,0,0,0,0,0,0,0,0,A~
M31,0,0,0,0,0,0,0,0,0)';
      PINUSE='POWER';
      NO_LOAD_CHECK='Both';
      NO_IO_CHECK='Both';
      NO_ASSERT_CHECK='TRUE';
      NO_DIR_CHECK='TRUE';
      ALLOW_CONNECT='TRUE';
    'VSS_AM32':
      PIN_NUMBER='(0,0,0,0,0,0,0,0,0,0,0,0,0,0,0,0,0,0,0,0,0,0,0,0,0,0,0,0,0,0,A~
M32,0,0,0,0,0,0,0,0,0)';
      PINUSE='POWER';
      NO_LOAD_CHECK='Both';
      NO_IO_CHECK='Both';
      NO_ASSERT_CHECK='TRUE';
      NO_DIR_CHECK='TRUE';
      ALLOW_CONNECT='TRUE';
    'VSS_AM33':
      PIN_NUMBER='(0,0,0,0,0,0,0,0,0,0,0,0,0,0,0,0,0,0,0,0,0,0,0,0,0,0,0,0,0,0,A~
M33,0,0,0,0,0,0,0,0,0)';
      PINUSE='POWER';
      NO_LOAD_CHECK='Both';
      NO_IO_CHECK='Both';
      NO_ASSERT_CHECK='TRUE';
      NO_DIR_CHECK='TRUE';
      ALLOW_CONNECT='TRUE';
    'VSS_AM34':
      PIN_NUMBER='(0,0,0,0,0,0,0,0,0,0,0,0,0,0,0,0,0,0,0,0,0,0,0,0,0,0,0,0,0,0,A~
M34,0,0,0,0,0,0,0,0,0)';
      PINUSE='POWER';
      NO_LOAD_CHECK='Both';
      NO_IO_CHECK='Both';
      NO_ASSERT_CHECK='TRUE';
      NO_DIR_CHECK='TRUE';
      ALLOW_CONNECT='TRUE';
    'VSS_AM39':
      PIN_NUMBER='(0,0,0,0,0,0,0,0,0,0,0,0,0,0,0,0,0,0,0,0,0,0,0,0,0,0,0,0,0,0,A~
M39,0,0,0,0,0,0,0,0,0)';
      PINUSE='POWER';
      NO_LOAD_CHECK='Both';
      NO_IO_CHECK='Both';
      NO_ASSERT_CHECK='TRUE';
      NO_DIR_CHECK='TRUE';
      ALLOW_CONNECT='TRUE';
    'VSS_AD49':
      PIN_NUMBER='(0,0,0,0,0,0,0,0,0,0,0,0,0,0,0,0,0,0,0,0,0,0,0,0,0,0,0,0,0,0,A~
D49,0,0,0,0,0,0,0,0,0)';
      PINUSE='POWER';
      NO_LOAD_CHECK='Both';
      NO_IO_CHECK='Both';
      NO_ASSERT_CHECK='TRUE';
      NO_DIR_CHECK='TRUE';
      ALLOW_CONNECT='TRUE';
    'VSS_AD50':
      PIN_NUMBER='(0,0,0,0,0,0,0,0,0,0,0,0,0,0,0,0,0,0,0,0,0,0,0,0,0,0,0,0,0,0,A~
D50,0,0,0,0,0,0,0,0,0)';
      PINUSE='POWER';
      NO_LOAD_CHECK='Both';
      NO_IO_CHECK='Both';
      NO_ASSERT_CHECK='TRUE';
      NO_DIR_CHECK='TRUE';
      ALLOW_CONNECT='TRUE';
    'VSS_AD51':
      PIN_NUMBER='(0,0,0,0,0,0,0,0,0,0,0,0,0,0,0,0,0,0,0,0,0,0,0,0,0,0,0,0,0,0,A~
D51,0,0,0,0,0,0,0,0,0)';
      PINUSE='POWER';
      NO_LOAD_CHECK='Both';
      NO_IO_CHECK='Both';
      NO_ASSERT_CHECK='TRUE';
      NO_DIR_CHECK='TRUE';
      ALLOW_CONNECT='TRUE';
    'VSS_AD52':
      PIN_NUMBER='(0,0,0,0,0,0,0,0,0,0,0,0,0,0,0,0,0,0,0,0,0,0,0,0,0,0,0,0,0,0,A~
D52,0,0,0,0,0,0,0,0,0)';
      PINUSE='POWER';
      NO_LOAD_CHECK='Both';
      NO_IO_CHECK='Both';
      NO_ASSERT_CHECK='TRUE';
      NO_DIR_CHECK='TRUE';
      ALLOW_CONNECT='TRUE';
    'VSS_AD53':
      PIN_NUMBER='(0,0,0,0,0,0,0,0,0,0,0,0,0,0,0,0,0,0,0,0,0,0,0,0,0,0,0,0,0,0,A~
D53,0,0,0,0,0,0,0,0,0)';
      PINUSE='POWER';
      NO_LOAD_CHECK='Both';
      NO_IO_CHECK='Both';
      NO_ASSERT_CHECK='TRUE';
      NO_DIR_CHECK='TRUE';
      ALLOW_CONNECT='TRUE';
    'VSS_AD57':
      PIN_NUMBER='(0,0,0,0,0,0,0,0,0,0,0,0,0,0,0,0,0,0,0,0,0,0,0,0,0,0,0,0,0,0,A~
D57,0,0,0,0,0,0,0,0,0)';
      PINUSE='POWER';
      NO_LOAD_CHECK='Both';
      NO_IO_CHECK='Both';
      NO_ASSERT_CHECK='TRUE';
      NO_DIR_CHECK='TRUE';
      ALLOW_CONNECT='TRUE';
    'VSS_AD59':
      PIN_NUMBER='(0,0,0,0,0,0,0,0,0,0,0,0,0,0,0,0,0,0,0,0,0,0,0,0,0,0,0,0,0,0,A~
D59,0,0,0,0,0,0,0,0,0)';
      PINUSE='POWER';
      NO_LOAD_CHECK='Both';
      NO_IO_CHECK='Both';
      NO_ASSERT_CHECK='TRUE';
      NO_DIR_CHECK='TRUE';
      ALLOW_CONNECT='TRUE';
    'VSS_AD61':
      PIN_NUMBER='(0,0,0,0,0,0,0,0,0,0,0,0,0,0,0,0,0,0,0,0,0,0,0,0,0,0,0,0,0,0,A~
D61,0,0,0,0,0,0,0,0,0)';
      PINUSE='POWER';
      NO_LOAD_CHECK='Both';
      NO_IO_CHECK='Both';
      NO_ASSERT_CHECK='TRUE';
      NO_DIR_CHECK='TRUE';
      ALLOW_CONNECT='TRUE';
    'VSS_AD64':
      PIN_NUMBER='(0,0,0,0,0,0,0,0,0,0,0,0,0,0,0,0,0,0,0,0,0,0,0,0,0,0,0,0,0,0,A~
D64,0,0,0,0,0,0,0,0,0)';
      PINUSE='POWER';
      NO_LOAD_CHECK='Both';
      NO_IO_CHECK='Both';
      NO_ASSERT_CHECK='TRUE';
      NO_DIR_CHECK='TRUE';
      ALLOW_CONNECT='TRUE';
    'VSS_AD66':
      PIN_NUMBER='(0,0,0,0,0,0,0,0,0,0,0,0,0,0,0,0,0,0,0,0,0,0,0,0,0,0,0,0,0,0,A~
D66,0,0,0,0,0,0,0,0,0)';
      PINUSE='POWER';
      NO_LOAD_CHECK='Both';
      NO_IO_CHECK='Both';
      NO_ASSERT_CHECK='TRUE';
      NO_DIR_CHECK='TRUE';
      ALLOW_CONNECT='TRUE';
    'VSS_AD68':
      PIN_NUMBER='(0,0,0,0,0,0,0,0,0,0,0,0,0,0,0,0,0,0,0,0,0,0,0,0,0,0,0,0,0,0,A~
D68,0,0,0,0,0,0,0,0,0)';
      PINUSE='POWER';
      NO_LOAD_CHECK='Both';
      NO_IO_CHECK='Both';
      NO_ASSERT_CHECK='TRUE';
      NO_DIR_CHECK='TRUE';
      ALLOW_CONNECT='TRUE';
    'VSS_AD71':
      PIN_NUMBER='(0,0,0,0,0,0,0,0,0,0,0,0,0,0,0,0,0,0,0,0,0,0,0,0,0,0,0,0,0,0,A~
D71,0,0,0,0,0,0,0,0,0)';
      PINUSE='POWER';
      NO_LOAD_CHECK='Both';
      NO_IO_CHECK='Both';
      NO_ASSERT_CHECK='TRUE';
      NO_DIR_CHECK='TRUE';
      ALLOW_CONNECT='TRUE';
    'VSS_AD73':
      PIN_NUMBER='(0,0,0,0,0,0,0,0,0,0,0,0,0,0,0,0,0,0,0,0,0,0,0,0,0,0,0,0,0,0,A~
D73,0,0,0,0,0,0,0,0,0)';
      PINUSE='POWER';
      NO_LOAD_CHECK='Both';
      NO_IO_CHECK='Both';
      NO_ASSERT_CHECK='TRUE';
      NO_DIR_CHECK='TRUE';
      ALLOW_CONNECT='TRUE';
    'VSS_AE1':
      PIN_NUMBER='(0,0,0,0,0,0,0,0,0,0,0,0,0,0,0,0,0,0,0,0,0,0,0,0,0,0,0,0,0,0,A~
E1,0,0,0,0,0,0,0,0,0)';
      PINUSE='POWER';
      NO_LOAD_CHECK='Both';
      NO_IO_CHECK='Both';
      NO_ASSERT_CHECK='TRUE';
      NO_DIR_CHECK='TRUE';
      ALLOW_CONNECT='TRUE';
    'VSS_AE6':
      PIN_NUMBER='(0,0,0,0,0,0,0,0,0,0,0,0,0,0,0,0,0,0,0,0,0,0,0,0,0,0,0,0,0,0,A~
E6,0,0,0,0,0,0,0,0,0)';
      PINUSE='POWER';
      NO_LOAD_CHECK='Both';
      NO_IO_CHECK='Both';
      NO_ASSERT_CHECK='TRUE';
      NO_DIR_CHECK='TRUE';
      ALLOW_CONNECT='TRUE';
    'VSS_AE8':
      PIN_NUMBER='(0,0,0,0,0,0,0,0,0,0,0,0,0,0,0,0,0,0,0,0,0,0,0,0,0,0,0,0,0,0,A~
E8,0,0,0,0,0,0,0,0,0)';
      PINUSE='POWER';
      NO_LOAD_CHECK='Both';
      NO_IO_CHECK='Both';
      NO_ASSERT_CHECK='TRUE';
      NO_DIR_CHECK='TRUE';
      ALLOW_CONNECT='TRUE';
    'VSS_AE11':
      PIN_NUMBER='(0,0,0,0,0,0,0,0,0,0,0,0,0,0,0,0,0,0,0,0,0,0,0,0,0,0,0,0,0,0,A~
E11,0,0,0,0,0,0,0,0,0)';
      PINUSE='POWER';
      NO_LOAD_CHECK='Both';
      NO_IO_CHECK='Both';
      NO_ASSERT_CHECK='TRUE';
      NO_DIR_CHECK='TRUE';
      ALLOW_CONNECT='TRUE';
    'VSS_AE13':
      PIN_NUMBER='(0,0,0,0,0,0,0,0,0,0,0,0,0,0,0,0,0,0,0,0,0,0,0,0,0,0,0,0,0,0,A~
E13,0,0,0,0,0,0,0,0,0)';
      PINUSE='POWER';
      NO_LOAD_CHECK='Both';
      NO_IO_CHECK='Both';
      NO_ASSERT_CHECK='TRUE';
      NO_DIR_CHECK='TRUE';
      ALLOW_CONNECT='TRUE';
    'VSS_AE15':
      PIN_NUMBER='(0,0,0,0,0,0,0,0,0,0,0,0,0,0,0,0,0,0,0,0,0,0,0,0,0,0,0,0,0,0,A~
E15,0,0,0,0,0,0,0,0,0)';
      PINUSE='POWER';
      NO_LOAD_CHECK='Both';
      NO_IO_CHECK='Both';
      NO_ASSERT_CHECK='TRUE';
      NO_DIR_CHECK='TRUE';
      ALLOW_CONNECT='TRUE';
    'VSS_AE18':
      PIN_NUMBER='(0,0,0,0,0,0,0,0,0,0,0,0,0,0,0,0,0,0,0,0,0,0,0,0,0,0,0,0,0,0,A~
E18,0,0,0,0,0,0,0,0,0)';
      PINUSE='POWER';
      NO_LOAD_CHECK='Both';
      NO_IO_CHECK='Both';
      NO_ASSERT_CHECK='TRUE';
      NO_DIR_CHECK='TRUE';
      ALLOW_CONNECT='TRUE';
    'VSS_AE20':
      PIN_NUMBER='(0,0,0,0,0,0,0,0,0,0,0,0,0,0,0,0,0,0,0,0,0,0,0,0,0,0,0,0,0,0,A~
E20,0,0,0,0,0,0,0,0,0)';
      PINUSE='POWER';
      NO_LOAD_CHECK='Both';
      NO_IO_CHECK='Both';
      NO_ASSERT_CHECK='TRUE';
      NO_DIR_CHECK='TRUE';
      ALLOW_CONNECT='TRUE';
    'VSS_AE22':
      PIN_NUMBER='(0,0,0,0,0,0,0,0,0,0,0,0,0,0,0,0,0,0,0,0,0,0,0,0,0,0,0,0,0,0,A~
E22,0,0,0,0,0,0,0,0,0)';
      PINUSE='POWER';
      NO_LOAD_CHECK='Both';
      NO_IO_CHECK='Both';
      NO_ASSERT_CHECK='TRUE';
      NO_DIR_CHECK='TRUE';
      ALLOW_CONNECT='TRUE';
    'VSS_AE25':
      PIN_NUMBER='(0,0,0,0,0,0,0,0,0,0,0,0,0,0,0,0,0,0,0,0,0,0,0,0,0,0,0,0,0,0,A~
E25,0,0,0,0,0,0,0,0,0)';
      PINUSE='POWER';
      NO_LOAD_CHECK='Both';
      NO_IO_CHECK='Both';
      NO_ASSERT_CHECK='TRUE';
      NO_DIR_CHECK='TRUE';
      ALLOW_CONNECT='TRUE';
    'VSS_AE28':
      PIN_NUMBER='(0,0,0,0,0,0,0,0,0,0,0,0,0,0,0,0,0,0,0,0,0,0,0,0,0,0,0,0,0,0,A~
E28,0,0,0,0,0,0,0,0,0)';
      PINUSE='POWER';
      NO_LOAD_CHECK='Both';
      NO_IO_CHECK='Both';
      NO_ASSERT_CHECK='TRUE';
      NO_DIR_CHECK='TRUE';
      ALLOW_CONNECT='TRUE';
    'VSS_AE31':
      PIN_NUMBER='(0,0,0,0,0,0,0,0,0,0,0,0,0,0,0,0,0,0,0,0,0,0,0,0,0,0,0,0,0,0,A~
E31,0,0,0,0,0,0,0,0,0)';
      PINUSE='POWER';
      NO_LOAD_CHECK='Both';
      NO_IO_CHECK='Both';
      NO_ASSERT_CHECK='TRUE';
      NO_DIR_CHECK='TRUE';
      ALLOW_CONNECT='TRUE';
    'VSS_AE34':
      PIN_NUMBER='(0,0,0,0,0,0,0,0,0,0,0,0,0,0,0,0,0,0,0,0,0,0,0,0,0,0,0,0,0,0,A~
E34,0,0,0,0,0,0,0,0,0)';
      PINUSE='POWER';
      NO_LOAD_CHECK='Both';
      NO_IO_CHECK='Both';
      NO_ASSERT_CHECK='TRUE';
      NO_DIR_CHECK='TRUE';
      ALLOW_CONNECT='TRUE';
    'VSS_AE35':
      PIN_NUMBER='(0,0,0,0,0,0,0,0,0,0,0,0,0,0,0,0,0,0,0,0,0,0,0,0,0,0,0,0,0,0,A~
E35,0,0,0,0,0,0,0,0,0)';
      PINUSE='POWER';
      NO_LOAD_CHECK='Both';
      NO_IO_CHECK='Both';
      NO_ASSERT_CHECK='TRUE';
      NO_DIR_CHECK='TRUE';
      ALLOW_CONNECT='TRUE';
    'VSS_AE36':
      PIN_NUMBER='(0,0,0,0,0,0,0,0,0,0,0,0,0,0,0,0,0,0,0,0,0,0,0,0,0,0,0,0,0,0,A~
E36,0,0,0,0,0,0,0,0,0)';
      PINUSE='POWER';
      NO_LOAD_CHECK='Both';
      NO_IO_CHECK='Both';
      NO_ASSERT_CHECK='TRUE';
      NO_DIR_CHECK='TRUE';
      ALLOW_CONNECT='TRUE';
    'VSS_AE40':
      PIN_NUMBER='(0,0,0,0,0,0,0,0,0,0,0,0,0,0,0,0,0,0,0,0,0,0,0,0,0,0,0,0,0,0,A~
E40,0,0,0,0,0,0,0,0,0)';
      PINUSE='POWER';
      NO_LOAD_CHECK='Both';
      NO_IO_CHECK='Both';
      NO_ASSERT_CHECK='TRUE';
      NO_DIR_CHECK='TRUE';
      ALLOW_CONNECT='TRUE';
    'VSS_AE41':
      PIN_NUMBER='(0,0,0,0,0,0,0,0,0,0,0,0,0,0,0,0,0,0,0,0,0,0,0,0,0,0,0,0,0,0,A~
E41,0,0,0,0,0,0,0,0,0)';
      PINUSE='POWER';
      NO_LOAD_CHECK='Both';
      NO_IO_CHECK='Both';
      NO_ASSERT_CHECK='TRUE';
      NO_DIR_CHECK='TRUE';
      ALLOW_CONNECT='TRUE';
    'VSS_AE42':
      PIN_NUMBER='(0,0,0,0,0,0,0,0,0,0,0,0,0,0,0,0,0,0,0,0,0,0,0,0,0,0,0,0,0,0,A~
E42,0,0,0,0,0,0,0,0,0)';
      PINUSE='POWER';
      NO_LOAD_CHECK='Both';
      NO_IO_CHECK='Both';
      NO_ASSERT_CHECK='TRUE';
      NO_DIR_CHECK='TRUE';
      ALLOW_CONNECT='TRUE';
    'VSS_AE45':
      PIN_NUMBER='(0,0,0,0,0,0,0,0,0,0,0,0,0,0,0,0,0,0,0,0,0,0,0,0,0,0,0,0,0,0,A~
E45,0,0,0,0,0,0,0,0,0)';
      PINUSE='POWER';
      NO_LOAD_CHECK='Both';
      NO_IO_CHECK='Both';
      NO_ASSERT_CHECK='TRUE';
      NO_DIR_CHECK='TRUE';
      ALLOW_CONNECT='TRUE';
    'VSS_AE48':
      PIN_NUMBER='(0,0,0,0,0,0,0,0,0,0,0,0,0,0,0,0,0,0,0,0,0,0,0,0,0,0,0,0,0,0,A~
E48,0,0,0,0,0,0,0,0,0)';
      PINUSE='POWER';
      NO_LOAD_CHECK='Both';
      NO_IO_CHECK='Both';
      NO_ASSERT_CHECK='TRUE';
      NO_DIR_CHECK='TRUE';
      ALLOW_CONNECT='TRUE';
    'VSS_AE51':
      PIN_NUMBER='(0,0,0,0,0,0,0,0,0,0,0,0,0,0,0,0,0,0,0,0,0,0,0,0,0,0,0,0,0,0,A~
E51,0,0,0,0,0,0,0,0,0)';
      PINUSE='POWER';
      NO_LOAD_CHECK='Both';
      NO_IO_CHECK='Both';
      NO_ASSERT_CHECK='TRUE';
      NO_DIR_CHECK='TRUE';
      ALLOW_CONNECT='TRUE';
    'VSS_AE54':
      PIN_NUMBER='(0,0,0,0,0,0,0,0,0,0,0,0,0,0,0,0,0,0,0,0,0,0,0,0,0,0,0,0,0,0,A~
E54,0,0,0,0,0,0,0,0,0)';
      PINUSE='POWER';
      NO_LOAD_CHECK='Both';
      NO_IO_CHECK='Both';
      NO_ASSERT_CHECK='TRUE';
      NO_DIR_CHECK='TRUE';
      ALLOW_CONNECT='TRUE';
    'VSS_AE56':
      PIN_NUMBER='(0,0,0,0,0,0,0,0,0,0,0,0,0,0,0,0,0,0,0,0,0,0,0,0,0,0,0,0,0,0,A~
E56,0,0,0,0,0,0,0,0,0)';
      PINUSE='POWER';
      NO_LOAD_CHECK='Both';
      NO_IO_CHECK='Both';
      NO_ASSERT_CHECK='TRUE';
      NO_DIR_CHECK='TRUE';
      ALLOW_CONNECT='TRUE';
    'VSS_AE58':
      PIN_NUMBER='(0,0,0,0,0,0,0,0,0,0,0,0,0,0,0,0,0,0,0,0,0,0,0,0,0,0,0,0,0,0,A~
E58,0,0,0,0,0,0,0,0,0)';
      PINUSE='POWER';
      NO_LOAD_CHECK='Both';
      NO_IO_CHECK='Both';
      NO_ASSERT_CHECK='TRUE';
      NO_DIR_CHECK='TRUE';
      ALLOW_CONNECT='TRUE';
    'VSS_AE61':
      PIN_NUMBER='(0,0,0,0,0,0,0,0,0,0,0,0,0,0,0,0,0,0,0,0,0,0,0,0,0,0,0,0,0,0,A~
E61,0,0,0,0,0,0,0,0,0)';
      PINUSE='POWER';
      NO_LOAD_CHECK='Both';
      NO_IO_CHECK='Both';
      NO_ASSERT_CHECK='TRUE';
      NO_DIR_CHECK='TRUE';
      ALLOW_CONNECT='TRUE';
    'VSS_AE63':
      PIN_NUMBER='(0,0,0,0,0,0,0,0,0,0,0,0,0,0,0,0,0,0,0,0,0,0,0,0,0,0,0,0,0,0,A~
E63,0,0,0,0,0,0,0,0,0)';
      PINUSE='POWER';
      NO_LOAD_CHECK='Both';
      NO_IO_CHECK='Both';
      NO_ASSERT_CHECK='TRUE';
      NO_DIR_CHECK='TRUE';
      ALLOW_CONNECT='TRUE';
    'VSS_AE65':
      PIN_NUMBER='(0,0,0,0,0,0,0,0,0,0,0,0,0,0,0,0,0,0,0,0,0,0,0,0,0,0,0,0,0,0,A~
E65,0,0,0,0,0,0,0,0,0)';
      PINUSE='POWER';
      NO_LOAD_CHECK='Both';
      NO_IO_CHECK='Both';
      NO_ASSERT_CHECK='TRUE';
      NO_DIR_CHECK='TRUE';
      ALLOW_CONNECT='TRUE';
    'VSS_AE68':
      PIN_NUMBER='(0,0,0,0,0,0,0,0,0,0,0,0,0,0,0,0,0,0,0,0,0,0,0,0,0,0,0,0,0,0,A~
E68,0,0,0,0,0,0,0,0,0)';
      PINUSE='POWER';
      NO_LOAD_CHECK='Both';
      NO_IO_CHECK='Both';
      NO_ASSERT_CHECK='TRUE';
      NO_DIR_CHECK='TRUE';
      ALLOW_CONNECT='TRUE';
    'VSS_AE70':
      PIN_NUMBER='(0,0,0,0,0,0,0,0,0,0,0,0,0,0,0,0,0,0,0,0,0,0,0,0,0,0,0,0,0,0,A~
E70,0,0,0,0,0,0,0,0,0)';
      PINUSE='POWER';
      NO_LOAD_CHECK='Both';
      NO_IO_CHECK='Both';
      NO_ASSERT_CHECK='TRUE';
      NO_DIR_CHECK='TRUE';
      ALLOW_CONNECT='TRUE';
    'VSS_AE72':
      PIN_NUMBER='(0,0,0,0,0,0,0,0,0,0,0,0,0,0,0,0,0,0,0,0,0,0,0,0,0,0,0,0,0,0,A~
E72,0,0,0,0,0,0,0,0,0)';
      PINUSE='POWER';
      NO_LOAD_CHECK='Both';
      NO_IO_CHECK='Both';
      NO_ASSERT_CHECK='TRUE';
      NO_DIR_CHECK='TRUE';
      ALLOW_CONNECT='TRUE';
    'VSS_AE75':
      PIN_NUMBER='(0,0,0,0,0,0,0,0,0,0,0,0,0,0,0,0,0,0,0,0,0,0,0,0,0,0,0,0,0,0,A~
E75,0,0,0,0,0,0,0,0,0)';
      PINUSE='POWER';
      NO_LOAD_CHECK='Both';
      NO_IO_CHECK='Both';
      NO_ASSERT_CHECK='TRUE';
      NO_DIR_CHECK='TRUE';
      ALLOW_CONNECT='TRUE';
    'VSS_AF3':
      PIN_NUMBER='(0,0,0,0,0,0,0,0,0,0,0,0,0,0,0,0,0,0,0,0,0,0,0,0,0,0,0,0,0,0,A~
F3,0,0,0,0,0,0,0,0,0)';
      PINUSE='POWER';
      NO_LOAD_CHECK='Both';
      NO_IO_CHECK='Both';
      NO_ASSERT_CHECK='TRUE';
      NO_DIR_CHECK='TRUE';
      ALLOW_CONNECT='TRUE';
    'VSS_AF8':
      PIN_NUMBER='(0,0,0,0,0,0,0,0,0,0,0,0,0,0,0,0,0,0,0,0,0,0,0,0,0,0,0,0,0,0,A~
F8,0,0,0,0,0,0,0,0,0)';
      PINUSE='POWER';
      NO_LOAD_CHECK='Both';
      NO_IO_CHECK='Both';
      NO_ASSERT_CHECK='TRUE';
      NO_DIR_CHECK='TRUE';
      ALLOW_CONNECT='TRUE';
    'VSS_AF10':
      PIN_NUMBER='(0,0,0,0,0,0,0,0,0,0,0,0,0,0,0,0,0,0,0,0,0,0,0,0,0,0,0,0,0,0,A~
F10,0,0,0,0,0,0,0,0,0)';
      PINUSE='POWER';
      NO_LOAD_CHECK='Both';
      NO_IO_CHECK='Both';
      NO_ASSERT_CHECK='TRUE';
      NO_DIR_CHECK='TRUE';
      ALLOW_CONNECT='TRUE';
    'VSS_AF15':
      PIN_NUMBER='(0,0,0,0,0,0,0,0,0,0,0,0,0,0,0,0,0,0,0,0,0,0,0,0,0,0,0,0,0,0,A~
F15,0,0,0,0,0,0,0,0,0)';
      PINUSE='POWER';
      NO_LOAD_CHECK='Both';
      NO_IO_CHECK='Both';
      NO_ASSERT_CHECK='TRUE';
      NO_DIR_CHECK='TRUE';
      ALLOW_CONNECT='TRUE';
    'VSS_AF17':
      PIN_NUMBER='(0,0,0,0,0,0,0,0,0,0,0,0,0,0,0,0,0,0,0,0,0,0,0,0,0,0,0,0,0,0,A~
F17,0,0,0,0,0,0,0,0,0)';
      PINUSE='POWER';
      NO_LOAD_CHECK='Both';
      NO_IO_CHECK='Both';
      NO_ASSERT_CHECK='TRUE';
      NO_DIR_CHECK='TRUE';
      ALLOW_CONNECT='TRUE';
    'VSS_AF22':
      PIN_NUMBER='(0,0,0,0,0,0,0,0,0,0,0,0,0,0,0,0,0,0,0,0,0,0,0,0,0,0,0,0,0,0,A~
F22,0,0,0,0,0,0,0,0,0)';
      PINUSE='POWER';
      NO_LOAD_CHECK='Both';
      NO_IO_CHECK='Both';
      NO_ASSERT_CHECK='TRUE';
      NO_DIR_CHECK='TRUE';
      ALLOW_CONNECT='TRUE';
    'VSS_AF25':
      PIN_NUMBER='(0,0,0,0,0,0,0,0,0,0,0,0,0,0,0,0,0,0,0,0,0,0,0,0,0,0,0,0,0,0,A~
F25,0,0,0,0,0,0,0,0,0)';
      PINUSE='POWER';
      NO_LOAD_CHECK='Both';
      NO_IO_CHECK='Both';
      NO_ASSERT_CHECK='TRUE';
      NO_DIR_CHECK='TRUE';
      ALLOW_CONNECT='TRUE';
    'VSS_AF28':
      PIN_NUMBER='(0,0,0,0,0,0,0,0,0,0,0,0,0,0,0,0,0,0,0,0,0,0,0,0,0,0,0,0,0,0,A~
F28,0,0,0,0,0,0,0,0,0)';
      PINUSE='POWER';
      NO_LOAD_CHECK='Both';
      NO_IO_CHECK='Both';
      NO_ASSERT_CHECK='TRUE';
      NO_DIR_CHECK='TRUE';
      ALLOW_CONNECT='TRUE';
    'VSS_AF31':
      PIN_NUMBER='(0,0,0,0,0,0,0,0,0,0,0,0,0,0,0,0,0,0,0,0,0,0,0,0,0,0,0,0,0,0,A~
F31,0,0,0,0,0,0,0,0,0)';
      PINUSE='POWER';
      NO_LOAD_CHECK='Both';
      NO_IO_CHECK='Both';
      NO_ASSERT_CHECK='TRUE';
      NO_DIR_CHECK='TRUE';
      ALLOW_CONNECT='TRUE';
    'VSS_AF34':
      PIN_NUMBER='(0,0,0,0,0,0,0,0,0,0,0,0,0,0,0,0,0,0,0,0,0,0,0,0,0,0,0,0,0,0,A~
F34,0,0,0,0,0,0,0,0,0)';
      PINUSE='POWER';
      NO_LOAD_CHECK='Both';
      NO_IO_CHECK='Both';
      NO_ASSERT_CHECK='TRUE';
      NO_DIR_CHECK='TRUE';
      ALLOW_CONNECT='TRUE';
    'VSS_AF37':
      PIN_NUMBER='(0,0,0,0,0,0,0,0,0,0,0,0,0,0,0,0,0,0,0,0,0,0,0,0,0,0,0,0,0,0,A~
F37,0,0,0,0,0,0,0,0,0)';
      PINUSE='POWER';
      NO_LOAD_CHECK='Both';
      NO_IO_CHECK='Both';
      NO_ASSERT_CHECK='TRUE';
      NO_DIR_CHECK='TRUE';
      ALLOW_CONNECT='TRUE';
    'VSS_AF39':
      PIN_NUMBER='(0,0,0,0,0,0,0,0,0,0,0,0,0,0,0,0,0,0,0,0,0,0,0,0,0,0,0,0,0,0,A~
F39,0,0,0,0,0,0,0,0,0)';
      PINUSE='POWER';
      NO_LOAD_CHECK='Both';
      NO_IO_CHECK='Both';
      NO_ASSERT_CHECK='TRUE';
      NO_DIR_CHECK='TRUE';
      ALLOW_CONNECT='TRUE';
    'VSS_AF42':
      PIN_NUMBER='(0,0,0,0,0,0,0,0,0,0,0,0,0,0,0,0,0,0,0,0,0,0,0,0,0,0,0,0,0,0,A~
F42,0,0,0,0,0,0,0,0,0)';
      PINUSE='POWER';
      NO_LOAD_CHECK='Both';
      NO_IO_CHECK='Both';
      NO_ASSERT_CHECK='TRUE';
      NO_DIR_CHECK='TRUE';
      ALLOW_CONNECT='TRUE';
    'VSS_AF45':
      PIN_NUMBER='(0,0,0,0,0,0,0,0,0,0,0,0,0,0,0,0,0,0,0,0,0,0,0,0,0,0,0,0,0,0,A~
F45,0,0,0,0,0,0,0,0,0)';
      PINUSE='POWER';
      NO_LOAD_CHECK='Both';
      NO_IO_CHECK='Both';
      NO_ASSERT_CHECK='TRUE';
      NO_DIR_CHECK='TRUE';
      ALLOW_CONNECT='TRUE';
    'VSS_AF48':
      PIN_NUMBER='(0,0,0,0,0,0,0,0,0,0,0,0,0,0,0,0,0,0,0,0,0,0,0,0,0,0,0,0,0,0,A~
F48,0,0,0,0,0,0,0,0,0)';
      PINUSE='POWER';
      NO_LOAD_CHECK='Both';
      NO_IO_CHECK='Both';
      NO_ASSERT_CHECK='TRUE';
      NO_DIR_CHECK='TRUE';
      ALLOW_CONNECT='TRUE';
    'VSS_AF51':
      PIN_NUMBER='(0,0,0,0,0,0,0,0,0,0,0,0,0,0,0,0,0,0,0,0,0,0,0,0,0,0,0,0,0,0,A~
F51,0,0,0,0,0,0,0,0,0)';
      PINUSE='POWER';
      NO_LOAD_CHECK='Both';
      NO_IO_CHECK='Both';
      NO_ASSERT_CHECK='TRUE';
      NO_DIR_CHECK='TRUE';
      ALLOW_CONNECT='TRUE';
    'VSS_AF54':
      PIN_NUMBER='(0,0,0,0,0,0,0,0,0,0,0,0,0,0,0,0,0,0,0,0,0,0,0,0,0,0,0,0,0,0,A~
F54,0,0,0,0,0,0,0,0,0)';
      PINUSE='POWER';
      NO_LOAD_CHECK='Both';
      NO_IO_CHECK='Both';
      NO_ASSERT_CHECK='TRUE';
      NO_DIR_CHECK='TRUE';
      ALLOW_CONNECT='TRUE';
    'VSS_AF59':
      PIN_NUMBER='(0,0,0,0,0,0,0,0,0,0,0,0,0,0,0,0,0,0,0,0,0,0,0,0,0,0,0,0,0,0,A~
F59,0,0,0,0,0,0,0,0,0)';
      PINUSE='POWER';
      NO_LOAD_CHECK='Both';
      NO_IO_CHECK='Both';
      NO_ASSERT_CHECK='TRUE';
      NO_DIR_CHECK='TRUE';
      ALLOW_CONNECT='TRUE';
    'VSS_AF61':
      PIN_NUMBER='(0,0,0,0,0,0,0,0,0,0,0,0,0,0,0,0,0,0,0,0,0,0,0,0,0,0,0,0,0,0,A~
F61,0,0,0,0,0,0,0,0,0)';
      PINUSE='POWER';
      NO_LOAD_CHECK='Both';
      NO_IO_CHECK='Both';
      NO_ASSERT_CHECK='TRUE';
      NO_DIR_CHECK='TRUE';
      ALLOW_CONNECT='TRUE';
    'VSS_AF66':
      PIN_NUMBER='(0,0,0,0,0,0,0,0,0,0,0,0,0,0,0,0,0,0,0,0,0,0,0,0,0,0,0,0,0,0,A~
F66,0,0,0,0,0,0,0,0,0)';
      PINUSE='POWER';
      NO_LOAD_CHECK='Both';
      NO_IO_CHECK='Both';
      NO_ASSERT_CHECK='TRUE';
      NO_DIR_CHECK='TRUE';
      ALLOW_CONNECT='TRUE';
    'VSS_AF68':
      PIN_NUMBER='(0,0,0,0,0,0,0,0,0,0,0,0,0,0,0,0,0,0,0,0,0,0,0,0,0,0,0,0,0,0,A~
F68,0,0,0,0,0,0,0,0,0)';
      PINUSE='POWER';
      NO_LOAD_CHECK='Both';
      NO_IO_CHECK='Both';
      NO_ASSERT_CHECK='TRUE';
      NO_DIR_CHECK='TRUE';
      ALLOW_CONNECT='TRUE';
    'VSS_AF73':
      PIN_NUMBER='(0,0,0,0,0,0,0,0,0,0,0,0,0,0,0,0,0,0,0,0,0,0,0,0,0,0,0,0,0,0,A~
F73,0,0,0,0,0,0,0,0,0)';
      PINUSE='POWER';
      NO_LOAD_CHECK='Both';
      NO_IO_CHECK='Both';
      NO_ASSERT_CHECK='TRUE';
      NO_DIR_CHECK='TRUE';
      ALLOW_CONNECT='TRUE';
    'VSS_AG1':
      PIN_NUMBER='(0,0,0,0,0,0,0,0,0,0,0,0,0,0,0,0,0,0,0,0,0,0,0,0,0,0,0,0,0,0,A~
G1,0,0,0,0,0,0,0,0,0)';
      PINUSE='POWER';
      NO_LOAD_CHECK='Both';
      NO_IO_CHECK='Both';
      NO_ASSERT_CHECK='TRUE';
      NO_DIR_CHECK='TRUE';
      ALLOW_CONNECT='TRUE';
    'VSS_AG4':
      PIN_NUMBER='(0,0,0,0,0,0,0,0,0,0,0,0,0,0,0,0,0,0,0,0,0,0,0,0,0,0,0,0,0,0,A~
G4,0,0,0,0,0,0,0,0,0)';
      PINUSE='POWER';
      NO_LOAD_CHECK='Both';
      NO_IO_CHECK='Both';
      NO_ASSERT_CHECK='TRUE';
      NO_DIR_CHECK='TRUE';
      ALLOW_CONNECT='TRUE';
    'VSS_AG6':
      PIN_NUMBER='(0,0,0,0,0,0,0,0,0,0,0,0,0,0,0,0,0,0,0,0,0,0,0,0,0,0,0,0,0,0,A~
G6,0,0,0,0,0,0,0,0,0)';
      PINUSE='POWER';
      NO_LOAD_CHECK='Both';
      NO_IO_CHECK='Both';
      NO_ASSERT_CHECK='TRUE';
      NO_DIR_CHECK='TRUE';
      ALLOW_CONNECT='TRUE';
    'VSS_AG8':
      PIN_NUMBER='(0,0,0,0,0,0,0,0,0,0,0,0,0,0,0,0,0,0,0,0,0,0,0,0,0,0,0,0,0,0,A~
G8,0,0,0,0,0,0,0,0,0)';
      PINUSE='POWER';
      NO_LOAD_CHECK='Both';
      NO_IO_CHECK='Both';
      NO_ASSERT_CHECK='TRUE';
      NO_DIR_CHECK='TRUE';
      ALLOW_CONNECT='TRUE';
    'VSS_AG11':
      PIN_NUMBER='(0,0,0,0,0,0,0,0,0,0,0,0,0,0,0,0,0,0,0,0,0,0,0,0,0,0,0,0,0,0,A~
G11,0,0,0,0,0,0,0,0,0)';
      PINUSE='POWER';
      NO_LOAD_CHECK='Both';
      NO_IO_CHECK='Both';
      NO_ASSERT_CHECK='TRUE';
      NO_DIR_CHECK='TRUE';
      ALLOW_CONNECT='TRUE';
    'VSS_AG13':
      PIN_NUMBER='(0,0,0,0,0,0,0,0,0,0,0,0,0,0,0,0,0,0,0,0,0,0,0,0,0,0,0,0,0,0,A~
G13,0,0,0,0,0,0,0,0,0)';
      PINUSE='POWER';
      NO_LOAD_CHECK='Both';
      NO_IO_CHECK='Both';
      NO_ASSERT_CHECK='TRUE';
      NO_DIR_CHECK='TRUE';
      ALLOW_CONNECT='TRUE';
    'VSS_AG15':
      PIN_NUMBER='(0,0,0,0,0,0,0,0,0,0,0,0,0,0,0,0,0,0,0,0,0,0,0,0,0,0,0,0,0,0,A~
G15,0,0,0,0,0,0,0,0,0)';
      PINUSE='POWER';
      NO_LOAD_CHECK='Both';
      NO_IO_CHECK='Both';
      NO_ASSERT_CHECK='TRUE';
      NO_DIR_CHECK='TRUE';
      ALLOW_CONNECT='TRUE';
    'VSS_AG18':
      PIN_NUMBER='(0,0,0,0,0,0,0,0,0,0,0,0,0,0,0,0,0,0,0,0,0,0,0,0,0,0,0,0,0,0,A~
G18,0,0,0,0,0,0,0,0,0)';
      PINUSE='POWER';
      NO_LOAD_CHECK='Both';
      NO_IO_CHECK='Both';
      NO_ASSERT_CHECK='TRUE';
      NO_DIR_CHECK='TRUE';
      ALLOW_CONNECT='TRUE';
    'VSS_AG20':
      PIN_NUMBER='(0,0,0,0,0,0,0,0,0,0,0,0,0,0,0,0,0,0,0,0,0,0,0,0,0,0,0,0,0,0,A~
G20,0,0,0,0,0,0,0,0,0)';
      PINUSE='POWER';
      NO_LOAD_CHECK='Both';
      NO_IO_CHECK='Both';
      NO_ASSERT_CHECK='TRUE';
      NO_DIR_CHECK='TRUE';
      ALLOW_CONNECT='TRUE';
    'VSS_AG22':
      PIN_NUMBER='(0,0,0,0,0,0,0,0,0,0,0,0,0,0,0,0,0,0,0,0,0,0,0,0,0,0,0,0,0,0,A~
G22,0,0,0,0,0,0,0,0,0)';
      PINUSE='POWER';
      NO_LOAD_CHECK='Both';
      NO_IO_CHECK='Both';
      NO_ASSERT_CHECK='TRUE';
      NO_DIR_CHECK='TRUE';
      ALLOW_CONNECT='TRUE';
    'VSS_AG25':
      PIN_NUMBER='(0,0,0,0,0,0,0,0,0,0,0,0,0,0,0,0,0,0,0,0,0,0,0,0,0,0,0,0,0,0,A~
G25,0,0,0,0,0,0,0,0,0)';
      PINUSE='POWER';
      NO_LOAD_CHECK='Both';
      NO_IO_CHECK='Both';
      NO_ASSERT_CHECK='TRUE';
      NO_DIR_CHECK='TRUE';
      ALLOW_CONNECT='TRUE';
    'VSS_AG28':
      PIN_NUMBER='(0,0,0,0,0,0,0,0,0,0,0,0,0,0,0,0,0,0,0,0,0,0,0,0,0,0,0,0,0,0,A~
G28,0,0,0,0,0,0,0,0,0)';
      PINUSE='POWER';
      NO_LOAD_CHECK='Both';
      NO_IO_CHECK='Both';
      NO_ASSERT_CHECK='TRUE';
      NO_DIR_CHECK='TRUE';
      ALLOW_CONNECT='TRUE';
    'VSS_AG31':
      PIN_NUMBER='(0,0,0,0,0,0,0,0,0,0,0,0,0,0,0,0,0,0,0,0,0,0,0,0,0,0,0,0,0,0,A~
G31,0,0,0,0,0,0,0,0,0)';
      PINUSE='POWER';
      NO_LOAD_CHECK='Both';
      NO_IO_CHECK='Both';
      NO_ASSERT_CHECK='TRUE';
      NO_DIR_CHECK='TRUE';
      ALLOW_CONNECT='TRUE';
    'VSS_AG34':
      PIN_NUMBER='(0,0,0,0,0,0,0,0,0,0,0,0,0,0,0,0,0,0,0,0,0,0,0,0,0,0,0,0,0,0,A~
G34,0,0,0,0,0,0,0,0,0)';
      PINUSE='POWER';
      NO_LOAD_CHECK='Both';
      NO_IO_CHECK='Both';
      NO_ASSERT_CHECK='TRUE';
      NO_DIR_CHECK='TRUE';
      ALLOW_CONNECT='TRUE';
    'VSS_AG42':
      PIN_NUMBER='(0,0,0,0,0,0,0,0,0,0,0,0,0,0,0,0,0,0,0,0,0,0,0,0,0,0,0,0,0,0,A~
G42,0,0,0,0,0,0,0,0,0)';
      PINUSE='POWER';
      NO_LOAD_CHECK='Both';
      NO_IO_CHECK='Both';
      NO_ASSERT_CHECK='TRUE';
      NO_DIR_CHECK='TRUE';
      ALLOW_CONNECT='TRUE';
    'VSS_AG45':
      PIN_NUMBER='(0,0,0,0,0,0,0,0,0,0,0,0,0,0,0,0,0,0,0,0,0,0,0,0,0,0,0,0,0,0,A~
G45,0,0,0,0,0,0,0,0,0)';
      PINUSE='POWER';
      NO_LOAD_CHECK='Both';
      NO_IO_CHECK='Both';
      NO_ASSERT_CHECK='TRUE';
      NO_DIR_CHECK='TRUE';
      ALLOW_CONNECT='TRUE';
    'VSS_AG48':
      PIN_NUMBER='(0,0,0,0,0,0,0,0,0,0,0,0,0,0,0,0,0,0,0,0,0,0,0,0,0,0,0,0,0,0,A~
G48,0,0,0,0,0,0,0,0,0)';
      PINUSE='POWER';
      NO_LOAD_CHECK='Both';
      NO_IO_CHECK='Both';
      NO_ASSERT_CHECK='TRUE';
      NO_DIR_CHECK='TRUE';
      ALLOW_CONNECT='TRUE';
    'VSS_AG51':
      PIN_NUMBER='(0,0,0,0,0,0,0,0,0,0,0,0,0,0,0,0,0,0,0,0,0,0,0,0,0,0,0,0,0,0,A~
G51,0,0,0,0,0,0,0,0,0)';
      PINUSE='POWER';
      NO_LOAD_CHECK='Both';
      NO_IO_CHECK='Both';
      NO_ASSERT_CHECK='TRUE';
      NO_DIR_CHECK='TRUE';
      ALLOW_CONNECT='TRUE';
    'VSS_AG54':
      PIN_NUMBER='(0,0,0,0,0,0,0,0,0,0,0,0,0,0,0,0,0,0,0,0,0,0,0,0,0,0,0,0,0,0,A~
G54,0,0,0,0,0,0,0,0,0)';
      PINUSE='POWER';
      NO_LOAD_CHECK='Both';
      NO_IO_CHECK='Both';
      NO_ASSERT_CHECK='TRUE';
      NO_DIR_CHECK='TRUE';
      ALLOW_CONNECT='TRUE';
    'VSS_AG56':
      PIN_NUMBER='(0,0,0,0,0,0,0,0,0,0,0,0,0,0,0,0,0,0,0,0,0,0,0,0,0,0,0,0,0,0,A~
G56,0,0,0,0,0,0,0,0,0)';
      PINUSE='POWER';
      NO_LOAD_CHECK='Both';
      NO_IO_CHECK='Both';
      NO_ASSERT_CHECK='TRUE';
      NO_DIR_CHECK='TRUE';
      ALLOW_CONNECT='TRUE';
    'VSS_AG58':
      PIN_NUMBER='(0,0,0,0,0,0,0,0,0,0,0,0,0,0,0,0,0,0,0,0,0,0,0,0,0,0,0,0,0,0,A~
G58,0,0,0,0,0,0,0,0,0)';
      PINUSE='POWER';
      NO_LOAD_CHECK='Both';
      NO_IO_CHECK='Both';
      NO_ASSERT_CHECK='TRUE';
      NO_DIR_CHECK='TRUE';
      ALLOW_CONNECT='TRUE';
    'VSS_AG61':
      PIN_NUMBER='(0,0,0,0,0,0,0,0,0,0,0,0,0,0,0,0,0,0,0,0,0,0,0,0,0,0,0,0,0,0,A~
G61,0,0,0,0,0,0,0,0,0)';
      PINUSE='POWER';
      NO_LOAD_CHECK='Both';
      NO_IO_CHECK='Both';
      NO_ASSERT_CHECK='TRUE';
      NO_DIR_CHECK='TRUE';
      ALLOW_CONNECT='TRUE';
    'VSS_AG63':
      PIN_NUMBER='(0,0,0,0,0,0,0,0,0,0,0,0,0,0,0,0,0,0,0,0,0,0,0,0,0,0,0,0,0,0,A~
G63,0,0,0,0,0,0,0,0,0)';
      PINUSE='POWER';
      NO_LOAD_CHECK='Both';
      NO_IO_CHECK='Both';
      NO_ASSERT_CHECK='TRUE';
      NO_DIR_CHECK='TRUE';
      ALLOW_CONNECT='TRUE';
    'VSS_AG65':
      PIN_NUMBER='(0,0,0,0,0,0,0,0,0,0,0,0,0,0,0,0,0,0,0,0,0,0,0,0,0,0,0,0,0,0,A~
G65,0,0,0,0,0,0,0,0,0)';
      PINUSE='POWER';
      NO_LOAD_CHECK='Both';
      NO_IO_CHECK='Both';
      NO_ASSERT_CHECK='TRUE';
      NO_DIR_CHECK='TRUE';
      ALLOW_CONNECT='TRUE';
    'VSS_AG68':
      PIN_NUMBER='(0,0,0,0,0,0,0,0,0,0,0,0,0,0,0,0,0,0,0,0,0,0,0,0,0,0,0,0,0,0,A~
G68,0,0,0,0,0,0,0,0,0)';
      PINUSE='POWER';
      NO_LOAD_CHECK='Both';
      NO_IO_CHECK='Both';
      NO_ASSERT_CHECK='TRUE';
      NO_DIR_CHECK='TRUE';
      ALLOW_CONNECT='TRUE';
    'VSS_AG70':
      PIN_NUMBER='(0,0,0,0,0,0,0,0,0,0,0,0,0,0,0,0,0,0,0,0,0,0,0,0,0,0,0,0,0,0,A~
G70,0,0,0,0,0,0,0,0,0)';
      PINUSE='POWER';
      NO_LOAD_CHECK='Both';
      NO_IO_CHECK='Both';
      NO_ASSERT_CHECK='TRUE';
      NO_DIR_CHECK='TRUE';
      ALLOW_CONNECT='TRUE';
    'VSS_AG72':
      PIN_NUMBER='(0,0,0,0,0,0,0,0,0,0,0,0,0,0,0,0,0,0,0,0,0,0,0,0,0,0,0,0,0,0,A~
G72,0,0,0,0,0,0,0,0,0)';
      PINUSE='POWER';
      NO_LOAD_CHECK='Both';
      NO_IO_CHECK='Both';
      NO_ASSERT_CHECK='TRUE';
      NO_DIR_CHECK='TRUE';
      ALLOW_CONNECT='TRUE';
    'VSS_AG75':
      PIN_NUMBER='(0,0,0,0,0,0,0,0,0,0,0,0,0,0,0,0,0,0,0,0,0,0,0,0,0,0,0,0,0,0,A~
G75,0,0,0,0,0,0,0,0,0)';
      PINUSE='POWER';
      NO_LOAD_CHECK='Both';
      NO_IO_CHECK='Both';
      NO_ASSERT_CHECK='TRUE';
      NO_DIR_CHECK='TRUE';
      ALLOW_CONNECT='TRUE';
    'VSS_AH3':
      PIN_NUMBER='(0,0,0,0,0,0,0,0,0,0,0,0,0,0,0,0,0,0,0,0,0,0,0,0,0,0,0,0,0,0,A~
H3,0,0,0,0,0,0,0,0,0)';
      PINUSE='POWER';
      NO_LOAD_CHECK='Both';
      NO_IO_CHECK='Both';
      NO_ASSERT_CHECK='TRUE';
      NO_DIR_CHECK='TRUE';
      ALLOW_CONNECT='TRUE';
    'VSS_AH5':
      PIN_NUMBER='(0,0,0,0,0,0,0,0,0,0,0,0,0,0,0,0,0,0,0,0,0,0,0,0,0,0,0,0,0,0,A~
H5,0,0,0,0,0,0,0,0,0)';
      PINUSE='POWER';
      NO_LOAD_CHECK='Both';
      NO_IO_CHECK='Both';
      NO_ASSERT_CHECK='TRUE';
      NO_DIR_CHECK='TRUE';
      ALLOW_CONNECT='TRUE';
    'VSS_AH8':
      PIN_NUMBER='(0,0,0,0,0,0,0,0,0,0,0,0,0,0,0,0,0,0,0,0,0,0,0,0,0,0,0,0,0,0,A~
H8,0,0,0,0,0,0,0,0,0)';
      PINUSE='POWER';
      NO_LOAD_CHECK='Both';
      NO_IO_CHECK='Both';
      NO_ASSERT_CHECK='TRUE';
      NO_DIR_CHECK='TRUE';
      ALLOW_CONNECT='TRUE';
    'VSS_AH10':
      PIN_NUMBER='(0,0,0,0,0,0,0,0,0,0,0,0,0,0,0,0,0,0,0,0,0,0,0,0,0,0,0,0,0,0,A~
H10,0,0,0,0,0,0,0,0,0)';
      PINUSE='POWER';
      NO_LOAD_CHECK='Both';
      NO_IO_CHECK='Both';
      NO_ASSERT_CHECK='TRUE';
      NO_DIR_CHECK='TRUE';
      ALLOW_CONNECT='TRUE';
    'VSS_AH12':
      PIN_NUMBER='(0,0,0,0,0,0,0,0,0,0,0,0,0,0,0,0,0,0,0,0,0,0,0,0,0,0,0,0,0,0,A~
H12,0,0,0,0,0,0,0,0,0)';
      PINUSE='POWER';
      NO_LOAD_CHECK='Both';
      NO_IO_CHECK='Both';
      NO_ASSERT_CHECK='TRUE';
      NO_DIR_CHECK='TRUE';
      ALLOW_CONNECT='TRUE';
    'VSS_AH15':
      PIN_NUMBER='(0,0,0,0,0,0,0,0,0,0,0,0,0,0,0,0,0,0,0,0,0,0,0,0,0,0,0,0,0,0,A~
H15,0,0,0,0,0,0,0,0,0)';
      PINUSE='POWER';
      NO_LOAD_CHECK='Both';
      NO_IO_CHECK='Both';
      NO_ASSERT_CHECK='TRUE';
      NO_DIR_CHECK='TRUE';
      ALLOW_CONNECT='TRUE';
    'VSS_AH17':
      PIN_NUMBER='(0,0,0,0,0,0,0,0,0,0,0,0,0,0,0,0,0,0,0,0,0,0,0,0,0,0,0,0,0,0,A~
H17,0,0,0,0,0,0,0,0,0)';
      PINUSE='POWER';
      NO_LOAD_CHECK='Both';
      NO_IO_CHECK='Both';
      NO_ASSERT_CHECK='TRUE';
      NO_DIR_CHECK='TRUE';
      ALLOW_CONNECT='TRUE';
    'VSS_AH19':
      PIN_NUMBER='(0,0,0,0,0,0,0,0,0,0,0,0,0,0,0,0,0,0,0,0,0,0,0,0,0,0,0,0,0,0,A~
H19,0,0,0,0,0,0,0,0,0)';
      PINUSE='POWER';
      NO_LOAD_CHECK='Both';
      NO_IO_CHECK='Both';
      NO_ASSERT_CHECK='TRUE';
      NO_DIR_CHECK='TRUE';
      ALLOW_CONNECT='TRUE';
    'VSS_AH23':
      PIN_NUMBER='(0,0,0,0,0,0,0,0,0,0,0,0,0,0,0,0,0,0,0,0,0,0,0,0,0,0,0,0,0,0,A~
H23,0,0,0,0,0,0,0,0,0)';
      PINUSE='POWER';
      NO_LOAD_CHECK='Both';
      NO_IO_CHECK='Both';
      NO_ASSERT_CHECK='TRUE';
      NO_DIR_CHECK='TRUE';
      ALLOW_CONNECT='TRUE';
    'VSS_AH24':
      PIN_NUMBER='(0,0,0,0,0,0,0,0,0,0,0,0,0,0,0,0,0,0,0,0,0,0,0,0,0,0,0,0,0,0,A~
H24,0,0,0,0,0,0,0,0,0)';
      PINUSE='POWER';
      NO_LOAD_CHECK='Both';
      NO_IO_CHECK='Both';
      NO_ASSERT_CHECK='TRUE';
      NO_DIR_CHECK='TRUE';
      ALLOW_CONNECT='TRUE';
    'VSS_AH25':
      PIN_NUMBER='(0,0,0,0,0,0,0,0,0,0,0,0,0,0,0,0,0,0,0,0,0,0,0,0,0,0,0,0,0,0,A~
H25,0,0,0,0,0,0,0,0,0)';
      PINUSE='POWER';
      NO_LOAD_CHECK='Both';
      NO_IO_CHECK='Both';
      NO_ASSERT_CHECK='TRUE';
      NO_DIR_CHECK='TRUE';
      ALLOW_CONNECT='TRUE';
    'VSS_AH26':
      PIN_NUMBER='(0,0,0,0,0,0,0,0,0,0,0,0,0,0,0,0,0,0,0,0,0,0,0,0,0,0,0,0,0,0,A~
H26,0,0,0,0,0,0,0,0,0)';
      PINUSE='POWER';
      NO_LOAD_CHECK='Both';
      NO_IO_CHECK='Both';
      NO_ASSERT_CHECK='TRUE';
      NO_DIR_CHECK='TRUE';
      ALLOW_CONNECT='TRUE';
    'VSS_AH27':
      PIN_NUMBER='(0,0,0,0,0,0,0,0,0,0,0,0,0,0,0,0,0,0,0,0,0,0,0,0,0,0,0,0,0,0,A~
H27,0,0,0,0,0,0,0,0,0)';
      PINUSE='POWER';
      NO_LOAD_CHECK='Both';
      NO_IO_CHECK='Both';
      NO_ASSERT_CHECK='TRUE';
      NO_DIR_CHECK='TRUE';
      ALLOW_CONNECT='TRUE';
    'VSS_AH28':
      PIN_NUMBER='(0,0,0,0,0,0,0,0,0,0,0,0,0,0,0,0,0,0,0,0,0,0,0,0,0,0,0,0,0,0,A~
H28,0,0,0,0,0,0,0,0,0)';
      PINUSE='POWER';
      NO_LOAD_CHECK='Both';
      NO_IO_CHECK='Both';
      NO_ASSERT_CHECK='TRUE';
      NO_DIR_CHECK='TRUE';
      ALLOW_CONNECT='TRUE';
    'VSS_AH29':
      PIN_NUMBER='(0,0,0,0,0,0,0,0,0,0,0,0,0,0,0,0,0,0,0,0,0,0,0,0,0,0,0,0,0,0,A~
H29,0,0,0,0,0,0,0,0,0)';
      PINUSE='POWER';
      NO_LOAD_CHECK='Both';
      NO_IO_CHECK='Both';
      NO_ASSERT_CHECK='TRUE';
      NO_DIR_CHECK='TRUE';
      ALLOW_CONNECT='TRUE';
    'VSS_AH30':
      PIN_NUMBER='(0,0,0,0,0,0,0,0,0,0,0,0,0,0,0,0,0,0,0,0,0,0,0,0,0,0,0,0,0,0,A~
H30,0,0,0,0,0,0,0,0,0)';
      PINUSE='POWER';
      NO_LOAD_CHECK='Both';
      NO_IO_CHECK='Both';
      NO_ASSERT_CHECK='TRUE';
      NO_DIR_CHECK='TRUE';
      ALLOW_CONNECT='TRUE';
    'VSS_AH31':
      PIN_NUMBER='(0,0,0,0,0,0,0,0,0,0,0,0,0,0,0,0,0,0,0,0,0,0,0,0,0,0,0,0,0,0,A~
H31,0,0,0,0,0,0,0,0,0)';
      PINUSE='POWER';
      NO_LOAD_CHECK='Both';
      NO_IO_CHECK='Both';
      NO_ASSERT_CHECK='TRUE';
      NO_DIR_CHECK='TRUE';
      ALLOW_CONNECT='TRUE';
    'VSS_AH32':
      PIN_NUMBER='(0,0,0,0,0,0,0,0,0,0,0,0,0,0,0,0,0,0,0,0,0,0,0,0,0,0,0,0,0,0,A~
H32,0,0,0,0,0,0,0,0,0)';
      PINUSE='POWER';
      NO_LOAD_CHECK='Both';
      NO_IO_CHECK='Both';
      NO_ASSERT_CHECK='TRUE';
      NO_DIR_CHECK='TRUE';
      ALLOW_CONNECT='TRUE';
    'VSS_AH34':
      PIN_NUMBER='(0,0,0,0,0,0,0,0,0,0,0,0,0,0,0,0,0,0,0,0,0,0,0,0,0,0,0,0,0,0,A~
H34,0,0,0,0,0,0,0,0,0)';
      PINUSE='POWER';
      NO_LOAD_CHECK='Both';
      NO_IO_CHECK='Both';
      NO_ASSERT_CHECK='TRUE';
      NO_DIR_CHECK='TRUE';
      ALLOW_CONNECT='TRUE';
    'VSS_AH37':
      PIN_NUMBER='(0,0,0,0,0,0,0,0,0,0,0,0,0,0,0,0,0,0,0,0,0,0,0,0,0,0,0,0,0,0,A~
H37,0,0,0,0,0,0,0,0,0)';
      PINUSE='POWER';
      NO_LOAD_CHECK='Both';
      NO_IO_CHECK='Both';
      NO_ASSERT_CHECK='TRUE';
      NO_DIR_CHECK='TRUE';
      ALLOW_CONNECT='TRUE';
    'VSS_AH39':
      PIN_NUMBER='(0,0,0,0,0,0,0,0,0,0,0,0,0,0,0,0,0,0,0,0,0,0,0,0,0,0,0,0,0,0,A~
H39,0,0,0,0,0,0,0,0,0)';
      PINUSE='POWER';
      NO_LOAD_CHECK='Both';
      NO_IO_CHECK='Both';
      NO_ASSERT_CHECK='TRUE';
      NO_DIR_CHECK='TRUE';
      ALLOW_CONNECT='TRUE';
    'VSS_AH42':
      PIN_NUMBER='(0,0,0,0,0,0,0,0,0,0,0,0,0,0,0,0,0,0,0,0,0,0,0,0,0,0,0,0,0,0,A~
H42,0,0,0,0,0,0,0,0,0)';
      PINUSE='POWER';
      NO_LOAD_CHECK='Both';
      NO_IO_CHECK='Both';
      NO_ASSERT_CHECK='TRUE';
      NO_DIR_CHECK='TRUE';
      ALLOW_CONNECT='TRUE';
    'VSS_AH43':
      PIN_NUMBER='(0,0,0,0,0,0,0,0,0,0,0,0,0,0,0,0,0,0,0,0,0,0,0,0,0,0,0,0,0,0,A~
H43,0,0,0,0,0,0,0,0,0)';
      PINUSE='POWER';
      NO_LOAD_CHECK='Both';
      NO_IO_CHECK='Both';
      NO_ASSERT_CHECK='TRUE';
      NO_DIR_CHECK='TRUE';
      ALLOW_CONNECT='TRUE';
    'VSS_AH44':
      PIN_NUMBER='(0,0,0,0,0,0,0,0,0,0,0,0,0,0,0,0,0,0,0,0,0,0,0,0,0,0,0,0,0,0,A~
H44,0,0,0,0,0,0,0,0,0)';
      PINUSE='POWER';
      NO_LOAD_CHECK='Both';
      NO_IO_CHECK='Both';
      NO_ASSERT_CHECK='TRUE';
      NO_DIR_CHECK='TRUE';
      ALLOW_CONNECT='TRUE';
    'VSS_AH45':
      PIN_NUMBER='(0,0,0,0,0,0,0,0,0,0,0,0,0,0,0,0,0,0,0,0,0,0,0,0,0,0,0,0,0,0,A~
H45,0,0,0,0,0,0,0,0,0)';
      PINUSE='POWER';
      NO_LOAD_CHECK='Both';
      NO_IO_CHECK='Both';
      NO_ASSERT_CHECK='TRUE';
      NO_DIR_CHECK='TRUE';
      ALLOW_CONNECT='TRUE';
    'VSS_AH46':
      PIN_NUMBER='(0,0,0,0,0,0,0,0,0,0,0,0,0,0,0,0,0,0,0,0,0,0,0,0,0,0,0,0,0,0,A~
H46,0,0,0,0,0,0,0,0,0)';
      PINUSE='POWER';
      NO_LOAD_CHECK='Both';
      NO_IO_CHECK='Both';
      NO_ASSERT_CHECK='TRUE';
      NO_DIR_CHECK='TRUE';
      ALLOW_CONNECT='TRUE';
    'VSS_AH47':
      PIN_NUMBER='(0,0,0,0,0,0,0,0,0,0,0,0,0,0,0,0,0,0,0,0,0,0,0,0,0,0,0,0,0,0,A~
H47,0,0,0,0,0,0,0,0,0)';
      PINUSE='POWER';
      NO_LOAD_CHECK='Both';
      NO_IO_CHECK='Both';
      NO_ASSERT_CHECK='TRUE';
      NO_DIR_CHECK='TRUE';
      ALLOW_CONNECT='TRUE';
    'VSS_AH48':
      PIN_NUMBER='(0,0,0,0,0,0,0,0,0,0,0,0,0,0,0,0,0,0,0,0,0,0,0,0,0,0,0,0,0,0,A~
H48,0,0,0,0,0,0,0,0,0)';
      PINUSE='POWER';
      NO_LOAD_CHECK='Both';
      NO_IO_CHECK='Both';
      NO_ASSERT_CHECK='TRUE';
      NO_DIR_CHECK='TRUE';
      ALLOW_CONNECT='TRUE';
    'VSS_AH49':
      PIN_NUMBER='(0,0,0,0,0,0,0,0,0,0,0,0,0,0,0,0,0,0,0,0,0,0,0,0,0,0,0,0,0,0,A~
H49,0,0,0,0,0,0,0,0,0)';
      PINUSE='POWER';
      NO_LOAD_CHECK='Both';
      NO_IO_CHECK='Both';
      NO_ASSERT_CHECK='TRUE';
      NO_DIR_CHECK='TRUE';
      ALLOW_CONNECT='TRUE';
    'VSS_AH50':
      PIN_NUMBER='(0,0,0,0,0,0,0,0,0,0,0,0,0,0,0,0,0,0,0,0,0,0,0,0,0,0,0,0,0,0,A~
H50,0,0,0,0,0,0,0,0,0)';
      PINUSE='POWER';
      NO_LOAD_CHECK='Both';
      NO_IO_CHECK='Both';
      NO_ASSERT_CHECK='TRUE';
      NO_DIR_CHECK='TRUE';
      ALLOW_CONNECT='TRUE';
    'VSS_AH51':
      PIN_NUMBER='(0,0,0,0,0,0,0,0,0,0,0,0,0,0,0,0,0,0,0,0,0,0,0,0,0,0,0,0,0,0,A~
H51,0,0,0,0,0,0,0,0,0)';
      PINUSE='POWER';
      NO_LOAD_CHECK='Both';
      NO_IO_CHECK='Both';
      NO_ASSERT_CHECK='TRUE';
      NO_DIR_CHECK='TRUE';
      ALLOW_CONNECT='TRUE';
    'VSS_AH52':
      PIN_NUMBER='(0,0,0,0,0,0,0,0,0,0,0,0,0,0,0,0,0,0,0,0,0,0,0,0,0,0,0,0,0,0,A~
H52,0,0,0,0,0,0,0,0,0)';
      PINUSE='POWER';
      NO_LOAD_CHECK='Both';
      NO_IO_CHECK='Both';
      NO_ASSERT_CHECK='TRUE';
      NO_DIR_CHECK='TRUE';
      ALLOW_CONNECT='TRUE';
    'VSS_AH53':
      PIN_NUMBER='(0,0,0,0,0,0,0,0,0,0,0,0,0,0,0,0,0,0,0,0,0,0,0,0,0,0,0,0,0,0,A~
H53,0,0,0,0,0,0,0,0,0)';
      PINUSE='POWER';
      NO_LOAD_CHECK='Both';
      NO_IO_CHECK='Both';
      NO_ASSERT_CHECK='TRUE';
      NO_DIR_CHECK='TRUE';
      ALLOW_CONNECT='TRUE';
    'VSS_AH57':
      PIN_NUMBER='(0,0,0,0,0,0,0,0,0,0,0,0,0,0,0,0,0,0,0,0,0,0,0,0,0,0,0,0,0,0,A~
H57,0,0,0,0,0,0,0,0,0)';
      PINUSE='POWER';
      NO_LOAD_CHECK='Both';
      NO_IO_CHECK='Both';
      NO_ASSERT_CHECK='TRUE';
      NO_DIR_CHECK='TRUE';
      ALLOW_CONNECT='TRUE';
    'VSS_AH59':
      PIN_NUMBER='(0,0,0,0,0,0,0,0,0,0,0,0,0,0,0,0,0,0,0,0,0,0,0,0,0,0,0,0,0,0,A~
H59,0,0,0,0,0,0,0,0,0)';
      PINUSE='POWER';
      NO_LOAD_CHECK='Both';
      NO_IO_CHECK='Both';
      NO_ASSERT_CHECK='TRUE';
      NO_DIR_CHECK='TRUE';
      ALLOW_CONNECT='TRUE';
    'VSS_AH61':
      PIN_NUMBER='(0,0,0,0,0,0,0,0,0,0,0,0,0,0,0,0,0,0,0,0,0,0,0,0,0,0,0,0,0,0,A~
H61,0,0,0,0,0,0,0,0,0)';
      PINUSE='POWER';
      NO_LOAD_CHECK='Both';
      NO_IO_CHECK='Both';
      NO_ASSERT_CHECK='TRUE';
      NO_DIR_CHECK='TRUE';
      ALLOW_CONNECT='TRUE';
    'VSS_AH64':
      PIN_NUMBER='(0,0,0,0,0,0,0,0,0,0,0,0,0,0,0,0,0,0,0,0,0,0,0,0,0,0,0,0,0,0,A~
H64,0,0,0,0,0,0,0,0,0)';
      PINUSE='POWER';
      NO_LOAD_CHECK='Both';
      NO_IO_CHECK='Both';
      NO_ASSERT_CHECK='TRUE';
      NO_DIR_CHECK='TRUE';
      ALLOW_CONNECT='TRUE';
    'VSS_AH66':
      PIN_NUMBER='(0,0,0,0,0,0,0,0,0,0,0,0,0,0,0,0,0,0,0,0,0,0,0,0,0,0,0,0,0,0,A~
H66,0,0,0,0,0,0,0,0,0)';
      PINUSE='POWER';
      NO_LOAD_CHECK='Both';
      NO_IO_CHECK='Both';
      NO_ASSERT_CHECK='TRUE';
      NO_DIR_CHECK='TRUE';
      ALLOW_CONNECT='TRUE';
    'VSS_AH68':
      PIN_NUMBER='(0,0,0,0,0,0,0,0,0,0,0,0,0,0,0,0,0,0,0,0,0,0,0,0,0,0,0,0,0,0,A~
H68,0,0,0,0,0,0,0,0,0)';
      PINUSE='POWER';
      NO_LOAD_CHECK='Both';
      NO_IO_CHECK='Both';
      NO_ASSERT_CHECK='TRUE';
      NO_DIR_CHECK='TRUE';
      ALLOW_CONNECT='TRUE';
    'VSS_AH71':
      PIN_NUMBER='(0,0,0,0,0,0,0,0,0,0,0,0,0,0,0,0,0,0,0,0,0,0,0,0,0,0,0,0,0,0,A~
H71,0,0,0,0,0,0,0,0,0)';
      PINUSE='POWER';
      NO_LOAD_CHECK='Both';
      NO_IO_CHECK='Both';
      NO_ASSERT_CHECK='TRUE';
      NO_DIR_CHECK='TRUE';
      ALLOW_CONNECT='TRUE';
    'VSS_AH73':
      PIN_NUMBER='(0,0,0,0,0,0,0,0,0,0,0,0,0,0,0,0,0,0,0,0,0,0,0,0,0,0,0,0,0,0,A~
H73,0,0,0,0,0,0,0,0,0)';
      PINUSE='POWER';
      NO_LOAD_CHECK='Both';
      NO_IO_CHECK='Both';
      NO_ASSERT_CHECK='TRUE';
      NO_DIR_CHECK='TRUE';
      ALLOW_CONNECT='TRUE';
    'VSS_AJ1':
      PIN_NUMBER='(0,0,0,0,0,0,0,0,0,0,0,0,0,0,0,0,0,0,0,0,0,0,0,0,0,0,0,0,0,0,A~
J1,0,0,0,0,0,0,0,0,0)';
      PINUSE='POWER';
      NO_LOAD_CHECK='Both';
      NO_IO_CHECK='Both';
      NO_ASSERT_CHECK='TRUE';
      NO_DIR_CHECK='TRUE';
      ALLOW_CONNECT='TRUE';
    'VSS_AJ6':
      PIN_NUMBER='(0,0,0,0,0,0,0,0,0,0,0,0,0,0,0,0,0,0,0,0,0,0,0,0,0,0,0,0,0,0,A~
J6,0,0,0,0,0,0,0,0,0)';
      PINUSE='POWER';
      NO_LOAD_CHECK='Both';
      NO_IO_CHECK='Both';
      NO_ASSERT_CHECK='TRUE';
      NO_DIR_CHECK='TRUE';
      ALLOW_CONNECT='TRUE';
    'VSS_AJ8':
      PIN_NUMBER='(0,0,0,0,0,0,0,0,0,0,0,0,0,0,0,0,0,0,0,0,0,0,0,0,0,0,0,0,0,0,A~
J8,0,0,0,0,0,0,0,0,0)';
      PINUSE='POWER';
      NO_LOAD_CHECK='Both';
      NO_IO_CHECK='Both';
      NO_ASSERT_CHECK='TRUE';
      NO_DIR_CHECK='TRUE';
      ALLOW_CONNECT='TRUE';
    'VSS_AJ15':
      PIN_NUMBER='(0,0,0,0,0,0,0,0,0,0,0,0,0,0,0,0,0,0,0,0,0,0,0,0,0,0,0,0,0,0,A~
J15,0,0,0,0,0,0,0,0,0)';
      PINUSE='POWER';
      NO_LOAD_CHECK='Both';
      NO_IO_CHECK='Both';
      NO_ASSERT_CHECK='TRUE';
      NO_DIR_CHECK='TRUE';
      ALLOW_CONNECT='TRUE';
    'VSS_AJ20':
      PIN_NUMBER='(0,0,0,0,0,0,0,0,0,0,0,0,0,0,0,0,0,0,0,0,0,0,0,0,0,0,0,0,0,0,A~
J20,0,0,0,0,0,0,0,0,0)';
      PINUSE='POWER';
      NO_LOAD_CHECK='Both';
      NO_IO_CHECK='Both';
      NO_ASSERT_CHECK='TRUE';
      NO_DIR_CHECK='TRUE';
      ALLOW_CONNECT='TRUE';
    'VSS_AJ22':
      PIN_NUMBER='(0,0,0,0,0,0,0,0,0,0,0,0,0,0,0,0,0,0,0,0,0,0,0,0,0,0,0,0,0,0,A~
J22,0,0,0,0,0,0,0,0,0)';
      PINUSE='POWER';
      NO_LOAD_CHECK='Both';
      NO_IO_CHECK='Both';
      NO_ASSERT_CHECK='TRUE';
      NO_DIR_CHECK='TRUE';
      ALLOW_CONNECT='TRUE';
    'VSS_AJ25':
      PIN_NUMBER='(0,0,0,0,0,0,0,0,0,0,0,0,0,0,0,0,0,0,0,0,0,0,0,0,0,0,0,0,0,0,A~
J25,0,0,0,0,0,0,0,0,0)';
      PINUSE='POWER';
      NO_LOAD_CHECK='Both';
      NO_IO_CHECK='Both';
      NO_ASSERT_CHECK='TRUE';
      NO_DIR_CHECK='TRUE';
      ALLOW_CONNECT='TRUE';
    'VSS_AJ28':
      PIN_NUMBER='(0,0,0,0,0,0,0,0,0,0,0,0,0,0,0,0,0,0,0,0,0,0,0,0,0,0,0,0,0,0,A~
J28,0,0,0,0,0,0,0,0,0)';
      PINUSE='POWER';
      NO_LOAD_CHECK='Both';
      NO_IO_CHECK='Both';
      NO_ASSERT_CHECK='TRUE';
      NO_DIR_CHECK='TRUE';
      ALLOW_CONNECT='TRUE';
    'VSS_AJ31':
      PIN_NUMBER='(0,0,0,0,0,0,0,0,0,0,0,0,0,0,0,0,0,0,0,0,0,0,0,0,0,0,0,0,0,0,A~
J31,0,0,0,0,0,0,0,0,0)';
      PINUSE='POWER';
      NO_LOAD_CHECK='Both';
      NO_IO_CHECK='Both';
      NO_ASSERT_CHECK='TRUE';
      NO_DIR_CHECK='TRUE';
      ALLOW_CONNECT='TRUE';
    'VSS_AJ34':
      PIN_NUMBER='(0,0,0,0,0,0,0,0,0,0,0,0,0,0,0,0,0,0,0,0,0,0,0,0,0,0,0,0,0,0,A~
J34,0,0,0,0,0,0,0,0,0)';
      PINUSE='POWER';
      NO_LOAD_CHECK='Both';
      NO_IO_CHECK='Both';
      NO_ASSERT_CHECK='TRUE';
      NO_DIR_CHECK='TRUE';
      ALLOW_CONNECT='TRUE';
    'VSS_AJ35':
      PIN_NUMBER='(0,0,0,0,0,0,0,0,0,0,0,0,0,0,0,0,0,0,0,0,0,0,0,0,0,0,0,0,0,0,A~
J35,0,0,0,0,0,0,0,0,0)';
      PINUSE='POWER';
      NO_LOAD_CHECK='Both';
      NO_IO_CHECK='Both';
      NO_ASSERT_CHECK='TRUE';
      NO_DIR_CHECK='TRUE';
      ALLOW_CONNECT='TRUE';
    'VSS_AJ36':
      PIN_NUMBER='(0,0,0,0,0,0,0,0,0,0,0,0,0,0,0,0,0,0,0,0,0,0,0,0,0,0,0,0,0,0,A~
J36,0,0,0,0,0,0,0,0,0)';
      PINUSE='POWER';
      NO_LOAD_CHECK='Both';
      NO_IO_CHECK='Both';
      NO_ASSERT_CHECK='TRUE';
      NO_DIR_CHECK='TRUE';
      ALLOW_CONNECT='TRUE';
    'VSS_AJ40':
      PIN_NUMBER='(0,0,0,0,0,0,0,0,0,0,0,0,0,0,0,0,0,0,0,0,0,0,0,0,0,0,0,0,0,0,A~
J40,0,0,0,0,0,0,0,0,0)';
      PINUSE='POWER';
      NO_LOAD_CHECK='Both';
      NO_IO_CHECK='Both';
      NO_ASSERT_CHECK='TRUE';
      NO_DIR_CHECK='TRUE';
      ALLOW_CONNECT='TRUE';
    'VSS_AJ41':
      PIN_NUMBER='(0,0,0,0,0,0,0,0,0,0,0,0,0,0,0,0,0,0,0,0,0,0,0,0,0,0,0,0,0,0,A~
J41,0,0,0,0,0,0,0,0,0)';
      PINUSE='POWER';
      NO_LOAD_CHECK='Both';
      NO_IO_CHECK='Both';
      NO_ASSERT_CHECK='TRUE';
      NO_DIR_CHECK='TRUE';
      ALLOW_CONNECT='TRUE';
    'VSS_AJ42':
      PIN_NUMBER='(0,0,0,0,0,0,0,0,0,0,0,0,0,0,0,0,0,0,0,0,0,0,0,0,0,0,0,0,0,0,A~
J42,0,0,0,0,0,0,0,0,0)';
      PINUSE='POWER';
      NO_LOAD_CHECK='Both';
      NO_IO_CHECK='Both';
      NO_ASSERT_CHECK='TRUE';
      NO_DIR_CHECK='TRUE';
      ALLOW_CONNECT='TRUE';
    'VSS_AJ45':
      PIN_NUMBER='(0,0,0,0,0,0,0,0,0,0,0,0,0,0,0,0,0,0,0,0,0,0,0,0,0,0,0,0,0,0,A~
J45,0,0,0,0,0,0,0,0,0)';
      PINUSE='POWER';
      NO_LOAD_CHECK='Both';
      NO_IO_CHECK='Both';
      NO_ASSERT_CHECK='TRUE';
      NO_DIR_CHECK='TRUE';
      ALLOW_CONNECT='TRUE';
    'VSS_AJ48':
      PIN_NUMBER='(0,0,0,0,0,0,0,0,0,0,0,0,0,0,0,0,0,0,0,0,0,0,0,0,0,0,0,0,0,0,A~
J48,0,0,0,0,0,0,0,0,0)';
      PINUSE='POWER';
      NO_LOAD_CHECK='Both';
      NO_IO_CHECK='Both';
      NO_ASSERT_CHECK='TRUE';
      NO_DIR_CHECK='TRUE';
      ALLOW_CONNECT='TRUE';
    'VSS_AJ51':
      PIN_NUMBER='(0,0,0,0,0,0,0,0,0,0,0,0,0,0,0,0,0,0,0,0,0,0,0,0,0,0,0,0,0,0,A~
J51,0,0,0,0,0,0,0,0,0)';
      PINUSE='POWER';
      NO_LOAD_CHECK='Both';
      NO_IO_CHECK='Both';
      NO_ASSERT_CHECK='TRUE';
      NO_DIR_CHECK='TRUE';
      ALLOW_CONNECT='TRUE';
    'VSS_AJ54':
      PIN_NUMBER='(0,0,0,0,0,0,0,0,0,0,0,0,0,0,0,0,0,0,0,0,0,0,0,0,0,0,0,0,0,0,A~
J54,0,0,0,0,0,0,0,0,0)';
      PINUSE='POWER';
      NO_LOAD_CHECK='Both';
      NO_IO_CHECK='Both';
      NO_ASSERT_CHECK='TRUE';
      NO_DIR_CHECK='TRUE';
      ALLOW_CONNECT='TRUE';
    'VSS_AJ56':
      PIN_NUMBER='(0,0,0,0,0,0,0,0,0,0,0,0,0,0,0,0,0,0,0,0,0,0,0,0,0,0,0,0,0,0,A~
J56,0,0,0,0,0,0,0,0,0)';
      PINUSE='POWER';
      NO_LOAD_CHECK='Both';
      NO_IO_CHECK='Both';
      NO_ASSERT_CHECK='TRUE';
      NO_DIR_CHECK='TRUE';
      ALLOW_CONNECT='TRUE';
    'VSS_AJ61':
      PIN_NUMBER='(0,0,0,0,0,0,0,0,0,0,0,0,0,0,0,0,0,0,0,0,0,0,0,0,0,0,0,0,0,0,A~
J61,0,0,0,0,0,0,0,0,0)';
      PINUSE='POWER';
      NO_LOAD_CHECK='Both';
      NO_IO_CHECK='Both';
      NO_ASSERT_CHECK='TRUE';
      NO_DIR_CHECK='TRUE';
      ALLOW_CONNECT='TRUE';
    'VSS_AJ63':
      PIN_NUMBER='(0,0,0,0,0,0,0,0,0,0,0,0,0,0,0,0,0,0,0,0,0,0,0,0,0,0,0,0,0,0,A~
J63,0,0,0,0,0,0,0,0,0)';
      PINUSE='POWER';
      NO_LOAD_CHECK='Both';
      NO_IO_CHECK='Both';
      NO_ASSERT_CHECK='TRUE';
      NO_DIR_CHECK='TRUE';
      ALLOW_CONNECT='TRUE';
    'VSS_AJ68':
      PIN_NUMBER='(0,0,0,0,0,0,0,0,0,0,0,0,0,0,0,0,0,0,0,0,0,0,0,0,0,0,0,0,0,0,A~
J68,0,0,0,0,0,0,0,0,0)';
      PINUSE='POWER';
      NO_LOAD_CHECK='Both';
      NO_IO_CHECK='Both';
      NO_ASSERT_CHECK='TRUE';
      NO_DIR_CHECK='TRUE';
      ALLOW_CONNECT='TRUE';
    'VSS_AJ70':
      PIN_NUMBER='(0,0,0,0,0,0,0,0,0,0,0,0,0,0,0,0,0,0,0,0,0,0,0,0,0,0,0,0,0,0,A~
J70,0,0,0,0,0,0,0,0,0)';
      PINUSE='POWER';
      NO_LOAD_CHECK='Both';
      NO_IO_CHECK='Both';
      NO_ASSERT_CHECK='TRUE';
      NO_DIR_CHECK='TRUE';
      ALLOW_CONNECT='TRUE';
    'VSS_AJ75':
      PIN_NUMBER='(0,0,0,0,0,0,0,0,0,0,0,0,0,0,0,0,0,0,0,0,0,0,0,0,0,0,0,0,0,0,A~
J75,0,0,0,0,0,0,0,0,0)';
      PINUSE='POWER';
      NO_LOAD_CHECK='Both';
      NO_IO_CHECK='Both';
      NO_ASSERT_CHECK='TRUE';
      NO_DIR_CHECK='TRUE';
      ALLOW_CONNECT='TRUE';
    'VSS_AK3':
      PIN_NUMBER='(0,0,0,0,0,0,0,0,0,0,0,0,0,0,0,0,0,0,0,0,0,0,0,0,0,0,0,0,0,0,A~
K3,0,0,0,0,0,0,0,0,0)';
      PINUSE='POWER';
      NO_LOAD_CHECK='Both';
      NO_IO_CHECK='Both';
      NO_ASSERT_CHECK='TRUE';
      NO_DIR_CHECK='TRUE';
      ALLOW_CONNECT='TRUE';
    'VSS_AK5':
      PIN_NUMBER='(0,0,0,0,0,0,0,0,0,0,0,0,0,0,0,0,0,0,0,0,0,0,0,0,0,0,0,0,0,0,A~
K5,0,0,0,0,0,0,0,0,0)';
      PINUSE='POWER';
      NO_LOAD_CHECK='Both';
      NO_IO_CHECK='Both';
      NO_ASSERT_CHECK='TRUE';
      NO_DIR_CHECK='TRUE';
      ALLOW_CONNECT='TRUE';
    'VSS_AK8':
      PIN_NUMBER='(0,0,0,0,0,0,0,0,0,0,0,0,0,0,0,0,0,0,0,0,0,0,0,0,0,0,0,0,0,0,A~
K8,0,0,0,0,0,0,0,0,0)';
      PINUSE='POWER';
      NO_LOAD_CHECK='Both';
      NO_IO_CHECK='Both';
      NO_ASSERT_CHECK='TRUE';
      NO_DIR_CHECK='TRUE';
      ALLOW_CONNECT='TRUE';
    'VSS_AM42':
      PIN_NUMBER='(0,0,0,0,0,0,0,0,0,0,0,0,0,0,0,0,0,0,0,0,0,0,0,0,0,0,0,0,0,0,0~
,AM42,0,0,0,0,0,0,0,0)';
      PINUSE='POWER';
      NO_LOAD_CHECK='Both';
      NO_IO_CHECK='Both';
      NO_ASSERT_CHECK='TRUE';
      NO_DIR_CHECK='TRUE';
      ALLOW_CONNECT='TRUE';
    'VSS_AM43':
      PIN_NUMBER='(0,0,0,0,0,0,0,0,0,0,0,0,0,0,0,0,0,0,0,0,0,0,0,0,0,0,0,0,0,0,0~
,AM43,0,0,0,0,0,0,0,0)';
      PINUSE='POWER';
      NO_LOAD_CHECK='Both';
      NO_IO_CHECK='Both';
      NO_ASSERT_CHECK='TRUE';
      NO_DIR_CHECK='TRUE';
      ALLOW_CONNECT='TRUE';
    'VSS_AM44':
      PIN_NUMBER='(0,0,0,0,0,0,0,0,0,0,0,0,0,0,0,0,0,0,0,0,0,0,0,0,0,0,0,0,0,0,0~
,AM44,0,0,0,0,0,0,0,0)';
      PINUSE='POWER';
      NO_LOAD_CHECK='Both';
      NO_IO_CHECK='Both';
      NO_ASSERT_CHECK='TRUE';
      NO_DIR_CHECK='TRUE';
      ALLOW_CONNECT='TRUE';
    'VSS_AM45':
      PIN_NUMBER='(0,0,0,0,0,0,0,0,0,0,0,0,0,0,0,0,0,0,0,0,0,0,0,0,0,0,0,0,0,0,0~
,AM45,0,0,0,0,0,0,0,0)';
      PINUSE='POWER';
      NO_LOAD_CHECK='Both';
      NO_IO_CHECK='Both';
      NO_ASSERT_CHECK='TRUE';
      NO_DIR_CHECK='TRUE';
      ALLOW_CONNECT='TRUE';
    'VSS_AM46':
      PIN_NUMBER='(0,0,0,0,0,0,0,0,0,0,0,0,0,0,0,0,0,0,0,0,0,0,0,0,0,0,0,0,0,0,0~
,AM46,0,0,0,0,0,0,0,0)';
      PINUSE='POWER';
      NO_LOAD_CHECK='Both';
      NO_IO_CHECK='Both';
      NO_ASSERT_CHECK='TRUE';
      NO_DIR_CHECK='TRUE';
      ALLOW_CONNECT='TRUE';
    'VSS_AM47':
      PIN_NUMBER='(0,0,0,0,0,0,0,0,0,0,0,0,0,0,0,0,0,0,0,0,0,0,0,0,0,0,0,0,0,0,0~
,AM47,0,0,0,0,0,0,0,0)';
      PINUSE='POWER';
      NO_LOAD_CHECK='Both';
      NO_IO_CHECK='Both';
      NO_ASSERT_CHECK='TRUE';
      NO_DIR_CHECK='TRUE';
      ALLOW_CONNECT='TRUE';
    'VSS_AM48':
      PIN_NUMBER='(0,0,0,0,0,0,0,0,0,0,0,0,0,0,0,0,0,0,0,0,0,0,0,0,0,0,0,0,0,0,0~
,AM48,0,0,0,0,0,0,0,0)';
      PINUSE='POWER';
      NO_LOAD_CHECK='Both';
      NO_IO_CHECK='Both';
      NO_ASSERT_CHECK='TRUE';
      NO_DIR_CHECK='TRUE';
      ALLOW_CONNECT='TRUE';
    'VSS_AM49':
      PIN_NUMBER='(0,0,0,0,0,0,0,0,0,0,0,0,0,0,0,0,0,0,0,0,0,0,0,0,0,0,0,0,0,0,0~
,AM49,0,0,0,0,0,0,0,0)';
      PINUSE='POWER';
      NO_LOAD_CHECK='Both';
      NO_IO_CHECK='Both';
      NO_ASSERT_CHECK='TRUE';
      NO_DIR_CHECK='TRUE';
      ALLOW_CONNECT='TRUE';
    'VSS_AM50':
      PIN_NUMBER='(0,0,0,0,0,0,0,0,0,0,0,0,0,0,0,0,0,0,0,0,0,0,0,0,0,0,0,0,0,0,0~
,AM50,0,0,0,0,0,0,0,0)';
      PINUSE='POWER';
      NO_LOAD_CHECK='Both';
      NO_IO_CHECK='Both';
      NO_ASSERT_CHECK='TRUE';
      NO_DIR_CHECK='TRUE';
      ALLOW_CONNECT='TRUE';
    'VSS_AM51':
      PIN_NUMBER='(0,0,0,0,0,0,0,0,0,0,0,0,0,0,0,0,0,0,0,0,0,0,0,0,0,0,0,0,0,0,0~
,AM51,0,0,0,0,0,0,0,0)';
      PINUSE='POWER';
      NO_LOAD_CHECK='Both';
      NO_IO_CHECK='Both';
      NO_ASSERT_CHECK='TRUE';
      NO_DIR_CHECK='TRUE';
      ALLOW_CONNECT='TRUE';
    'VSS_AM52':
      PIN_NUMBER='(0,0,0,0,0,0,0,0,0,0,0,0,0,0,0,0,0,0,0,0,0,0,0,0,0,0,0,0,0,0,0~
,AM52,0,0,0,0,0,0,0,0)';
      PINUSE='POWER';
      NO_LOAD_CHECK='Both';
      NO_IO_CHECK='Both';
      NO_ASSERT_CHECK='TRUE';
      NO_DIR_CHECK='TRUE';
      ALLOW_CONNECT='TRUE';
    'VSS_AM53':
      PIN_NUMBER='(0,0,0,0,0,0,0,0,0,0,0,0,0,0,0,0,0,0,0,0,0,0,0,0,0,0,0,0,0,0,0~
,AM53,0,0,0,0,0,0,0,0)';
      PINUSE='POWER';
      NO_LOAD_CHECK='Both';
      NO_IO_CHECK='Both';
      NO_ASSERT_CHECK='TRUE';
      NO_DIR_CHECK='TRUE';
      ALLOW_CONNECT='TRUE';
    'VSS_AM59':
      PIN_NUMBER='(0,0,0,0,0,0,0,0,0,0,0,0,0,0,0,0,0,0,0,0,0,0,0,0,0,0,0,0,0,0,0~
,AM59,0,0,0,0,0,0,0,0)';
      PINUSE='POWER';
      NO_LOAD_CHECK='Both';
      NO_IO_CHECK='Both';
      NO_ASSERT_CHECK='TRUE';
      NO_DIR_CHECK='TRUE';
      ALLOW_CONNECT='TRUE';
    'VSS_AM61':
      PIN_NUMBER='(0,0,0,0,0,0,0,0,0,0,0,0,0,0,0,0,0,0,0,0,0,0,0,0,0,0,0,0,0,0,0~
,AM61,0,0,0,0,0,0,0,0)';
      PINUSE='POWER';
      NO_LOAD_CHECK='Both';
      NO_IO_CHECK='Both';
      NO_ASSERT_CHECK='TRUE';
      NO_DIR_CHECK='TRUE';
      ALLOW_CONNECT='TRUE';
    'VSS_AM66':
      PIN_NUMBER='(0,0,0,0,0,0,0,0,0,0,0,0,0,0,0,0,0,0,0,0,0,0,0,0,0,0,0,0,0,0,0~
,AM66,0,0,0,0,0,0,0,0)';
      PINUSE='POWER';
      NO_LOAD_CHECK='Both';
      NO_IO_CHECK='Both';
      NO_ASSERT_CHECK='TRUE';
      NO_DIR_CHECK='TRUE';
      ALLOW_CONNECT='TRUE';
    'VSS_AM68':
      PIN_NUMBER='(0,0,0,0,0,0,0,0,0,0,0,0,0,0,0,0,0,0,0,0,0,0,0,0,0,0,0,0,0,0,0~
,AM68,0,0,0,0,0,0,0,0)';
      PINUSE='POWER';
      NO_LOAD_CHECK='Both';
      NO_IO_CHECK='Both';
      NO_ASSERT_CHECK='TRUE';
      NO_DIR_CHECK='TRUE';
      ALLOW_CONNECT='TRUE';
    'VSS_AM73':
      PIN_NUMBER='(0,0,0,0,0,0,0,0,0,0,0,0,0,0,0,0,0,0,0,0,0,0,0,0,0,0,0,0,0,0,0~
,AM73,0,0,0,0,0,0,0,0)';
      PINUSE='POWER';
      NO_LOAD_CHECK='Both';
      NO_IO_CHECK='Both';
      NO_ASSERT_CHECK='TRUE';
      NO_DIR_CHECK='TRUE';
      ALLOW_CONNECT='TRUE';
    'VSS_AN1':
      PIN_NUMBER='(0,0,0,0,0,0,0,0,0,0,0,0,0,0,0,0,0,0,0,0,0,0,0,0,0,0,0,0,0,0,0~
,AN1,0,0,0,0,0,0,0,0)';
      PINUSE='POWER';
      NO_LOAD_CHECK='Both';
      NO_IO_CHECK='Both';
      NO_ASSERT_CHECK='TRUE';
      NO_DIR_CHECK='TRUE';
      ALLOW_CONNECT='TRUE';
    'VSS_AN4':
      PIN_NUMBER='(0,0,0,0,0,0,0,0,0,0,0,0,0,0,0,0,0,0,0,0,0,0,0,0,0,0,0,0,0,0,0~
,AN4,0,0,0,0,0,0,0,0)';
      PINUSE='POWER';
      NO_LOAD_CHECK='Both';
      NO_IO_CHECK='Both';
      NO_ASSERT_CHECK='TRUE';
      NO_DIR_CHECK='TRUE';
      ALLOW_CONNECT='TRUE';
    'VSS_AN6':
      PIN_NUMBER='(0,0,0,0,0,0,0,0,0,0,0,0,0,0,0,0,0,0,0,0,0,0,0,0,0,0,0,0,0,0,0~
,AN6,0,0,0,0,0,0,0,0)';
      PINUSE='POWER';
      NO_LOAD_CHECK='Both';
      NO_IO_CHECK='Both';
      NO_ASSERT_CHECK='TRUE';
      NO_DIR_CHECK='TRUE';
      ALLOW_CONNECT='TRUE';
    'VSS_AN8':
      PIN_NUMBER='(0,0,0,0,0,0,0,0,0,0,0,0,0,0,0,0,0,0,0,0,0,0,0,0,0,0,0,0,0,0,0~
,AN8,0,0,0,0,0,0,0,0)';
      PINUSE='POWER';
      NO_LOAD_CHECK='Both';
      NO_IO_CHECK='Both';
      NO_ASSERT_CHECK='TRUE';
      NO_DIR_CHECK='TRUE';
      ALLOW_CONNECT='TRUE';
    'VSS_AN11':
      PIN_NUMBER='(0,0,0,0,0,0,0,0,0,0,0,0,0,0,0,0,0,0,0,0,0,0,0,0,0,0,0,0,0,0,0~
,AN11,0,0,0,0,0,0,0,0)';
      PINUSE='POWER';
      NO_LOAD_CHECK='Both';
      NO_IO_CHECK='Both';
      NO_ASSERT_CHECK='TRUE';
      NO_DIR_CHECK='TRUE';
      ALLOW_CONNECT='TRUE';
    'VSS_AN13':
      PIN_NUMBER='(0,0,0,0,0,0,0,0,0,0,0,0,0,0,0,0,0,0,0,0,0,0,0,0,0,0,0,0,0,0,0~
,AN13,0,0,0,0,0,0,0,0)';
      PINUSE='POWER';
      NO_LOAD_CHECK='Both';
      NO_IO_CHECK='Both';
      NO_ASSERT_CHECK='TRUE';
      NO_DIR_CHECK='TRUE';
      ALLOW_CONNECT='TRUE';
    'VSS_AN15':
      PIN_NUMBER='(0,0,0,0,0,0,0,0,0,0,0,0,0,0,0,0,0,0,0,0,0,0,0,0,0,0,0,0,0,0,0~
,AN15,0,0,0,0,0,0,0,0)';
      PINUSE='POWER';
      NO_LOAD_CHECK='Both';
      NO_IO_CHECK='Both';
      NO_ASSERT_CHECK='TRUE';
      NO_DIR_CHECK='TRUE';
      ALLOW_CONNECT='TRUE';
    'VSS_AN18':
      PIN_NUMBER='(0,0,0,0,0,0,0,0,0,0,0,0,0,0,0,0,0,0,0,0,0,0,0,0,0,0,0,0,0,0,0~
,AN18,0,0,0,0,0,0,0,0)';
      PINUSE='POWER';
      NO_LOAD_CHECK='Both';
      NO_IO_CHECK='Both';
      NO_ASSERT_CHECK='TRUE';
      NO_DIR_CHECK='TRUE';
      ALLOW_CONNECT='TRUE';
    'VSS_AN22':
      PIN_NUMBER='(0,0,0,0,0,0,0,0,0,0,0,0,0,0,0,0,0,0,0,0,0,0,0,0,0,0,0,0,0,0,0~
,AN22,0,0,0,0,0,0,0,0)';
      PINUSE='POWER';
      NO_LOAD_CHECK='Both';
      NO_IO_CHECK='Both';
      NO_ASSERT_CHECK='TRUE';
      NO_DIR_CHECK='TRUE';
      ALLOW_CONNECT='TRUE';
    'VSS_AN25':
      PIN_NUMBER='(0,0,0,0,0,0,0,0,0,0,0,0,0,0,0,0,0,0,0,0,0,0,0,0,0,0,0,0,0,0,0~
,AN25,0,0,0,0,0,0,0,0)';
      PINUSE='POWER';
      NO_LOAD_CHECK='Both';
      NO_IO_CHECK='Both';
      NO_ASSERT_CHECK='TRUE';
      NO_DIR_CHECK='TRUE';
      ALLOW_CONNECT='TRUE';
    'VSS_AN28':
      PIN_NUMBER='(0,0,0,0,0,0,0,0,0,0,0,0,0,0,0,0,0,0,0,0,0,0,0,0,0,0,0,0,0,0,0~
,AN28,0,0,0,0,0,0,0,0)';
      PINUSE='POWER';
      NO_LOAD_CHECK='Both';
      NO_IO_CHECK='Both';
      NO_ASSERT_CHECK='TRUE';
      NO_DIR_CHECK='TRUE';
      ALLOW_CONNECT='TRUE';
    'VSS_AN31':
      PIN_NUMBER='(0,0,0,0,0,0,0,0,0,0,0,0,0,0,0,0,0,0,0,0,0,0,0,0,0,0,0,0,0,0,0~
,AN31,0,0,0,0,0,0,0,0)';
      PINUSE='POWER';
      NO_LOAD_CHECK='Both';
      NO_IO_CHECK='Both';
      NO_ASSERT_CHECK='TRUE';
      NO_DIR_CHECK='TRUE';
      ALLOW_CONNECT='TRUE';
    'VSS_AN34':
      PIN_NUMBER='(0,0,0,0,0,0,0,0,0,0,0,0,0,0,0,0,0,0,0,0,0,0,0,0,0,0,0,0,0,0,0~
,AN34,0,0,0,0,0,0,0,0)';
      PINUSE='POWER';
      NO_LOAD_CHECK='Both';
      NO_IO_CHECK='Both';
      NO_ASSERT_CHECK='TRUE';
      NO_DIR_CHECK='TRUE';
      ALLOW_CONNECT='TRUE';
    'VSS_AN35':
      PIN_NUMBER='(0,0,0,0,0,0,0,0,0,0,0,0,0,0,0,0,0,0,0,0,0,0,0,0,0,0,0,0,0,0,0~
,AN35,0,0,0,0,0,0,0,0)';
      PINUSE='POWER';
      NO_LOAD_CHECK='Both';
      NO_IO_CHECK='Both';
      NO_ASSERT_CHECK='TRUE';
      NO_DIR_CHECK='TRUE';
      ALLOW_CONNECT='TRUE';
    'VSS_AN36':
      PIN_NUMBER='(0,0,0,0,0,0,0,0,0,0,0,0,0,0,0,0,0,0,0,0,0,0,0,0,0,0,0,0,0,0,0~
,AN36,0,0,0,0,0,0,0,0)';
      PINUSE='POWER';
      NO_LOAD_CHECK='Both';
      NO_IO_CHECK='Both';
      NO_ASSERT_CHECK='TRUE';
      NO_DIR_CHECK='TRUE';
      ALLOW_CONNECT='TRUE';
    'VSS_AN40':
      PIN_NUMBER='(0,0,0,0,0,0,0,0,0,0,0,0,0,0,0,0,0,0,0,0,0,0,0,0,0,0,0,0,0,0,0~
,AN40,0,0,0,0,0,0,0,0)';
      PINUSE='POWER';
      NO_LOAD_CHECK='Both';
      NO_IO_CHECK='Both';
      NO_ASSERT_CHECK='TRUE';
      NO_DIR_CHECK='TRUE';
      ALLOW_CONNECT='TRUE';
    'VSS_AN41':
      PIN_NUMBER='(0,0,0,0,0,0,0,0,0,0,0,0,0,0,0,0,0,0,0,0,0,0,0,0,0,0,0,0,0,0,0~
,AN41,0,0,0,0,0,0,0,0)';
      PINUSE='POWER';
      NO_LOAD_CHECK='Both';
      NO_IO_CHECK='Both';
      NO_ASSERT_CHECK='TRUE';
      NO_DIR_CHECK='TRUE';
      ALLOW_CONNECT='TRUE';
    'VSS_AN42':
      PIN_NUMBER='(0,0,0,0,0,0,0,0,0,0,0,0,0,0,0,0,0,0,0,0,0,0,0,0,0,0,0,0,0,0,0~
,AN42,0,0,0,0,0,0,0,0)';
      PINUSE='POWER';
      NO_LOAD_CHECK='Both';
      NO_IO_CHECK='Both';
      NO_ASSERT_CHECK='TRUE';
      NO_DIR_CHECK='TRUE';
      ALLOW_CONNECT='TRUE';
    'VSS_AN45':
      PIN_NUMBER='(0,0,0,0,0,0,0,0,0,0,0,0,0,0,0,0,0,0,0,0,0,0,0,0,0,0,0,0,0,0,0~
,AN45,0,0,0,0,0,0,0,0)';
      PINUSE='POWER';
      NO_LOAD_CHECK='Both';
      NO_IO_CHECK='Both';
      NO_ASSERT_CHECK='TRUE';
      NO_DIR_CHECK='TRUE';
      ALLOW_CONNECT='TRUE';
    'VSS_AN48':
      PIN_NUMBER='(0,0,0,0,0,0,0,0,0,0,0,0,0,0,0,0,0,0,0,0,0,0,0,0,0,0,0,0,0,0,0~
,AN48,0,0,0,0,0,0,0,0)';
      PINUSE='POWER';
      NO_LOAD_CHECK='Both';
      NO_IO_CHECK='Both';
      NO_ASSERT_CHECK='TRUE';
      NO_DIR_CHECK='TRUE';
      ALLOW_CONNECT='TRUE';
    'VSS_AN51':
      PIN_NUMBER='(0,0,0,0,0,0,0,0,0,0,0,0,0,0,0,0,0,0,0,0,0,0,0,0,0,0,0,0,0,0,0~
,AN51,0,0,0,0,0,0,0,0)';
      PINUSE='POWER';
      NO_LOAD_CHECK='Both';
      NO_IO_CHECK='Both';
      NO_ASSERT_CHECK='TRUE';
      NO_DIR_CHECK='TRUE';
      ALLOW_CONNECT='TRUE';
    'VSS_AN54':
      PIN_NUMBER='(0,0,0,0,0,0,0,0,0,0,0,0,0,0,0,0,0,0,0,0,0,0,0,0,0,0,0,0,0,0,0~
,AN54,0,0,0,0,0,0,0,0)';
      PINUSE='POWER';
      NO_LOAD_CHECK='Both';
      NO_IO_CHECK='Both';
      NO_ASSERT_CHECK='TRUE';
      NO_DIR_CHECK='TRUE';
      ALLOW_CONNECT='TRUE';
    'VSS_AN56':
      PIN_NUMBER='(0,0,0,0,0,0,0,0,0,0,0,0,0,0,0,0,0,0,0,0,0,0,0,0,0,0,0,0,0,0,0~
,AN56,0,0,0,0,0,0,0,0)';
      PINUSE='POWER';
      NO_LOAD_CHECK='Both';
      NO_IO_CHECK='Both';
      NO_ASSERT_CHECK='TRUE';
      NO_DIR_CHECK='TRUE';
      ALLOW_CONNECT='TRUE';
    'VSS_AN58':
      PIN_NUMBER='(0,0,0,0,0,0,0,0,0,0,0,0,0,0,0,0,0,0,0,0,0,0,0,0,0,0,0,0,0,0,0~
,AN58,0,0,0,0,0,0,0,0)';
      PINUSE='POWER';
      NO_LOAD_CHECK='Both';
      NO_IO_CHECK='Both';
      NO_ASSERT_CHECK='TRUE';
      NO_DIR_CHECK='TRUE';
      ALLOW_CONNECT='TRUE';
    'VSS_AN61':
      PIN_NUMBER='(0,0,0,0,0,0,0,0,0,0,0,0,0,0,0,0,0,0,0,0,0,0,0,0,0,0,0,0,0,0,0~
,AN61,0,0,0,0,0,0,0,0)';
      PINUSE='POWER';
      NO_LOAD_CHECK='Both';
      NO_IO_CHECK='Both';
      NO_ASSERT_CHECK='TRUE';
      NO_DIR_CHECK='TRUE';
      ALLOW_CONNECT='TRUE';
    'VSS_AN63':
      PIN_NUMBER='(0,0,0,0,0,0,0,0,0,0,0,0,0,0,0,0,0,0,0,0,0,0,0,0,0,0,0,0,0,0,0~
,AN63,0,0,0,0,0,0,0,0)';
      PINUSE='POWER';
      NO_LOAD_CHECK='Both';
      NO_IO_CHECK='Both';
      NO_ASSERT_CHECK='TRUE';
      NO_DIR_CHECK='TRUE';
      ALLOW_CONNECT='TRUE';
    'VSS_AN65':
      PIN_NUMBER='(0,0,0,0,0,0,0,0,0,0,0,0,0,0,0,0,0,0,0,0,0,0,0,0,0,0,0,0,0,0,0~
,AN65,0,0,0,0,0,0,0,0)';
      PINUSE='POWER';
      NO_LOAD_CHECK='Both';
      NO_IO_CHECK='Both';
      NO_ASSERT_CHECK='TRUE';
      NO_DIR_CHECK='TRUE';
      ALLOW_CONNECT='TRUE';
    'VSS_AN68':
      PIN_NUMBER='(0,0,0,0,0,0,0,0,0,0,0,0,0,0,0,0,0,0,0,0,0,0,0,0,0,0,0,0,0,0,0~
,AN68,0,0,0,0,0,0,0,0)';
      PINUSE='POWER';
      NO_LOAD_CHECK='Both';
      NO_IO_CHECK='Both';
      NO_ASSERT_CHECK='TRUE';
      NO_DIR_CHECK='TRUE';
      ALLOW_CONNECT='TRUE';
    'VSS_AN70':
      PIN_NUMBER='(0,0,0,0,0,0,0,0,0,0,0,0,0,0,0,0,0,0,0,0,0,0,0,0,0,0,0,0,0,0,0~
,AN70,0,0,0,0,0,0,0,0)';
      PINUSE='POWER';
      NO_LOAD_CHECK='Both';
      NO_IO_CHECK='Both';
      NO_ASSERT_CHECK='TRUE';
      NO_DIR_CHECK='TRUE';
      ALLOW_CONNECT='TRUE';
    'VSS_AN72':
      PIN_NUMBER='(0,0,0,0,0,0,0,0,0,0,0,0,0,0,0,0,0,0,0,0,0,0,0,0,0,0,0,0,0,0,0~
,AN72,0,0,0,0,0,0,0,0)';
      PINUSE='POWER';
      NO_LOAD_CHECK='Both';
      NO_IO_CHECK='Both';
      NO_ASSERT_CHECK='TRUE';
      NO_DIR_CHECK='TRUE';
      ALLOW_CONNECT='TRUE';
    'VSS_AN75':
      PIN_NUMBER='(0,0,0,0,0,0,0,0,0,0,0,0,0,0,0,0,0,0,0,0,0,0,0,0,0,0,0,0,0,0,0~
,AN75,0,0,0,0,0,0,0,0)';
      PINUSE='POWER';
      NO_LOAD_CHECK='Both';
      NO_IO_CHECK='Both';
      NO_ASSERT_CHECK='TRUE';
      NO_DIR_CHECK='TRUE';
      ALLOW_CONNECT='TRUE';
    'VSS_AP3':
      PIN_NUMBER='(0,0,0,0,0,0,0,0,0,0,0,0,0,0,0,0,0,0,0,0,0,0,0,0,0,0,0,0,0,0,0~
,AP3,0,0,0,0,0,0,0,0)';
      PINUSE='POWER';
      NO_LOAD_CHECK='Both';
      NO_IO_CHECK='Both';
      NO_ASSERT_CHECK='TRUE';
      NO_DIR_CHECK='TRUE';
      ALLOW_CONNECT='TRUE';
    'VSS_AP5':
      PIN_NUMBER='(0,0,0,0,0,0,0,0,0,0,0,0,0,0,0,0,0,0,0,0,0,0,0,0,0,0,0,0,0,0,0~
,AP5,0,0,0,0,0,0,0,0)';
      PINUSE='POWER';
      NO_LOAD_CHECK='Both';
      NO_IO_CHECK='Both';
      NO_ASSERT_CHECK='TRUE';
      NO_DIR_CHECK='TRUE';
      ALLOW_CONNECT='TRUE';
    'VSS_AP8':
      PIN_NUMBER='(0,0,0,0,0,0,0,0,0,0,0,0,0,0,0,0,0,0,0,0,0,0,0,0,0,0,0,0,0,0,0~
,AP8,0,0,0,0,0,0,0,0)';
      PINUSE='POWER';
      NO_LOAD_CHECK='Both';
      NO_IO_CHECK='Both';
      NO_ASSERT_CHECK='TRUE';
      NO_DIR_CHECK='TRUE';
      ALLOW_CONNECT='TRUE';
    'VSS_AP10':
      PIN_NUMBER='(0,0,0,0,0,0,0,0,0,0,0,0,0,0,0,0,0,0,0,0,0,0,0,0,0,0,0,0,0,0,0~
,AP10,0,0,0,0,0,0,0,0)';
      PINUSE='POWER';
      NO_LOAD_CHECK='Both';
      NO_IO_CHECK='Both';
      NO_ASSERT_CHECK='TRUE';
      NO_DIR_CHECK='TRUE';
      ALLOW_CONNECT='TRUE';
    'VSS_AP12':
      PIN_NUMBER='(0,0,0,0,0,0,0,0,0,0,0,0,0,0,0,0,0,0,0,0,0,0,0,0,0,0,0,0,0,0,0~
,AP12,0,0,0,0,0,0,0,0)';
      PINUSE='POWER';
      NO_LOAD_CHECK='Both';
      NO_IO_CHECK='Both';
      NO_ASSERT_CHECK='TRUE';
      NO_DIR_CHECK='TRUE';
      ALLOW_CONNECT='TRUE';
    'VSS_AP15':
      PIN_NUMBER='(0,0,0,0,0,0,0,0,0,0,0,0,0,0,0,0,0,0,0,0,0,0,0,0,0,0,0,0,0,0,0~
,AP15,0,0,0,0,0,0,0,0)';
      PINUSE='POWER';
      NO_LOAD_CHECK='Both';
      NO_IO_CHECK='Both';
      NO_ASSERT_CHECK='TRUE';
      NO_DIR_CHECK='TRUE';
      ALLOW_CONNECT='TRUE';
    'VSS_AP17':
      PIN_NUMBER='(0,0,0,0,0,0,0,0,0,0,0,0,0,0,0,0,0,0,0,0,0,0,0,0,0,0,0,0,0,0,0~
,AP17,0,0,0,0,0,0,0,0)';
      PINUSE='POWER';
      NO_LOAD_CHECK='Both';
      NO_IO_CHECK='Both';
      NO_ASSERT_CHECK='TRUE';
      NO_DIR_CHECK='TRUE';
      ALLOW_CONNECT='TRUE';
    'VSS_AP19':
      PIN_NUMBER='(0,0,0,0,0,0,0,0,0,0,0,0,0,0,0,0,0,0,0,0,0,0,0,0,0,0,0,0,0,0,0~
,AP19,0,0,0,0,0,0,0,0)';
      PINUSE='POWER';
      NO_LOAD_CHECK='Both';
      NO_IO_CHECK='Both';
      NO_ASSERT_CHECK='TRUE';
      NO_DIR_CHECK='TRUE';
      ALLOW_CONNECT='TRUE';
    'VSS_AP22':
      PIN_NUMBER='(0,0,0,0,0,0,0,0,0,0,0,0,0,0,0,0,0,0,0,0,0,0,0,0,0,0,0,0,0,0,0~
,AP22,0,0,0,0,0,0,0,0)';
      PINUSE='POWER';
      NO_LOAD_CHECK='Both';
      NO_IO_CHECK='Both';
      NO_ASSERT_CHECK='TRUE';
      NO_DIR_CHECK='TRUE';
      ALLOW_CONNECT='TRUE';
    'VSS_AP25':
      PIN_NUMBER='(0,0,0,0,0,0,0,0,0,0,0,0,0,0,0,0,0,0,0,0,0,0,0,0,0,0,0,0,0,0,0~
,AP25,0,0,0,0,0,0,0,0)';
      PINUSE='POWER';
      NO_LOAD_CHECK='Both';
      NO_IO_CHECK='Both';
      NO_ASSERT_CHECK='TRUE';
      NO_DIR_CHECK='TRUE';
      ALLOW_CONNECT='TRUE';
    'VSS_AP28':
      PIN_NUMBER='(0,0,0,0,0,0,0,0,0,0,0,0,0,0,0,0,0,0,0,0,0,0,0,0,0,0,0,0,0,0,0~
,AP28,0,0,0,0,0,0,0,0)';
      PINUSE='POWER';
      NO_LOAD_CHECK='Both';
      NO_IO_CHECK='Both';
      NO_ASSERT_CHECK='TRUE';
      NO_DIR_CHECK='TRUE';
      ALLOW_CONNECT='TRUE';
    'VSS_AP31':
      PIN_NUMBER='(0,0,0,0,0,0,0,0,0,0,0,0,0,0,0,0,0,0,0,0,0,0,0,0,0,0,0,0,0,0,0~
,AP31,0,0,0,0,0,0,0,0)';
      PINUSE='POWER';
      NO_LOAD_CHECK='Both';
      NO_IO_CHECK='Both';
      NO_ASSERT_CHECK='TRUE';
      NO_DIR_CHECK='TRUE';
      ALLOW_CONNECT='TRUE';
    'VSS_AP34':
      PIN_NUMBER='(0,0,0,0,0,0,0,0,0,0,0,0,0,0,0,0,0,0,0,0,0,0,0,0,0,0,0,0,0,0,0~
,AP34,0,0,0,0,0,0,0,0)';
      PINUSE='POWER';
      NO_LOAD_CHECK='Both';
      NO_IO_CHECK='Both';
      NO_ASSERT_CHECK='TRUE';
      NO_DIR_CHECK='TRUE';
      ALLOW_CONNECT='TRUE';
    'VSS_AP37':
      PIN_NUMBER='(0,0,0,0,0,0,0,0,0,0,0,0,0,0,0,0,0,0,0,0,0,0,0,0,0,0,0,0,0,0,0~
,AP37,0,0,0,0,0,0,0,0)';
      PINUSE='POWER';
      NO_LOAD_CHECK='Both';
      NO_IO_CHECK='Both';
      NO_ASSERT_CHECK='TRUE';
      NO_DIR_CHECK='TRUE';
      ALLOW_CONNECT='TRUE';
    'VSS_AP39':
      PIN_NUMBER='(0,0,0,0,0,0,0,0,0,0,0,0,0,0,0,0,0,0,0,0,0,0,0,0,0,0,0,0,0,0,0~
,AP39,0,0,0,0,0,0,0,0)';
      PINUSE='POWER';
      NO_LOAD_CHECK='Both';
      NO_IO_CHECK='Both';
      NO_ASSERT_CHECK='TRUE';
      NO_DIR_CHECK='TRUE';
      ALLOW_CONNECT='TRUE';
    'VSS_AP42':
      PIN_NUMBER='(0,0,0,0,0,0,0,0,0,0,0,0,0,0,0,0,0,0,0,0,0,0,0,0,0,0,0,0,0,0,0~
,AP42,0,0,0,0,0,0,0,0)';
      PINUSE='POWER';
      NO_LOAD_CHECK='Both';
      NO_IO_CHECK='Both';
      NO_ASSERT_CHECK='TRUE';
      NO_DIR_CHECK='TRUE';
      ALLOW_CONNECT='TRUE';
    'VSS_AP45':
      PIN_NUMBER='(0,0,0,0,0,0,0,0,0,0,0,0,0,0,0,0,0,0,0,0,0,0,0,0,0,0,0,0,0,0,0~
,AP45,0,0,0,0,0,0,0,0)';
      PINUSE='POWER';
      NO_LOAD_CHECK='Both';
      NO_IO_CHECK='Both';
      NO_ASSERT_CHECK='TRUE';
      NO_DIR_CHECK='TRUE';
      ALLOW_CONNECT='TRUE';
    'VSS_AP48':
      PIN_NUMBER='(0,0,0,0,0,0,0,0,0,0,0,0,0,0,0,0,0,0,0,0,0,0,0,0,0,0,0,0,0,0,0~
,AP48,0,0,0,0,0,0,0,0)';
      PINUSE='POWER';
      NO_LOAD_CHECK='Both';
      NO_IO_CHECK='Both';
      NO_ASSERT_CHECK='TRUE';
      NO_DIR_CHECK='TRUE';
      ALLOW_CONNECT='TRUE';
    'VSS_AP51':
      PIN_NUMBER='(0,0,0,0,0,0,0,0,0,0,0,0,0,0,0,0,0,0,0,0,0,0,0,0,0,0,0,0,0,0,0~
,AP51,0,0,0,0,0,0,0,0)';
      PINUSE='POWER';
      NO_LOAD_CHECK='Both';
      NO_IO_CHECK='Both';
      NO_ASSERT_CHECK='TRUE';
      NO_DIR_CHECK='TRUE';
      ALLOW_CONNECT='TRUE';
    'VSS_AP54':
      PIN_NUMBER='(0,0,0,0,0,0,0,0,0,0,0,0,0,0,0,0,0,0,0,0,0,0,0,0,0,0,0,0,0,0,0~
,AP54,0,0,0,0,0,0,0,0)';
      PINUSE='POWER';
      NO_LOAD_CHECK='Both';
      NO_IO_CHECK='Both';
      NO_ASSERT_CHECK='TRUE';
      NO_DIR_CHECK='TRUE';
      ALLOW_CONNECT='TRUE';
    'VSS_AP57':
      PIN_NUMBER='(0,0,0,0,0,0,0,0,0,0,0,0,0,0,0,0,0,0,0,0,0,0,0,0,0,0,0,0,0,0,0~
,AP57,0,0,0,0,0,0,0,0)';
      PINUSE='POWER';
      NO_LOAD_CHECK='Both';
      NO_IO_CHECK='Both';
      NO_ASSERT_CHECK='TRUE';
      NO_DIR_CHECK='TRUE';
      ALLOW_CONNECT='TRUE';
    'VSS_AP59':
      PIN_NUMBER='(0,0,0,0,0,0,0,0,0,0,0,0,0,0,0,0,0,0,0,0,0,0,0,0,0,0,0,0,0,0,0~
,AP59,0,0,0,0,0,0,0,0)';
      PINUSE='POWER';
      NO_LOAD_CHECK='Both';
      NO_IO_CHECK='Both';
      NO_ASSERT_CHECK='TRUE';
      NO_DIR_CHECK='TRUE';
      ALLOW_CONNECT='TRUE';
    'VSS_AP61':
      PIN_NUMBER='(0,0,0,0,0,0,0,0,0,0,0,0,0,0,0,0,0,0,0,0,0,0,0,0,0,0,0,0,0,0,0~
,AP61,0,0,0,0,0,0,0,0)';
      PINUSE='POWER';
      NO_LOAD_CHECK='Both';
      NO_IO_CHECK='Both';
      NO_ASSERT_CHECK='TRUE';
      NO_DIR_CHECK='TRUE';
      ALLOW_CONNECT='TRUE';
    'VSS_AP64':
      PIN_NUMBER='(0,0,0,0,0,0,0,0,0,0,0,0,0,0,0,0,0,0,0,0,0,0,0,0,0,0,0,0,0,0,0~
,AP64,0,0,0,0,0,0,0,0)';
      PINUSE='POWER';
      NO_LOAD_CHECK='Both';
      NO_IO_CHECK='Both';
      NO_ASSERT_CHECK='TRUE';
      NO_DIR_CHECK='TRUE';
      ALLOW_CONNECT='TRUE';
    'VSS_AP66':
      PIN_NUMBER='(0,0,0,0,0,0,0,0,0,0,0,0,0,0,0,0,0,0,0,0,0,0,0,0,0,0,0,0,0,0,0~
,AP66,0,0,0,0,0,0,0,0)';
      PINUSE='POWER';
      NO_LOAD_CHECK='Both';
      NO_IO_CHECK='Both';
      NO_ASSERT_CHECK='TRUE';
      NO_DIR_CHECK='TRUE';
      ALLOW_CONNECT='TRUE';
    'VSS_AP68':
      PIN_NUMBER='(0,0,0,0,0,0,0,0,0,0,0,0,0,0,0,0,0,0,0,0,0,0,0,0,0,0,0,0,0,0,0~
,AP68,0,0,0,0,0,0,0,0)';
      PINUSE='POWER';
      NO_LOAD_CHECK='Both';
      NO_IO_CHECK='Both';
      NO_ASSERT_CHECK='TRUE';
      NO_DIR_CHECK='TRUE';
      ALLOW_CONNECT='TRUE';
    'VSS_AP71':
      PIN_NUMBER='(0,0,0,0,0,0,0,0,0,0,0,0,0,0,0,0,0,0,0,0,0,0,0,0,0,0,0,0,0,0,0~
,AP71,0,0,0,0,0,0,0,0)';
      PINUSE='POWER';
      NO_LOAD_CHECK='Both';
      NO_IO_CHECK='Both';
      NO_ASSERT_CHECK='TRUE';
      NO_DIR_CHECK='TRUE';
      ALLOW_CONNECT='TRUE';
    'VSS_AP73':
      PIN_NUMBER='(0,0,0,0,0,0,0,0,0,0,0,0,0,0,0,0,0,0,0,0,0,0,0,0,0,0,0,0,0,0,0~
,AP73,0,0,0,0,0,0,0,0)';
      PINUSE='POWER';
      NO_LOAD_CHECK='Both';
      NO_IO_CHECK='Both';
      NO_ASSERT_CHECK='TRUE';
      NO_DIR_CHECK='TRUE';
      ALLOW_CONNECT='TRUE';
    'VSS_AR1':
      PIN_NUMBER='(0,0,0,0,0,0,0,0,0,0,0,0,0,0,0,0,0,0,0,0,0,0,0,0,0,0,0,0,0,0,0~
,AR1,0,0,0,0,0,0,0,0)';
      PINUSE='POWER';
      NO_LOAD_CHECK='Both';
      NO_IO_CHECK='Both';
      NO_ASSERT_CHECK='TRUE';
      NO_DIR_CHECK='TRUE';
      ALLOW_CONNECT='TRUE';
    'VSS_AR5':
      PIN_NUMBER='(0,0,0,0,0,0,0,0,0,0,0,0,0,0,0,0,0,0,0,0,0,0,0,0,0,0,0,0,0,0,0~
,AR5,0,0,0,0,0,0,0,0)';
      PINUSE='POWER';
      NO_LOAD_CHECK='Both';
      NO_IO_CHECK='Both';
      NO_ASSERT_CHECK='TRUE';
      NO_DIR_CHECK='TRUE';
      ALLOW_CONNECT='TRUE';
    'VSS_AR6':
      PIN_NUMBER='(0,0,0,0,0,0,0,0,0,0,0,0,0,0,0,0,0,0,0,0,0,0,0,0,0,0,0,0,0,0,0~
,AR6,0,0,0,0,0,0,0,0)';
      PINUSE='POWER';
      NO_LOAD_CHECK='Both';
      NO_IO_CHECK='Both';
      NO_ASSERT_CHECK='TRUE';
      NO_DIR_CHECK='TRUE';
      ALLOW_CONNECT='TRUE';
    'VSS_AR8':
      PIN_NUMBER='(0,0,0,0,0,0,0,0,0,0,0,0,0,0,0,0,0,0,0,0,0,0,0,0,0,0,0,0,0,0,0~
,AR8,0,0,0,0,0,0,0,0)';
      PINUSE='POWER';
      NO_LOAD_CHECK='Both';
      NO_IO_CHECK='Both';
      NO_ASSERT_CHECK='TRUE';
      NO_DIR_CHECK='TRUE';
      ALLOW_CONNECT='TRUE';
    'VSS_AR9':
      PIN_NUMBER='(0,0,0,0,0,0,0,0,0,0,0,0,0,0,0,0,0,0,0,0,0,0,0,0,0,0,0,0,0,0,0~
,AR9,0,0,0,0,0,0,0,0)';
      PINUSE='POWER';
      NO_LOAD_CHECK='Both';
      NO_IO_CHECK='Both';
      NO_ASSERT_CHECK='TRUE';
      NO_DIR_CHECK='TRUE';
      ALLOW_CONNECT='TRUE';
    'VSS_AR12':
      PIN_NUMBER='(0,0,0,0,0,0,0,0,0,0,0,0,0,0,0,0,0,0,0,0,0,0,0,0,0,0,0,0,0,0,0~
,AR12,0,0,0,0,0,0,0,0)';
      PINUSE='POWER';
      NO_LOAD_CHECK='Both';
      NO_IO_CHECK='Both';
      NO_ASSERT_CHECK='TRUE';
      NO_DIR_CHECK='TRUE';
      ALLOW_CONNECT='TRUE';
    'VSS_AR13':
      PIN_NUMBER='(0,0,0,0,0,0,0,0,0,0,0,0,0,0,0,0,0,0,0,0,0,0,0,0,0,0,0,0,0,0,0~
,AR13,0,0,0,0,0,0,0,0)';
      PINUSE='POWER';
      NO_LOAD_CHECK='Both';
      NO_IO_CHECK='Both';
      NO_ASSERT_CHECK='TRUE';
      NO_DIR_CHECK='TRUE';
      ALLOW_CONNECT='TRUE';
    'VSS_AR15':
      PIN_NUMBER='(0,0,0,0,0,0,0,0,0,0,0,0,0,0,0,0,0,0,0,0,0,0,0,0,0,0,0,0,0,0,0~
,AR15,0,0,0,0,0,0,0,0)';
      PINUSE='POWER';
      NO_LOAD_CHECK='Both';
      NO_IO_CHECK='Both';
      NO_ASSERT_CHECK='TRUE';
      NO_DIR_CHECK='TRUE';
      ALLOW_CONNECT='TRUE';
    'VSS_AR16':
      PIN_NUMBER='(0,0,0,0,0,0,0,0,0,0,0,0,0,0,0,0,0,0,0,0,0,0,0,0,0,0,0,0,0,0,0~
,AR16,0,0,0,0,0,0,0,0)';
      PINUSE='POWER';
      NO_LOAD_CHECK='Both';
      NO_IO_CHECK='Both';
      NO_ASSERT_CHECK='TRUE';
      NO_DIR_CHECK='TRUE';
      ALLOW_CONNECT='TRUE';
    'VSS_AR19':
      PIN_NUMBER='(0,0,0,0,0,0,0,0,0,0,0,0,0,0,0,0,0,0,0,0,0,0,0,0,0,0,0,0,0,0,0~
,AR19,0,0,0,0,0,0,0,0)';
      PINUSE='POWER';
      NO_LOAD_CHECK='Both';
      NO_IO_CHECK='Both';
      NO_ASSERT_CHECK='TRUE';
      NO_DIR_CHECK='TRUE';
      ALLOW_CONNECT='TRUE';
    'VSS_AR20':
      PIN_NUMBER='(0,0,0,0,0,0,0,0,0,0,0,0,0,0,0,0,0,0,0,0,0,0,0,0,0,0,0,0,0,0,0~
,AR20,0,0,0,0,0,0,0,0)';
      PINUSE='POWER';
      NO_LOAD_CHECK='Both';
      NO_IO_CHECK='Both';
      NO_ASSERT_CHECK='TRUE';
      NO_DIR_CHECK='TRUE';
      ALLOW_CONNECT='TRUE';
    'VSS_AR22':
      PIN_NUMBER='(0,0,0,0,0,0,0,0,0,0,0,0,0,0,0,0,0,0,0,0,0,0,0,0,0,0,0,0,0,0,0~
,AR22,0,0,0,0,0,0,0,0)';
      PINUSE='POWER';
      NO_LOAD_CHECK='Both';
      NO_IO_CHECK='Both';
      NO_ASSERT_CHECK='TRUE';
      NO_DIR_CHECK='TRUE';
      ALLOW_CONNECT='TRUE';
    'VSS_AR24':
      PIN_NUMBER='(0,0,0,0,0,0,0,0,0,0,0,0,0,0,0,0,0,0,0,0,0,0,0,0,0,0,0,0,0,0,0~
,AR24,0,0,0,0,0,0,0,0)';
      PINUSE='POWER';
      NO_LOAD_CHECK='Both';
      NO_IO_CHECK='Both';
      NO_ASSERT_CHECK='TRUE';
      NO_DIR_CHECK='TRUE';
      ALLOW_CONNECT='TRUE';
    'VSS_AR26':
      PIN_NUMBER='(0,0,0,0,0,0,0,0,0,0,0,0,0,0,0,0,0,0,0,0,0,0,0,0,0,0,0,0,0,0,0~
,AR26,0,0,0,0,0,0,0,0)';
      PINUSE='POWER';
      NO_LOAD_CHECK='Both';
      NO_IO_CHECK='Both';
      NO_ASSERT_CHECK='TRUE';
      NO_DIR_CHECK='TRUE';
      ALLOW_CONNECT='TRUE';
    'VSS_AR28':
      PIN_NUMBER='(0,0,0,0,0,0,0,0,0,0,0,0,0,0,0,0,0,0,0,0,0,0,0,0,0,0,0,0,0,0,0~
,AR28,0,0,0,0,0,0,0,0)';
      PINUSE='POWER';
      NO_LOAD_CHECK='Both';
      NO_IO_CHECK='Both';
      NO_ASSERT_CHECK='TRUE';
      NO_DIR_CHECK='TRUE';
      ALLOW_CONNECT='TRUE';
    'VSS_AR30':
      PIN_NUMBER='(0,0,0,0,0,0,0,0,0,0,0,0,0,0,0,0,0,0,0,0,0,0,0,0,0,0,0,0,0,0,0~
,AR30,0,0,0,0,0,0,0,0)';
      PINUSE='POWER';
      NO_LOAD_CHECK='Both';
      NO_IO_CHECK='Both';
      NO_ASSERT_CHECK='TRUE';
      NO_DIR_CHECK='TRUE';
      ALLOW_CONNECT='TRUE';
    'VSS_AR32':
      PIN_NUMBER='(0,0,0,0,0,0,0,0,0,0,0,0,0,0,0,0,0,0,0,0,0,0,0,0,0,0,0,0,0,0,0~
,AR32,0,0,0,0,0,0,0,0)';
      PINUSE='POWER';
      NO_LOAD_CHECK='Both';
      NO_IO_CHECK='Both';
      NO_ASSERT_CHECK='TRUE';
      NO_DIR_CHECK='TRUE';
      ALLOW_CONNECT='TRUE';
    'VSS_AR34':
      PIN_NUMBER='(0,0,0,0,0,0,0,0,0,0,0,0,0,0,0,0,0,0,0,0,0,0,0,0,0,0,0,0,0,0,0~
,AR34,0,0,0,0,0,0,0,0)';
      PINUSE='POWER';
      NO_LOAD_CHECK='Both';
      NO_IO_CHECK='Both';
      NO_ASSERT_CHECK='TRUE';
      NO_DIR_CHECK='TRUE';
      ALLOW_CONNECT='TRUE';
    'VSS_AR36':
      PIN_NUMBER='(0,0,0,0,0,0,0,0,0,0,0,0,0,0,0,0,0,0,0,0,0,0,0,0,0,0,0,0,0,0,0~
,AR36,0,0,0,0,0,0,0,0)';
      PINUSE='POWER';
      NO_LOAD_CHECK='Both';
      NO_IO_CHECK='Both';
      NO_ASSERT_CHECK='TRUE';
      NO_DIR_CHECK='TRUE';
      ALLOW_CONNECT='TRUE';
    'VSS_AR41':
      PIN_NUMBER='(0,0,0,0,0,0,0,0,0,0,0,0,0,0,0,0,0,0,0,0,0,0,0,0,0,0,0,0,0,0,0~
,AR41,0,0,0,0,0,0,0,0)';
      PINUSE='POWER';
      NO_LOAD_CHECK='Both';
      NO_IO_CHECK='Both';
      NO_ASSERT_CHECK='TRUE';
      NO_DIR_CHECK='TRUE';
      ALLOW_CONNECT='TRUE';
    'VSS_AR43':
      PIN_NUMBER='(0,0,0,0,0,0,0,0,0,0,0,0,0,0,0,0,0,0,0,0,0,0,0,0,0,0,0,0,0,0,0~
,AR43,0,0,0,0,0,0,0,0)';
      PINUSE='POWER';
      NO_LOAD_CHECK='Both';
      NO_IO_CHECK='Both';
      NO_ASSERT_CHECK='TRUE';
      NO_DIR_CHECK='TRUE';
      ALLOW_CONNECT='TRUE';
    'VSS_AR45':
      PIN_NUMBER='(0,0,0,0,0,0,0,0,0,0,0,0,0,0,0,0,0,0,0,0,0,0,0,0,0,0,0,0,0,0,0~
,AR45,0,0,0,0,0,0,0,0)';
      PINUSE='POWER';
      NO_LOAD_CHECK='Both';
      NO_IO_CHECK='Both';
      NO_ASSERT_CHECK='TRUE';
      NO_DIR_CHECK='TRUE';
      ALLOW_CONNECT='TRUE';
    'VSS_AR47':
      PIN_NUMBER='(0,0,0,0,0,0,0,0,0,0,0,0,0,0,0,0,0,0,0,0,0,0,0,0,0,0,0,0,0,0,0~
,AR47,0,0,0,0,0,0,0,0)';
      PINUSE='POWER';
      NO_LOAD_CHECK='Both';
      NO_IO_CHECK='Both';
      NO_ASSERT_CHECK='TRUE';
      NO_DIR_CHECK='TRUE';
      ALLOW_CONNECT='TRUE';
    'VSS_AR49':
      PIN_NUMBER='(0,0,0,0,0,0,0,0,0,0,0,0,0,0,0,0,0,0,0,0,0,0,0,0,0,0,0,0,0,0,0~
,AR49,0,0,0,0,0,0,0,0)';
      PINUSE='POWER';
      NO_LOAD_CHECK='Both';
      NO_IO_CHECK='Both';
      NO_ASSERT_CHECK='TRUE';
      NO_DIR_CHECK='TRUE';
      ALLOW_CONNECT='TRUE';
    'VSS_AR51':
      PIN_NUMBER='(0,0,0,0,0,0,0,0,0,0,0,0,0,0,0,0,0,0,0,0,0,0,0,0,0,0,0,0,0,0,0~
,AR51,0,0,0,0,0,0,0,0)';
      PINUSE='POWER';
      NO_LOAD_CHECK='Both';
      NO_IO_CHECK='Both';
      NO_ASSERT_CHECK='TRUE';
      NO_DIR_CHECK='TRUE';
      ALLOW_CONNECT='TRUE';
    'VSS_AR53':
      PIN_NUMBER='(0,0,0,0,0,0,0,0,0,0,0,0,0,0,0,0,0,0,0,0,0,0,0,0,0,0,0,0,0,0,0~
,AR53,0,0,0,0,0,0,0,0)';
      PINUSE='POWER';
      NO_LOAD_CHECK='Both';
      NO_IO_CHECK='Both';
      NO_ASSERT_CHECK='TRUE';
      NO_DIR_CHECK='TRUE';
      ALLOW_CONNECT='TRUE';
    'VSS_AR56':
      PIN_NUMBER='(0,0,0,0,0,0,0,0,0,0,0,0,0,0,0,0,0,0,0,0,0,0,0,0,0,0,0,0,0,0,0~
,AR56,0,0,0,0,0,0,0,0)';
      PINUSE='POWER';
      NO_LOAD_CHECK='Both';
      NO_IO_CHECK='Both';
      NO_ASSERT_CHECK='TRUE';
      NO_DIR_CHECK='TRUE';
      ALLOW_CONNECT='TRUE';
    'VSS_AR57':
      PIN_NUMBER='(0,0,0,0,0,0,0,0,0,0,0,0,0,0,0,0,0,0,0,0,0,0,0,0,0,0,0,0,0,0,0~
,AR57,0,0,0,0,0,0,0,0)';
      PINUSE='POWER';
      NO_LOAD_CHECK='Both';
      NO_IO_CHECK='Both';
      NO_ASSERT_CHECK='TRUE';
      NO_DIR_CHECK='TRUE';
      ALLOW_CONNECT='TRUE';
    'VSS_AR60':
      PIN_NUMBER='(0,0,0,0,0,0,0,0,0,0,0,0,0,0,0,0,0,0,0,0,0,0,0,0,0,0,0,0,0,0,0~
,AR60,0,0,0,0,0,0,0,0)';
      PINUSE='POWER';
      NO_LOAD_CHECK='Both';
      NO_IO_CHECK='Both';
      NO_ASSERT_CHECK='TRUE';
      NO_DIR_CHECK='TRUE';
      ALLOW_CONNECT='TRUE';
    'VSS_AR61':
      PIN_NUMBER='(0,0,0,0,0,0,0,0,0,0,0,0,0,0,0,0,0,0,0,0,0,0,0,0,0,0,0,0,0,0,0~
,AR61,0,0,0,0,0,0,0,0)';
      PINUSE='POWER';
      NO_LOAD_CHECK='Both';
      NO_IO_CHECK='Both';
      NO_ASSERT_CHECK='TRUE';
      NO_DIR_CHECK='TRUE';
      ALLOW_CONNECT='TRUE';
    'VSS_AR63':
      PIN_NUMBER='(0,0,0,0,0,0,0,0,0,0,0,0,0,0,0,0,0,0,0,0,0,0,0,0,0,0,0,0,0,0,0~
,AR63,0,0,0,0,0,0,0,0)';
      PINUSE='POWER';
      NO_LOAD_CHECK='Both';
      NO_IO_CHECK='Both';
      NO_ASSERT_CHECK='TRUE';
      NO_DIR_CHECK='TRUE';
      ALLOW_CONNECT='TRUE';
    'VSS_AR64':
      PIN_NUMBER='(0,0,0,0,0,0,0,0,0,0,0,0,0,0,0,0,0,0,0,0,0,0,0,0,0,0,0,0,0,0,0~
,AR64,0,0,0,0,0,0,0,0)';
      PINUSE='POWER';
      NO_LOAD_CHECK='Both';
      NO_IO_CHECK='Both';
      NO_ASSERT_CHECK='TRUE';
      NO_DIR_CHECK='TRUE';
      ALLOW_CONNECT='TRUE';
    'VSS_AR67':
      PIN_NUMBER='(0,0,0,0,0,0,0,0,0,0,0,0,0,0,0,0,0,0,0,0,0,0,0,0,0,0,0,0,0,0,0~
,AR67,0,0,0,0,0,0,0,0)';
      PINUSE='POWER';
      NO_LOAD_CHECK='Both';
      NO_IO_CHECK='Both';
      NO_ASSERT_CHECK='TRUE';
      NO_DIR_CHECK='TRUE';
      ALLOW_CONNECT='TRUE';
    'VSS_AR68':
      PIN_NUMBER='(0,0,0,0,0,0,0,0,0,0,0,0,0,0,0,0,0,0,0,0,0,0,0,0,0,0,0,0,0,0,0~
,AR68,0,0,0,0,0,0,0,0)';
      PINUSE='POWER';
      NO_LOAD_CHECK='Both';
      NO_IO_CHECK='Both';
      NO_ASSERT_CHECK='TRUE';
      NO_DIR_CHECK='TRUE';
      ALLOW_CONNECT='TRUE';
    'VSS_AR70':
      PIN_NUMBER='(0,0,0,0,0,0,0,0,0,0,0,0,0,0,0,0,0,0,0,0,0,0,0,0,0,0,0,0,0,0,0~
,AR70,0,0,0,0,0,0,0,0)';
      PINUSE='POWER';
      NO_LOAD_CHECK='Both';
      NO_IO_CHECK='Both';
      NO_ASSERT_CHECK='TRUE';
      NO_DIR_CHECK='TRUE';
      ALLOW_CONNECT='TRUE';
    'VSS_AR71':
      PIN_NUMBER='(0,0,0,0,0,0,0,0,0,0,0,0,0,0,0,0,0,0,0,0,0,0,0,0,0,0,0,0,0,0,0~
,AR71,0,0,0,0,0,0,0,0)';
      PINUSE='POWER';
      NO_LOAD_CHECK='Both';
      NO_IO_CHECK='Both';
      NO_ASSERT_CHECK='TRUE';
      NO_DIR_CHECK='TRUE';
      ALLOW_CONNECT='TRUE';
    'VSS_AR75':
      PIN_NUMBER='(0,0,0,0,0,0,0,0,0,0,0,0,0,0,0,0,0,0,0,0,0,0,0,0,0,0,0,0,0,0,0~
,AR75,0,0,0,0,0,0,0,0)';
      PINUSE='POWER';
      NO_LOAD_CHECK='Both';
      NO_IO_CHECK='Both';
      NO_ASSERT_CHECK='TRUE';
      NO_DIR_CHECK='TRUE';
      ALLOW_CONNECT='TRUE';
    'VSS_AT3':
      PIN_NUMBER='(0,0,0,0,0,0,0,0,0,0,0,0,0,0,0,0,0,0,0,0,0,0,0,0,0,0,0,0,0,0,0~
,AT3,0,0,0,0,0,0,0,0)';
      PINUSE='POWER';
      NO_LOAD_CHECK='Both';
      NO_IO_CHECK='Both';
      NO_ASSERT_CHECK='TRUE';
      NO_DIR_CHECK='TRUE';
      ALLOW_CONNECT='TRUE';
    'VSS_AT4':
      PIN_NUMBER='(0,0,0,0,0,0,0,0,0,0,0,0,0,0,0,0,0,0,0,0,0,0,0,0,0,0,0,0,0,0,0~
,AT4,0,0,0,0,0,0,0,0)';
      PINUSE='POWER';
      NO_LOAD_CHECK='Both';
      NO_IO_CHECK='Both';
      NO_ASSERT_CHECK='TRUE';
      NO_DIR_CHECK='TRUE';
      ALLOW_CONNECT='TRUE';
    'VSS_AT5':
      PIN_NUMBER='(0,0,0,0,0,0,0,0,0,0,0,0,0,0,0,0,0,0,0,0,0,0,0,0,0,0,0,0,0,0,0~
,AT5,0,0,0,0,0,0,0,0)';
      PINUSE='POWER';
      NO_LOAD_CHECK='Both';
      NO_IO_CHECK='Both';
      NO_ASSERT_CHECK='TRUE';
      NO_DIR_CHECK='TRUE';
      ALLOW_CONNECT='TRUE';
    'VSS_AT6':
      PIN_NUMBER='(0,0,0,0,0,0,0,0,0,0,0,0,0,0,0,0,0,0,0,0,0,0,0,0,0,0,0,0,0,0,0~
,AT6,0,0,0,0,0,0,0,0)';
      PINUSE='POWER';
      NO_LOAD_CHECK='Both';
      NO_IO_CHECK='Both';
      NO_ASSERT_CHECK='TRUE';
      NO_DIR_CHECK='TRUE';
      ALLOW_CONNECT='TRUE';
    'VSS_AT8':
      PIN_NUMBER='(0,0,0,0,0,0,0,0,0,0,0,0,0,0,0,0,0,0,0,0,0,0,0,0,0,0,0,0,0,0,0~
,AT8,0,0,0,0,0,0,0,0)';
      PINUSE='POWER';
      NO_LOAD_CHECK='Both';
      NO_IO_CHECK='Both';
      NO_ASSERT_CHECK='TRUE';
      NO_DIR_CHECK='TRUE';
      ALLOW_CONNECT='TRUE';
    'VSS_AT9':
      PIN_NUMBER='(0,0,0,0,0,0,0,0,0,0,0,0,0,0,0,0,0,0,0,0,0,0,0,0,0,0,0,0,0,0,0~
,AT9,0,0,0,0,0,0,0,0)';
      PINUSE='POWER';
      NO_LOAD_CHECK='Both';
      NO_IO_CHECK='Both';
      NO_ASSERT_CHECK='TRUE';
      NO_DIR_CHECK='TRUE';
      ALLOW_CONNECT='TRUE';
    'VSS_AT10':
      PIN_NUMBER='(0,0,0,0,0,0,0,0,0,0,0,0,0,0,0,0,0,0,0,0,0,0,0,0,0,0,0,0,0,0,0~
,AT10,0,0,0,0,0,0,0,0)';
      PINUSE='POWER';
      NO_LOAD_CHECK='Both';
      NO_IO_CHECK='Both';
      NO_ASSERT_CHECK='TRUE';
      NO_DIR_CHECK='TRUE';
      ALLOW_CONNECT='TRUE';
    'VSS_AT12':
      PIN_NUMBER='(0,0,0,0,0,0,0,0,0,0,0,0,0,0,0,0,0,0,0,0,0,0,0,0,0,0,0,0,0,0,0~
,AT12,0,0,0,0,0,0,0,0)';
      PINUSE='POWER';
      NO_LOAD_CHECK='Both';
      NO_IO_CHECK='Both';
      NO_ASSERT_CHECK='TRUE';
      NO_DIR_CHECK='TRUE';
      ALLOW_CONNECT='TRUE';
    'VSS_AT13':
      PIN_NUMBER='(0,0,0,0,0,0,0,0,0,0,0,0,0,0,0,0,0,0,0,0,0,0,0,0,0,0,0,0,0,0,0~
,AT13,0,0,0,0,0,0,0,0)';
      PINUSE='POWER';
      NO_LOAD_CHECK='Both';
      NO_IO_CHECK='Both';
      NO_ASSERT_CHECK='TRUE';
      NO_DIR_CHECK='TRUE';
      ALLOW_CONNECT='TRUE';
    'VSS_AT15':
      PIN_NUMBER='(0,0,0,0,0,0,0,0,0,0,0,0,0,0,0,0,0,0,0,0,0,0,0,0,0,0,0,0,0,0,0~
,AT15,0,0,0,0,0,0,0,0)';
      PINUSE='POWER';
      NO_LOAD_CHECK='Both';
      NO_IO_CHECK='Both';
      NO_ASSERT_CHECK='TRUE';
      NO_DIR_CHECK='TRUE';
      ALLOW_CONNECT='TRUE';
    'VSS_AT16':
      PIN_NUMBER='(0,0,0,0,0,0,0,0,0,0,0,0,0,0,0,0,0,0,0,0,0,0,0,0,0,0,0,0,0,0,0~
,AT16,0,0,0,0,0,0,0,0)';
      PINUSE='POWER';
      NO_LOAD_CHECK='Both';
      NO_IO_CHECK='Both';
      NO_ASSERT_CHECK='TRUE';
      NO_DIR_CHECK='TRUE';
      ALLOW_CONNECT='TRUE';
    'VSS_AT17':
      PIN_NUMBER='(0,0,0,0,0,0,0,0,0,0,0,0,0,0,0,0,0,0,0,0,0,0,0,0,0,0,0,0,0,0,0~
,AT17,0,0,0,0,0,0,0,0)';
      PINUSE='POWER';
      NO_LOAD_CHECK='Both';
      NO_IO_CHECK='Both';
      NO_ASSERT_CHECK='TRUE';
      NO_DIR_CHECK='TRUE';
      ALLOW_CONNECT='TRUE';
    'VSS_AT19':
      PIN_NUMBER='(0,0,0,0,0,0,0,0,0,0,0,0,0,0,0,0,0,0,0,0,0,0,0,0,0,0,0,0,0,0,0~
,AT19,0,0,0,0,0,0,0,0)';
      PINUSE='POWER';
      NO_LOAD_CHECK='Both';
      NO_IO_CHECK='Both';
      NO_ASSERT_CHECK='TRUE';
      NO_DIR_CHECK='TRUE';
      ALLOW_CONNECT='TRUE';
    'VSS_AT20':
      PIN_NUMBER='(0,0,0,0,0,0,0,0,0,0,0,0,0,0,0,0,0,0,0,0,0,0,0,0,0,0,0,0,0,0,0~
,AT20,0,0,0,0,0,0,0,0)';
      PINUSE='POWER';
      NO_LOAD_CHECK='Both';
      NO_IO_CHECK='Both';
      NO_ASSERT_CHECK='TRUE';
      NO_DIR_CHECK='TRUE';
      ALLOW_CONNECT='TRUE';
    'VSS_AT23':
      PIN_NUMBER='(0,0,0,0,0,0,0,0,0,0,0,0,0,0,0,0,0,0,0,0,0,0,0,0,0,0,0,0,0,0,0~
,AT23,0,0,0,0,0,0,0,0)';
      PINUSE='POWER';
      NO_LOAD_CHECK='Both';
      NO_IO_CHECK='Both';
      NO_ASSERT_CHECK='TRUE';
      NO_DIR_CHECK='TRUE';
      ALLOW_CONNECT='TRUE';
    'VSS_AT25':
      PIN_NUMBER='(0,0,0,0,0,0,0,0,0,0,0,0,0,0,0,0,0,0,0,0,0,0,0,0,0,0,0,0,0,0,0~
,AT25,0,0,0,0,0,0,0,0)';
      PINUSE='POWER';
      NO_LOAD_CHECK='Both';
      NO_IO_CHECK='Both';
      NO_ASSERT_CHECK='TRUE';
      NO_DIR_CHECK='TRUE';
      ALLOW_CONNECT='TRUE';
    'VSS_AT27':
      PIN_NUMBER='(0,0,0,0,0,0,0,0,0,0,0,0,0,0,0,0,0,0,0,0,0,0,0,0,0,0,0,0,0,0,0~
,AT27,0,0,0,0,0,0,0,0)';
      PINUSE='POWER';
      NO_LOAD_CHECK='Both';
      NO_IO_CHECK='Both';
      NO_ASSERT_CHECK='TRUE';
      NO_DIR_CHECK='TRUE';
      ALLOW_CONNECT='TRUE';
    'VSS_AT29':
      PIN_NUMBER='(0,0,0,0,0,0,0,0,0,0,0,0,0,0,0,0,0,0,0,0,0,0,0,0,0,0,0,0,0,0,0~
,AT29,0,0,0,0,0,0,0,0)';
      PINUSE='POWER';
      NO_LOAD_CHECK='Both';
      NO_IO_CHECK='Both';
      NO_ASSERT_CHECK='TRUE';
      NO_DIR_CHECK='TRUE';
      ALLOW_CONNECT='TRUE';
    'VSS_AT31':
      PIN_NUMBER='(0,0,0,0,0,0,0,0,0,0,0,0,0,0,0,0,0,0,0,0,0,0,0,0,0,0,0,0,0,0,0~
,AT31,0,0,0,0,0,0,0,0)';
      PINUSE='POWER';
      NO_LOAD_CHECK='Both';
      NO_IO_CHECK='Both';
      NO_ASSERT_CHECK='TRUE';
      NO_DIR_CHECK='TRUE';
      ALLOW_CONNECT='TRUE';
    'VSS_AT33':
      PIN_NUMBER='(0,0,0,0,0,0,0,0,0,0,0,0,0,0,0,0,0,0,0,0,0,0,0,0,0,0,0,0,0,0,0~
,AT33,0,0,0,0,0,0,0,0)';
      PINUSE='POWER';
      NO_LOAD_CHECK='Both';
      NO_IO_CHECK='Both';
      NO_ASSERT_CHECK='TRUE';
      NO_DIR_CHECK='TRUE';
      ALLOW_CONNECT='TRUE';
    'VSS_AT35':
      PIN_NUMBER='(0,0,0,0,0,0,0,0,0,0,0,0,0,0,0,0,0,0,0,0,0,0,0,0,0,0,0,0,0,0,0~
,AT35,0,0,0,0,0,0,0,0)';
      PINUSE='POWER';
      NO_LOAD_CHECK='Both';
      NO_IO_CHECK='Both';
      NO_ASSERT_CHECK='TRUE';
      NO_DIR_CHECK='TRUE';
      ALLOW_CONNECT='TRUE';
    'VSS_AT37':
      PIN_NUMBER='(0,0,0,0,0,0,0,0,0,0,0,0,0,0,0,0,0,0,0,0,0,0,0,0,0,0,0,0,0,0,0~
,AT37,0,0,0,0,0,0,0,0)';
      PINUSE='POWER';
      NO_LOAD_CHECK='Both';
      NO_IO_CHECK='Both';
      NO_ASSERT_CHECK='TRUE';
      NO_DIR_CHECK='TRUE';
      ALLOW_CONNECT='TRUE';
    'VSS_AT40':
      PIN_NUMBER='(0,0,0,0,0,0,0,0,0,0,0,0,0,0,0,0,0,0,0,0,0,0,0,0,0,0,0,0,0,0,0~
,AT40,0,0,0,0,0,0,0,0)';
      PINUSE='POWER';
      NO_LOAD_CHECK='Both';
      NO_IO_CHECK='Both';
      NO_ASSERT_CHECK='TRUE';
      NO_DIR_CHECK='TRUE';
      ALLOW_CONNECT='TRUE';
    'VSS_AT42':
      PIN_NUMBER='(0,0,0,0,0,0,0,0,0,0,0,0,0,0,0,0,0,0,0,0,0,0,0,0,0,0,0,0,0,0,0~
,AT42,0,0,0,0,0,0,0,0)';
      PINUSE='POWER';
      NO_LOAD_CHECK='Both';
      NO_IO_CHECK='Both';
      NO_ASSERT_CHECK='TRUE';
      NO_DIR_CHECK='TRUE';
      ALLOW_CONNECT='TRUE';
    'VSS_AT44':
      PIN_NUMBER='(0,0,0,0,0,0,0,0,0,0,0,0,0,0,0,0,0,0,0,0,0,0,0,0,0,0,0,0,0,0,0~
,AT44,0,0,0,0,0,0,0,0)';
      PINUSE='POWER';
      NO_LOAD_CHECK='Both';
      NO_IO_CHECK='Both';
      NO_ASSERT_CHECK='TRUE';
      NO_DIR_CHECK='TRUE';
      ALLOW_CONNECT='TRUE';
    'VSS_AT46':
      PIN_NUMBER='(0,0,0,0,0,0,0,0,0,0,0,0,0,0,0,0,0,0,0,0,0,0,0,0,0,0,0,0,0,0,0~
,AT46,0,0,0,0,0,0,0,0)';
      PINUSE='POWER';
      NO_LOAD_CHECK='Both';
      NO_IO_CHECK='Both';
      NO_ASSERT_CHECK='TRUE';
      NO_DIR_CHECK='TRUE';
      ALLOW_CONNECT='TRUE';
    'VSS_AT48':
      PIN_NUMBER='(0,0,0,0,0,0,0,0,0,0,0,0,0,0,0,0,0,0,0,0,0,0,0,0,0,0,0,0,0,0,0~
,AT48,0,0,0,0,0,0,0,0)';
      PINUSE='POWER';
      NO_LOAD_CHECK='Both';
      NO_IO_CHECK='Both';
      NO_ASSERT_CHECK='TRUE';
      NO_DIR_CHECK='TRUE';
      ALLOW_CONNECT='TRUE';
    'VSS_AT50':
      PIN_NUMBER='(0,0,0,0,0,0,0,0,0,0,0,0,0,0,0,0,0,0,0,0,0,0,0,0,0,0,0,0,0,0,0~
,AT50,0,0,0,0,0,0,0,0)';
      PINUSE='POWER';
      NO_LOAD_CHECK='Both';
      NO_IO_CHECK='Both';
      NO_ASSERT_CHECK='TRUE';
      NO_DIR_CHECK='TRUE';
      ALLOW_CONNECT='TRUE';
    'VSS_AT52':
      PIN_NUMBER='(0,0,0,0,0,0,0,0,0,0,0,0,0,0,0,0,0,0,0,0,0,0,0,0,0,0,0,0,0,0,0~
,AT52,0,0,0,0,0,0,0,0)';
      PINUSE='POWER';
      NO_LOAD_CHECK='Both';
      NO_IO_CHECK='Both';
      NO_ASSERT_CHECK='TRUE';
      NO_DIR_CHECK='TRUE';
      ALLOW_CONNECT='TRUE';
    'VSS_AT54':
      PIN_NUMBER='(0,0,0,0,0,0,0,0,0,0,0,0,0,0,0,0,0,0,0,0,0,0,0,0,0,0,0,0,0,0,0~
,AT54,0,0,0,0,0,0,0,0)';
      PINUSE='POWER';
      NO_LOAD_CHECK='Both';
      NO_IO_CHECK='Both';
      NO_ASSERT_CHECK='TRUE';
      NO_DIR_CHECK='TRUE';
      ALLOW_CONNECT='TRUE';
    'VSS_AT56':
      PIN_NUMBER='(0,0,0,0,0,0,0,0,0,0,0,0,0,0,0,0,0,0,0,0,0,0,0,0,0,0,0,0,0,0,0~
,AT56,0,0,0,0,0,0,0,0)';
      PINUSE='POWER';
      NO_LOAD_CHECK='Both';
      NO_IO_CHECK='Both';
      NO_ASSERT_CHECK='TRUE';
      NO_DIR_CHECK='TRUE';
      ALLOW_CONNECT='TRUE';
    'VSS_AT57':
      PIN_NUMBER='(0,0,0,0,0,0,0,0,0,0,0,0,0,0,0,0,0,0,0,0,0,0,0,0,0,0,0,0,0,0,0~
,AT57,0,0,0,0,0,0,0,0)';
      PINUSE='POWER';
      NO_LOAD_CHECK='Both';
      NO_IO_CHECK='Both';
      NO_ASSERT_CHECK='TRUE';
      NO_DIR_CHECK='TRUE';
      ALLOW_CONNECT='TRUE';
    'VSS_AT59':
      PIN_NUMBER='(0,0,0,0,0,0,0,0,0,0,0,0,0,0,0,0,0,0,0,0,0,0,0,0,0,0,0,0,0,0,0~
,AT59,0,0,0,0,0,0,0,0)';
      PINUSE='POWER';
      NO_LOAD_CHECK='Both';
      NO_IO_CHECK='Both';
      NO_ASSERT_CHECK='TRUE';
      NO_DIR_CHECK='TRUE';
      ALLOW_CONNECT='TRUE';
    'VSS_AT60':
      PIN_NUMBER='(0,0,0,0,0,0,0,0,0,0,0,0,0,0,0,0,0,0,0,0,0,0,0,0,0,0,0,0,0,0,0~
,AT60,0,0,0,0,0,0,0,0)';
      PINUSE='POWER';
      NO_LOAD_CHECK='Both';
      NO_IO_CHECK='Both';
      NO_ASSERT_CHECK='TRUE';
      NO_DIR_CHECK='TRUE';
      ALLOW_CONNECT='TRUE';
    'VSS_AT61':
      PIN_NUMBER='(0,0,0,0,0,0,0,0,0,0,0,0,0,0,0,0,0,0,0,0,0,0,0,0,0,0,0,0,0,0,0~
,AT61,0,0,0,0,0,0,0,0)';
      PINUSE='POWER';
      NO_LOAD_CHECK='Both';
      NO_IO_CHECK='Both';
      NO_ASSERT_CHECK='TRUE';
      NO_DIR_CHECK='TRUE';
      ALLOW_CONNECT='TRUE';
    'VSS_AT63':
      PIN_NUMBER='(0,0,0,0,0,0,0,0,0,0,0,0,0,0,0,0,0,0,0,0,0,0,0,0,0,0,0,0,0,0,0~
,AT63,0,0,0,0,0,0,0,0)';
      PINUSE='POWER';
      NO_LOAD_CHECK='Both';
      NO_IO_CHECK='Both';
      NO_ASSERT_CHECK='TRUE';
      NO_DIR_CHECK='TRUE';
      ALLOW_CONNECT='TRUE';
    'VSS_AT64':
      PIN_NUMBER='(0,0,0,0,0,0,0,0,0,0,0,0,0,0,0,0,0,0,0,0,0,0,0,0,0,0,0,0,0,0,0~
,AT64,0,0,0,0,0,0,0,0)';
      PINUSE='POWER';
      NO_LOAD_CHECK='Both';
      NO_IO_CHECK='Both';
      NO_ASSERT_CHECK='TRUE';
      NO_DIR_CHECK='TRUE';
      ALLOW_CONNECT='TRUE';
    'VSS_AT66':
      PIN_NUMBER='(0,0,0,0,0,0,0,0,0,0,0,0,0,0,0,0,0,0,0,0,0,0,0,0,0,0,0,0,0,0,0~
,AT66,0,0,0,0,0,0,0,0)';
      PINUSE='POWER';
      NO_LOAD_CHECK='Both';
      NO_IO_CHECK='Both';
      NO_ASSERT_CHECK='TRUE';
      NO_DIR_CHECK='TRUE';
      ALLOW_CONNECT='TRUE';
    'VSS_AT67':
      PIN_NUMBER='(0,0,0,0,0,0,0,0,0,0,0,0,0,0,0,0,0,0,0,0,0,0,0,0,0,0,0,0,0,0,0~
,AT67,0,0,0,0,0,0,0,0)';
      PINUSE='POWER';
      NO_LOAD_CHECK='Both';
      NO_IO_CHECK='Both';
      NO_ASSERT_CHECK='TRUE';
      NO_DIR_CHECK='TRUE';
      ALLOW_CONNECT='TRUE';
    'VSS_AT68':
      PIN_NUMBER='(0,0,0,0,0,0,0,0,0,0,0,0,0,0,0,0,0,0,0,0,0,0,0,0,0,0,0,0,0,0,0~
,AT68,0,0,0,0,0,0,0,0)';
      PINUSE='POWER';
      NO_LOAD_CHECK='Both';
      NO_IO_CHECK='Both';
      NO_ASSERT_CHECK='TRUE';
      NO_DIR_CHECK='TRUE';
      ALLOW_CONNECT='TRUE';
    'VSS_AT70':
      PIN_NUMBER='(0,0,0,0,0,0,0,0,0,0,0,0,0,0,0,0,0,0,0,0,0,0,0,0,0,0,0,0,0,0,0~
,AT70,0,0,0,0,0,0,0,0)';
      PINUSE='POWER';
      NO_LOAD_CHECK='Both';
      NO_IO_CHECK='Both';
      NO_ASSERT_CHECK='TRUE';
      NO_DIR_CHECK='TRUE';
      ALLOW_CONNECT='TRUE';
    'VSS_AT71':
      PIN_NUMBER='(0,0,0,0,0,0,0,0,0,0,0,0,0,0,0,0,0,0,0,0,0,0,0,0,0,0,0,0,0,0,0~
,AT71,0,0,0,0,0,0,0,0)';
      PINUSE='POWER';
      NO_LOAD_CHECK='Both';
      NO_IO_CHECK='Both';
      NO_ASSERT_CHECK='TRUE';
      NO_DIR_CHECK='TRUE';
      ALLOW_CONNECT='TRUE';
    'VSS_AT72':
      PIN_NUMBER='(0,0,0,0,0,0,0,0,0,0,0,0,0,0,0,0,0,0,0,0,0,0,0,0,0,0,0,0,0,0,0~
,AT72,0,0,0,0,0,0,0,0)';
      PINUSE='POWER';
      NO_LOAD_CHECK='Both';
      NO_IO_CHECK='Both';
      NO_ASSERT_CHECK='TRUE';
      NO_DIR_CHECK='TRUE';
      ALLOW_CONNECT='TRUE';
    'VSS_AT73':
      PIN_NUMBER='(0,0,0,0,0,0,0,0,0,0,0,0,0,0,0,0,0,0,0,0,0,0,0,0,0,0,0,0,0,0,0~
,AT73,0,0,0,0,0,0,0,0)';
      PINUSE='POWER';
      NO_LOAD_CHECK='Both';
      NO_IO_CHECK='Both';
      NO_ASSERT_CHECK='TRUE';
      NO_DIR_CHECK='TRUE';
      ALLOW_CONNECT='TRUE';
    'VSS_AU1':
      PIN_NUMBER='(0,0,0,0,0,0,0,0,0,0,0,0,0,0,0,0,0,0,0,0,0,0,0,0,0,0,0,0,0,0,0~
,AU1,0,0,0,0,0,0,0,0)';
      PINUSE='POWER';
      NO_LOAD_CHECK='Both';
      NO_IO_CHECK='Both';
      NO_ASSERT_CHECK='TRUE';
      NO_DIR_CHECK='TRUE';
      ALLOW_CONNECT='TRUE';
    'VSS_AU3':
      PIN_NUMBER='(0,0,0,0,0,0,0,0,0,0,0,0,0,0,0,0,0,0,0,0,0,0,0,0,0,0,0,0,0,0,0~
,AU3,0,0,0,0,0,0,0,0)';
      PINUSE='POWER';
      NO_LOAD_CHECK='Both';
      NO_IO_CHECK='Both';
      NO_ASSERT_CHECK='TRUE';
      NO_DIR_CHECK='TRUE';
      ALLOW_CONNECT='TRUE';
    'VSS_AU4':
      PIN_NUMBER='(0,0,0,0,0,0,0,0,0,0,0,0,0,0,0,0,0,0,0,0,0,0,0,0,0,0,0,0,0,0,0~
,AU4,0,0,0,0,0,0,0,0)';
      PINUSE='POWER';
      NO_LOAD_CHECK='Both';
      NO_IO_CHECK='Both';
      NO_ASSERT_CHECK='TRUE';
      NO_DIR_CHECK='TRUE';
      ALLOW_CONNECT='TRUE';
    'VSS_AU6':
      PIN_NUMBER='(0,0,0,0,0,0,0,0,0,0,0,0,0,0,0,0,0,0,0,0,0,0,0,0,0,0,0,0,0,0,0~
,AU6,0,0,0,0,0,0,0,0)';
      PINUSE='POWER';
      NO_LOAD_CHECK='Both';
      NO_IO_CHECK='Both';
      NO_ASSERT_CHECK='TRUE';
      NO_DIR_CHECK='TRUE';
      ALLOW_CONNECT='TRUE';
    'VSS_AU8':
      PIN_NUMBER='(0,0,0,0,0,0,0,0,0,0,0,0,0,0,0,0,0,0,0,0,0,0,0,0,0,0,0,0,0,0,0~
,AU8,0,0,0,0,0,0,0,0)';
      PINUSE='POWER';
      NO_LOAD_CHECK='Both';
      NO_IO_CHECK='Both';
      NO_ASSERT_CHECK='TRUE';
      NO_DIR_CHECK='TRUE';
      ALLOW_CONNECT='TRUE';
    'VSS_AU11':
      PIN_NUMBER='(0,0,0,0,0,0,0,0,0,0,0,0,0,0,0,0,0,0,0,0,0,0,0,0,0,0,0,0,0,0,0~
,AU11,0,0,0,0,0,0,0,0)';
      PINUSE='POWER';
      NO_LOAD_CHECK='Both';
      NO_IO_CHECK='Both';
      NO_ASSERT_CHECK='TRUE';
      NO_DIR_CHECK='TRUE';
      ALLOW_CONNECT='TRUE';
    'VSS_AU13':
      PIN_NUMBER='(0,0,0,0,0,0,0,0,0,0,0,0,0,0,0,0,0,0,0,0,0,0,0,0,0,0,0,0,0,0,0~
,AU13,0,0,0,0,0,0,0,0)';
      PINUSE='POWER';
      NO_LOAD_CHECK='Both';
      NO_IO_CHECK='Both';
      NO_ASSERT_CHECK='TRUE';
      NO_DIR_CHECK='TRUE';
      ALLOW_CONNECT='TRUE';
    'VSS_AU15':
      PIN_NUMBER='(0,0,0,0,0,0,0,0,0,0,0,0,0,0,0,0,0,0,0,0,0,0,0,0,0,0,0,0,0,0,0~
,AU15,0,0,0,0,0,0,0,0)';
      PINUSE='POWER';
      NO_LOAD_CHECK='Both';
      NO_IO_CHECK='Both';
      NO_ASSERT_CHECK='TRUE';
      NO_DIR_CHECK='TRUE';
      ALLOW_CONNECT='TRUE';
    'VSS_AU18':
      PIN_NUMBER='(0,0,0,0,0,0,0,0,0,0,0,0,0,0,0,0,0,0,0,0,0,0,0,0,0,0,0,0,0,0,0~
,AU18,0,0,0,0,0,0,0,0)';
      PINUSE='POWER';
      NO_LOAD_CHECK='Both';
      NO_IO_CHECK='Both';
      NO_ASSERT_CHECK='TRUE';
      NO_DIR_CHECK='TRUE';
      ALLOW_CONNECT='TRUE';
    'VSS_AU20':
      PIN_NUMBER='(0,0,0,0,0,0,0,0,0,0,0,0,0,0,0,0,0,0,0,0,0,0,0,0,0,0,0,0,0,0,0~
,AU20,0,0,0,0,0,0,0,0)';
      PINUSE='POWER';
      NO_LOAD_CHECK='Both';
      NO_IO_CHECK='Both';
      NO_ASSERT_CHECK='TRUE';
      NO_DIR_CHECK='TRUE';
      ALLOW_CONNECT='TRUE';
    'VSS_AU22':
      PIN_NUMBER='(0,0,0,0,0,0,0,0,0,0,0,0,0,0,0,0,0,0,0,0,0,0,0,0,0,0,0,0,0,0,0~
,AU22,0,0,0,0,0,0,0,0)';
      PINUSE='POWER';
      NO_LOAD_CHECK='Both';
      NO_IO_CHECK='Both';
      NO_ASSERT_CHECK='TRUE';
      NO_DIR_CHECK='TRUE';
      ALLOW_CONNECT='TRUE';
    'VSS_AU24':
      PIN_NUMBER='(0,0,0,0,0,0,0,0,0,0,0,0,0,0,0,0,0,0,0,0,0,0,0,0,0,0,0,0,0,0,0~
,AU24,0,0,0,0,0,0,0,0)';
      PINUSE='POWER';
      NO_LOAD_CHECK='Both';
      NO_IO_CHECK='Both';
      NO_ASSERT_CHECK='TRUE';
      NO_DIR_CHECK='TRUE';
      ALLOW_CONNECT='TRUE';
    'VSS_AU26':
      PIN_NUMBER='(0,0,0,0,0,0,0,0,0,0,0,0,0,0,0,0,0,0,0,0,0,0,0,0,0,0,0,0,0,0,0~
,AU26,0,0,0,0,0,0,0,0)';
      PINUSE='POWER';
      NO_LOAD_CHECK='Both';
      NO_IO_CHECK='Both';
      NO_ASSERT_CHECK='TRUE';
      NO_DIR_CHECK='TRUE';
      ALLOW_CONNECT='TRUE';
    'VSS_AU28':
      PIN_NUMBER='(0,0,0,0,0,0,0,0,0,0,0,0,0,0,0,0,0,0,0,0,0,0,0,0,0,0,0,0,0,0,0~
,AU28,0,0,0,0,0,0,0,0)';
      PINUSE='POWER';
      NO_LOAD_CHECK='Both';
      NO_IO_CHECK='Both';
      NO_ASSERT_CHECK='TRUE';
      NO_DIR_CHECK='TRUE';
      ALLOW_CONNECT='TRUE';
    'VSS_AU30':
      PIN_NUMBER='(0,0,0,0,0,0,0,0,0,0,0,0,0,0,0,0,0,0,0,0,0,0,0,0,0,0,0,0,0,0,0~
,AU30,0,0,0,0,0,0,0,0)';
      PINUSE='POWER';
      NO_LOAD_CHECK='Both';
      NO_IO_CHECK='Both';
      NO_ASSERT_CHECK='TRUE';
      NO_DIR_CHECK='TRUE';
      ALLOW_CONNECT='TRUE';
    'VSS_AU32':
      PIN_NUMBER='(0,0,0,0,0,0,0,0,0,0,0,0,0,0,0,0,0,0,0,0,0,0,0,0,0,0,0,0,0,0,0~
,AU32,0,0,0,0,0,0,0,0)';
      PINUSE='POWER';
      NO_LOAD_CHECK='Both';
      NO_IO_CHECK='Both';
      NO_ASSERT_CHECK='TRUE';
      NO_DIR_CHECK='TRUE';
      ALLOW_CONNECT='TRUE';
    'VSS_AU34':
      PIN_NUMBER='(0,0,0,0,0,0,0,0,0,0,0,0,0,0,0,0,0,0,0,0,0,0,0,0,0,0,0,0,0,0,0~
,AU34,0,0,0,0,0,0,0,0)';
      PINUSE='POWER';
      NO_LOAD_CHECK='Both';
      NO_IO_CHECK='Both';
      NO_ASSERT_CHECK='TRUE';
      NO_DIR_CHECK='TRUE';
      ALLOW_CONNECT='TRUE';
    'VSS_AU36':
      PIN_NUMBER='(0,0,0,0,0,0,0,0,0,0,0,0,0,0,0,0,0,0,0,0,0,0,0,0,0,0,0,0,0,0,0~
,AU36,0,0,0,0,0,0,0,0)';
      PINUSE='POWER';
      NO_LOAD_CHECK='Both';
      NO_IO_CHECK='Both';
      NO_ASSERT_CHECK='TRUE';
      NO_DIR_CHECK='TRUE';
      ALLOW_CONNECT='TRUE';
    'VSS_AU41':
      PIN_NUMBER='(0,0,0,0,0,0,0,0,0,0,0,0,0,0,0,0,0,0,0,0,0,0,0,0,0,0,0,0,0,0,0~
,AU41,0,0,0,0,0,0,0,0)';
      PINUSE='POWER';
      NO_LOAD_CHECK='Both';
      NO_IO_CHECK='Both';
      NO_ASSERT_CHECK='TRUE';
      NO_DIR_CHECK='TRUE';
      ALLOW_CONNECT='TRUE';
    'VSS_AU43':
      PIN_NUMBER='(0,0,0,0,0,0,0,0,0,0,0,0,0,0,0,0,0,0,0,0,0,0,0,0,0,0,0,0,0,0,0~
,AU43,0,0,0,0,0,0,0,0)';
      PINUSE='POWER';
      NO_LOAD_CHECK='Both';
      NO_IO_CHECK='Both';
      NO_ASSERT_CHECK='TRUE';
      NO_DIR_CHECK='TRUE';
      ALLOW_CONNECT='TRUE';
    'VSS_AU45':
      PIN_NUMBER='(0,0,0,0,0,0,0,0,0,0,0,0,0,0,0,0,0,0,0,0,0,0,0,0,0,0,0,0,0,0,0~
,AU45,0,0,0,0,0,0,0,0)';
      PINUSE='POWER';
      NO_LOAD_CHECK='Both';
      NO_IO_CHECK='Both';
      NO_ASSERT_CHECK='TRUE';
      NO_DIR_CHECK='TRUE';
      ALLOW_CONNECT='TRUE';
    'VSS_AU47':
      PIN_NUMBER='(0,0,0,0,0,0,0,0,0,0,0,0,0,0,0,0,0,0,0,0,0,0,0,0,0,0,0,0,0,0,0~
,AU47,0,0,0,0,0,0,0,0)';
      PINUSE='POWER';
      NO_LOAD_CHECK='Both';
      NO_IO_CHECK='Both';
      NO_ASSERT_CHECK='TRUE';
      NO_DIR_CHECK='TRUE';
      ALLOW_CONNECT='TRUE';
    'VSS_AU49':
      PIN_NUMBER='(0,0,0,0,0,0,0,0,0,0,0,0,0,0,0,0,0,0,0,0,0,0,0,0,0,0,0,0,0,0,0~
,AU49,0,0,0,0,0,0,0,0)';
      PINUSE='POWER';
      NO_LOAD_CHECK='Both';
      NO_IO_CHECK='Both';
      NO_ASSERT_CHECK='TRUE';
      NO_DIR_CHECK='TRUE';
      ALLOW_CONNECT='TRUE';
    'VSS_AU51':
      PIN_NUMBER='(0,0,0,0,0,0,0,0,0,0,0,0,0,0,0,0,0,0,0,0,0,0,0,0,0,0,0,0,0,0,0~
,AU51,0,0,0,0,0,0,0,0)';
      PINUSE='POWER';
      NO_LOAD_CHECK='Both';
      NO_IO_CHECK='Both';
      NO_ASSERT_CHECK='TRUE';
      NO_DIR_CHECK='TRUE';
      ALLOW_CONNECT='TRUE';
    'VSS_AU53':
      PIN_NUMBER='(0,0,0,0,0,0,0,0,0,0,0,0,0,0,0,0,0,0,0,0,0,0,0,0,0,0,0,0,0,0,0~
,AU53,0,0,0,0,0,0,0,0)';
      PINUSE='POWER';
      NO_LOAD_CHECK='Both';
      NO_IO_CHECK='Both';
      NO_ASSERT_CHECK='TRUE';
      NO_DIR_CHECK='TRUE';
      ALLOW_CONNECT='TRUE';
    'VSS_AU56':
      PIN_NUMBER='(0,0,0,0,0,0,0,0,0,0,0,0,0,0,0,0,0,0,0,0,0,0,0,0,0,0,0,0,0,0,0~
,AU56,0,0,0,0,0,0,0,0)';
      PINUSE='POWER';
      NO_LOAD_CHECK='Both';
      NO_IO_CHECK='Both';
      NO_ASSERT_CHECK='TRUE';
      NO_DIR_CHECK='TRUE';
      ALLOW_CONNECT='TRUE';
    'VSS_AU58':
      PIN_NUMBER='(0,0,0,0,0,0,0,0,0,0,0,0,0,0,0,0,0,0,0,0,0,0,0,0,0,0,0,0,0,0,0~
,AU58,0,0,0,0,0,0,0,0)';
      PINUSE='POWER';
      NO_LOAD_CHECK='Both';
      NO_IO_CHECK='Both';
      NO_ASSERT_CHECK='TRUE';
      NO_DIR_CHECK='TRUE';
      ALLOW_CONNECT='TRUE';
    'VSS_AU61':
      PIN_NUMBER='(0,0,0,0,0,0,0,0,0,0,0,0,0,0,0,0,0,0,0,0,0,0,0,0,0,0,0,0,0,0,0~
,AU61,0,0,0,0,0,0,0,0)';
      PINUSE='POWER';
      NO_LOAD_CHECK='Both';
      NO_IO_CHECK='Both';
      NO_ASSERT_CHECK='TRUE';
      NO_DIR_CHECK='TRUE';
      ALLOW_CONNECT='TRUE';
    'VSS_AU63':
      PIN_NUMBER='(0,0,0,0,0,0,0,0,0,0,0,0,0,0,0,0,0,0,0,0,0,0,0,0,0,0,0,0,0,0,0~
,AU63,0,0,0,0,0,0,0,0)';
      PINUSE='POWER';
      NO_LOAD_CHECK='Both';
      NO_IO_CHECK='Both';
      NO_ASSERT_CHECK='TRUE';
      NO_DIR_CHECK='TRUE';
      ALLOW_CONNECT='TRUE';
    'VSS_AU65':
      PIN_NUMBER='(0,0,0,0,0,0,0,0,0,0,0,0,0,0,0,0,0,0,0,0,0,0,0,0,0,0,0,0,0,0,0~
,AU65,0,0,0,0,0,0,0,0)';
      PINUSE='POWER';
      NO_LOAD_CHECK='Both';
      NO_IO_CHECK='Both';
      NO_ASSERT_CHECK='TRUE';
      NO_DIR_CHECK='TRUE';
      ALLOW_CONNECT='TRUE';
    'VSS_AU68':
      PIN_NUMBER='(0,0,0,0,0,0,0,0,0,0,0,0,0,0,0,0,0,0,0,0,0,0,0,0,0,0,0,0,0,0,0~
,AU68,0,0,0,0,0,0,0,0)';
      PINUSE='POWER';
      NO_LOAD_CHECK='Both';
      NO_IO_CHECK='Both';
      NO_ASSERT_CHECK='TRUE';
      NO_DIR_CHECK='TRUE';
      ALLOW_CONNECT='TRUE';
    'VSS_AU70':
      PIN_NUMBER='(0,0,0,0,0,0,0,0,0,0,0,0,0,0,0,0,0,0,0,0,0,0,0,0,0,0,0,0,0,0,0~
,AU70,0,0,0,0,0,0,0,0)';
      PINUSE='POWER';
      NO_LOAD_CHECK='Both';
      NO_IO_CHECK='Both';
      NO_ASSERT_CHECK='TRUE';
      NO_DIR_CHECK='TRUE';
      ALLOW_CONNECT='TRUE';
    'VSS_AU72':
      PIN_NUMBER='(0,0,0,0,0,0,0,0,0,0,0,0,0,0,0,0,0,0,0,0,0,0,0,0,0,0,0,0,0,0,0~
,AU72,0,0,0,0,0,0,0,0)';
      PINUSE='POWER';
      NO_LOAD_CHECK='Both';
      NO_IO_CHECK='Both';
      NO_ASSERT_CHECK='TRUE';
      NO_DIR_CHECK='TRUE';
      ALLOW_CONNECT='TRUE';
    'VSS_AU73':
      PIN_NUMBER='(0,0,0,0,0,0,0,0,0,0,0,0,0,0,0,0,0,0,0,0,0,0,0,0,0,0,0,0,0,0,0~
,AU73,0,0,0,0,0,0,0,0)';
      PINUSE='POWER';
      NO_LOAD_CHECK='Both';
      NO_IO_CHECK='Both';
      NO_ASSERT_CHECK='TRUE';
      NO_DIR_CHECK='TRUE';
      ALLOW_CONNECT='TRUE';
    'VSS_AU75':
      PIN_NUMBER='(0,0,0,0,0,0,0,0,0,0,0,0,0,0,0,0,0,0,0,0,0,0,0,0,0,0,0,0,0,0,0~
,AU75,0,0,0,0,0,0,0,0)';
      PINUSE='POWER';
      NO_LOAD_CHECK='Both';
      NO_IO_CHECK='Both';
      NO_ASSERT_CHECK='TRUE';
      NO_DIR_CHECK='TRUE';
      ALLOW_CONNECT='TRUE';
    'VSS_AV3':
      PIN_NUMBER='(0,0,0,0,0,0,0,0,0,0,0,0,0,0,0,0,0,0,0,0,0,0,0,0,0,0,0,0,0,0,0~
,AV3,0,0,0,0,0,0,0,0)';
      PINUSE='POWER';
      NO_LOAD_CHECK='Both';
      NO_IO_CHECK='Both';
      NO_ASSERT_CHECK='TRUE';
      NO_DIR_CHECK='TRUE';
      ALLOW_CONNECT='TRUE';
    'VSS_AV8':
      PIN_NUMBER='(0,0,0,0,0,0,0,0,0,0,0,0,0,0,0,0,0,0,0,0,0,0,0,0,0,0,0,0,0,0,0~
,AV8,0,0,0,0,0,0,0,0)';
      PINUSE='POWER';
      NO_LOAD_CHECK='Both';
      NO_IO_CHECK='Both';
      NO_ASSERT_CHECK='TRUE';
      NO_DIR_CHECK='TRUE';
      ALLOW_CONNECT='TRUE';
    'VSS_AV10':
      PIN_NUMBER='(0,0,0,0,0,0,0,0,0,0,0,0,0,0,0,0,0,0,0,0,0,0,0,0,0,0,0,0,0,0,0~
,AV10,0,0,0,0,0,0,0,0)';
      PINUSE='POWER';
      NO_LOAD_CHECK='Both';
      NO_IO_CHECK='Both';
      NO_ASSERT_CHECK='TRUE';
      NO_DIR_CHECK='TRUE';
      ALLOW_CONNECT='TRUE';
    'VSS_AV15':
      PIN_NUMBER='(0,0,0,0,0,0,0,0,0,0,0,0,0,0,0,0,0,0,0,0,0,0,0,0,0,0,0,0,0,0,0~
,AV15,0,0,0,0,0,0,0,0)';
      PINUSE='POWER';
      NO_LOAD_CHECK='Both';
      NO_IO_CHECK='Both';
      NO_ASSERT_CHECK='TRUE';
      NO_DIR_CHECK='TRUE';
      ALLOW_CONNECT='TRUE';
    'VSS_AV17':
      PIN_NUMBER='(0,0,0,0,0,0,0,0,0,0,0,0,0,0,0,0,0,0,0,0,0,0,0,0,0,0,0,0,0,0,0~
,AV17,0,0,0,0,0,0,0,0)';
      PINUSE='POWER';
      NO_LOAD_CHECK='Both';
      NO_IO_CHECK='Both';
      NO_ASSERT_CHECK='TRUE';
      NO_DIR_CHECK='TRUE';
      ALLOW_CONNECT='TRUE';
    'VSS_AV23':
      PIN_NUMBER='(0,0,0,0,0,0,0,0,0,0,0,0,0,0,0,0,0,0,0,0,0,0,0,0,0,0,0,0,0,0,0~
,AV23,0,0,0,0,0,0,0,0)';
      PINUSE='POWER';
      NO_LOAD_CHECK='Both';
      NO_IO_CHECK='Both';
      NO_ASSERT_CHECK='TRUE';
      NO_DIR_CHECK='TRUE';
      ALLOW_CONNECT='TRUE';
    'VSS_AV25':
      PIN_NUMBER='(0,0,0,0,0,0,0,0,0,0,0,0,0,0,0,0,0,0,0,0,0,0,0,0,0,0,0,0,0,0,0~
,AV25,0,0,0,0,0,0,0,0)';
      PINUSE='POWER';
      NO_LOAD_CHECK='Both';
      NO_IO_CHECK='Both';
      NO_ASSERT_CHECK='TRUE';
      NO_DIR_CHECK='TRUE';
      ALLOW_CONNECT='TRUE';
    'VSS_AV27':
      PIN_NUMBER='(0,0,0,0,0,0,0,0,0,0,0,0,0,0,0,0,0,0,0,0,0,0,0,0,0,0,0,0,0,0,0~
,AV27,0,0,0,0,0,0,0,0)';
      PINUSE='POWER';
      NO_LOAD_CHECK='Both';
      NO_IO_CHECK='Both';
      NO_ASSERT_CHECK='TRUE';
      NO_DIR_CHECK='TRUE';
      ALLOW_CONNECT='TRUE';
    'VSS_AV29':
      PIN_NUMBER='(0,0,0,0,0,0,0,0,0,0,0,0,0,0,0,0,0,0,0,0,0,0,0,0,0,0,0,0,0,0,0~
,AV29,0,0,0,0,0,0,0,0)';
      PINUSE='POWER';
      NO_LOAD_CHECK='Both';
      NO_IO_CHECK='Both';
      NO_ASSERT_CHECK='TRUE';
      NO_DIR_CHECK='TRUE';
      ALLOW_CONNECT='TRUE';
    'VSS_AV31':
      PIN_NUMBER='(0,0,0,0,0,0,0,0,0,0,0,0,0,0,0,0,0,0,0,0,0,0,0,0,0,0,0,0,0,0,0~
,AV31,0,0,0,0,0,0,0,0)';
      PINUSE='POWER';
      NO_LOAD_CHECK='Both';
      NO_IO_CHECK='Both';
      NO_ASSERT_CHECK='TRUE';
      NO_DIR_CHECK='TRUE';
      ALLOW_CONNECT='TRUE';
    'VSS_AV33':
      PIN_NUMBER='(0,0,0,0,0,0,0,0,0,0,0,0,0,0,0,0,0,0,0,0,0,0,0,0,0,0,0,0,0,0,0~
,AV33,0,0,0,0,0,0,0,0)';
      PINUSE='POWER';
      NO_LOAD_CHECK='Both';
      NO_IO_CHECK='Both';
      NO_ASSERT_CHECK='TRUE';
      NO_DIR_CHECK='TRUE';
      ALLOW_CONNECT='TRUE';
    'VSS_AV35':
      PIN_NUMBER='(0,0,0,0,0,0,0,0,0,0,0,0,0,0,0,0,0,0,0,0,0,0,0,0,0,0,0,0,0,0,0~
,AV35,0,0,0,0,0,0,0,0)';
      PINUSE='POWER';
      NO_LOAD_CHECK='Both';
      NO_IO_CHECK='Both';
      NO_ASSERT_CHECK='TRUE';
      NO_DIR_CHECK='TRUE';
      ALLOW_CONNECT='TRUE';
    'VSS_AV37':
      PIN_NUMBER='(0,0,0,0,0,0,0,0,0,0,0,0,0,0,0,0,0,0,0,0,0,0,0,0,0,0,0,0,0,0,0~
,AV37,0,0,0,0,0,0,0,0)';
      PINUSE='POWER';
      NO_LOAD_CHECK='Both';
      NO_IO_CHECK='Both';
      NO_ASSERT_CHECK='TRUE';
      NO_DIR_CHECK='TRUE';
      ALLOW_CONNECT='TRUE';
    'VSS_AV40':
      PIN_NUMBER='(0,0,0,0,0,0,0,0,0,0,0,0,0,0,0,0,0,0,0,0,0,0,0,0,0,0,0,0,0,0,0~
,AV40,0,0,0,0,0,0,0,0)';
      PINUSE='POWER';
      NO_LOAD_CHECK='Both';
      NO_IO_CHECK='Both';
      NO_ASSERT_CHECK='TRUE';
      NO_DIR_CHECK='TRUE';
      ALLOW_CONNECT='TRUE';
    'VSS_AV42':
      PIN_NUMBER='(0,0,0,0,0,0,0,0,0,0,0,0,0,0,0,0,0,0,0,0,0,0,0,0,0,0,0,0,0,0,0~
,AV42,0,0,0,0,0,0,0,0)';
      PINUSE='POWER';
      NO_LOAD_CHECK='Both';
      NO_IO_CHECK='Both';
      NO_ASSERT_CHECK='TRUE';
      NO_DIR_CHECK='TRUE';
      ALLOW_CONNECT='TRUE';
    'VSS_AV44':
      PIN_NUMBER='(0,0,0,0,0,0,0,0,0,0,0,0,0,0,0,0,0,0,0,0,0,0,0,0,0,0,0,0,0,0,0~
,AV44,0,0,0,0,0,0,0,0)';
      PINUSE='POWER';
      NO_LOAD_CHECK='Both';
      NO_IO_CHECK='Both';
      NO_ASSERT_CHECK='TRUE';
      NO_DIR_CHECK='TRUE';
      ALLOW_CONNECT='TRUE';
    'VSS_AV46':
      PIN_NUMBER='(0,0,0,0,0,0,0,0,0,0,0,0,0,0,0,0,0,0,0,0,0,0,0,0,0,0,0,0,0,0,0~
,AV46,0,0,0,0,0,0,0,0)';
      PINUSE='POWER';
      NO_LOAD_CHECK='Both';
      NO_IO_CHECK='Both';
      NO_ASSERT_CHECK='TRUE';
      NO_DIR_CHECK='TRUE';
      ALLOW_CONNECT='TRUE';
    'VSS_AV48':
      PIN_NUMBER='(0,0,0,0,0,0,0,0,0,0,0,0,0,0,0,0,0,0,0,0,0,0,0,0,0,0,0,0,0,0,0~
,AV48,0,0,0,0,0,0,0,0)';
      PINUSE='POWER';
      NO_LOAD_CHECK='Both';
      NO_IO_CHECK='Both';
      NO_ASSERT_CHECK='TRUE';
      NO_DIR_CHECK='TRUE';
      ALLOW_CONNECT='TRUE';
    'VSS_AV50':
      PIN_NUMBER='(0,0,0,0,0,0,0,0,0,0,0,0,0,0,0,0,0,0,0,0,0,0,0,0,0,0,0,0,0,0,0~
,AV50,0,0,0,0,0,0,0,0)';
      PINUSE='POWER';
      NO_LOAD_CHECK='Both';
      NO_IO_CHECK='Both';
      NO_ASSERT_CHECK='TRUE';
      NO_DIR_CHECK='TRUE';
      ALLOW_CONNECT='TRUE';
    'VSS_AV52':
      PIN_NUMBER='(0,0,0,0,0,0,0,0,0,0,0,0,0,0,0,0,0,0,0,0,0,0,0,0,0,0,0,0,0,0,0~
,AV52,0,0,0,0,0,0,0,0)';
      PINUSE='POWER';
      NO_LOAD_CHECK='Both';
      NO_IO_CHECK='Both';
      NO_ASSERT_CHECK='TRUE';
      NO_DIR_CHECK='TRUE';
      ALLOW_CONNECT='TRUE';
    'VSS_AV54':
      PIN_NUMBER='(0,0,0,0,0,0,0,0,0,0,0,0,0,0,0,0,0,0,0,0,0,0,0,0,0,0,0,0,0,0,0~
,AV54,0,0,0,0,0,0,0,0)';
      PINUSE='POWER';
      NO_LOAD_CHECK='Both';
      NO_IO_CHECK='Both';
      NO_ASSERT_CHECK='TRUE';
      NO_DIR_CHECK='TRUE';
      ALLOW_CONNECT='TRUE';
    'VSS_AV59':
      PIN_NUMBER='(0,0,0,0,0,0,0,0,0,0,0,0,0,0,0,0,0,0,0,0,0,0,0,0,0,0,0,0,0,0,0~
,AV59,0,0,0,0,0,0,0,0)';
      PINUSE='POWER';
      NO_LOAD_CHECK='Both';
      NO_IO_CHECK='Both';
      NO_ASSERT_CHECK='TRUE';
      NO_DIR_CHECK='TRUE';
      ALLOW_CONNECT='TRUE';
    'VSS_AV61':
      PIN_NUMBER='(0,0,0,0,0,0,0,0,0,0,0,0,0,0,0,0,0,0,0,0,0,0,0,0,0,0,0,0,0,0,0~
,AV61,0,0,0,0,0,0,0,0)';
      PINUSE='POWER';
      NO_LOAD_CHECK='Both';
      NO_IO_CHECK='Both';
      NO_ASSERT_CHECK='TRUE';
      NO_DIR_CHECK='TRUE';
      ALLOW_CONNECT='TRUE';
    'VSS_AV66':
      PIN_NUMBER='(0,0,0,0,0,0,0,0,0,0,0,0,0,0,0,0,0,0,0,0,0,0,0,0,0,0,0,0,0,0,0~
,AV66,0,0,0,0,0,0,0,0)';
      PINUSE='POWER';
      NO_LOAD_CHECK='Both';
      NO_IO_CHECK='Both';
      NO_ASSERT_CHECK='TRUE';
      NO_DIR_CHECK='TRUE';
      ALLOW_CONNECT='TRUE';
    'VSS_AV68':
      PIN_NUMBER='(0,0,0,0,0,0,0,0,0,0,0,0,0,0,0,0,0,0,0,0,0,0,0,0,0,0,0,0,0,0,0~
,AV68,0,0,0,0,0,0,0,0)';
      PINUSE='POWER';
      NO_LOAD_CHECK='Both';
      NO_IO_CHECK='Both';
      NO_ASSERT_CHECK='TRUE';
      NO_DIR_CHECK='TRUE';
      ALLOW_CONNECT='TRUE';
    'VSS_AV73':
      PIN_NUMBER='(0,0,0,0,0,0,0,0,0,0,0,0,0,0,0,0,0,0,0,0,0,0,0,0,0,0,0,0,0,0,0~
,AV73,0,0,0,0,0,0,0,0)';
      PINUSE='POWER';
      NO_LOAD_CHECK='Both';
      NO_IO_CHECK='Both';
      NO_ASSERT_CHECK='TRUE';
      NO_DIR_CHECK='TRUE';
      ALLOW_CONNECT='TRUE';
    'VSS_AW1':
      PIN_NUMBER='(0,0,0,0,0,0,0,0,0,0,0,0,0,0,0,0,0,0,0,0,0,0,0,0,0,0,0,0,0,0,0~
,AW1,0,0,0,0,0,0,0,0)';
      PINUSE='POWER';
      NO_LOAD_CHECK='Both';
      NO_IO_CHECK='Both';
      NO_ASSERT_CHECK='TRUE';
      NO_DIR_CHECK='TRUE';
      ALLOW_CONNECT='TRUE';
    'VSS_AW4':
      PIN_NUMBER='(0,0,0,0,0,0,0,0,0,0,0,0,0,0,0,0,0,0,0,0,0,0,0,0,0,0,0,0,0,0,0~
,AW4,0,0,0,0,0,0,0,0)';
      PINUSE='POWER';
      NO_LOAD_CHECK='Both';
      NO_IO_CHECK='Both';
      NO_ASSERT_CHECK='TRUE';
      NO_DIR_CHECK='TRUE';
      ALLOW_CONNECT='TRUE';
    'VSS_AW6':
      PIN_NUMBER='(0,0,0,0,0,0,0,0,0,0,0,0,0,0,0,0,0,0,0,0,0,0,0,0,0,0,0,0,0,0,0~
,AW6,0,0,0,0,0,0,0,0)';
      PINUSE='POWER';
      NO_LOAD_CHECK='Both';
      NO_IO_CHECK='Both';
      NO_ASSERT_CHECK='TRUE';
      NO_DIR_CHECK='TRUE';
      ALLOW_CONNECT='TRUE';
    'VSS_AW8':
      PIN_NUMBER='(0,0,0,0,0,0,0,0,0,0,0,0,0,0,0,0,0,0,0,0,0,0,0,0,0,0,0,0,0,0,0~
,AW8,0,0,0,0,0,0,0,0)';
      PINUSE='POWER';
      NO_LOAD_CHECK='Both';
      NO_IO_CHECK='Both';
      NO_ASSERT_CHECK='TRUE';
      NO_DIR_CHECK='TRUE';
      ALLOW_CONNECT='TRUE';
    'VSS_AW11':
      PIN_NUMBER='(0,0,0,0,0,0,0,0,0,0,0,0,0,0,0,0,0,0,0,0,0,0,0,0,0,0,0,0,0,0,0~
,AW11,0,0,0,0,0,0,0,0)';
      PINUSE='POWER';
      NO_LOAD_CHECK='Both';
      NO_IO_CHECK='Both';
      NO_ASSERT_CHECK='TRUE';
      NO_DIR_CHECK='TRUE';
      ALLOW_CONNECT='TRUE';
    'VSS_AW13':
      PIN_NUMBER='(0,0,0,0,0,0,0,0,0,0,0,0,0,0,0,0,0,0,0,0,0,0,0,0,0,0,0,0,0,0,0~
,AW13,0,0,0,0,0,0,0,0)';
      PINUSE='POWER';
      NO_LOAD_CHECK='Both';
      NO_IO_CHECK='Both';
      NO_ASSERT_CHECK='TRUE';
      NO_DIR_CHECK='TRUE';
      ALLOW_CONNECT='TRUE';
    'VSS_AW15':
      PIN_NUMBER='(0,0,0,0,0,0,0,0,0,0,0,0,0,0,0,0,0,0,0,0,0,0,0,0,0,0,0,0,0,0,0~
,AW15,0,0,0,0,0,0,0,0)';
      PINUSE='POWER';
      NO_LOAD_CHECK='Both';
      NO_IO_CHECK='Both';
      NO_ASSERT_CHECK='TRUE';
      NO_DIR_CHECK='TRUE';
      ALLOW_CONNECT='TRUE';
    'VSS_AW18':
      PIN_NUMBER='(0,0,0,0,0,0,0,0,0,0,0,0,0,0,0,0,0,0,0,0,0,0,0,0,0,0,0,0,0,0,0~
,AW18,0,0,0,0,0,0,0,0)';
      PINUSE='POWER';
      NO_LOAD_CHECK='Both';
      NO_IO_CHECK='Both';
      NO_ASSERT_CHECK='TRUE';
      NO_DIR_CHECK='TRUE';
      ALLOW_CONNECT='TRUE';
    'VSS_AW20':
      PIN_NUMBER='(0,0,0,0,0,0,0,0,0,0,0,0,0,0,0,0,0,0,0,0,0,0,0,0,0,0,0,0,0,0,0~
,AW20,0,0,0,0,0,0,0,0)';
      PINUSE='POWER';
      NO_LOAD_CHECK='Both';
      NO_IO_CHECK='Both';
      NO_ASSERT_CHECK='TRUE';
      NO_DIR_CHECK='TRUE';
      ALLOW_CONNECT='TRUE';
    'VSS_AW22':
      PIN_NUMBER='(0,0,0,0,0,0,0,0,0,0,0,0,0,0,0,0,0,0,0,0,0,0,0,0,0,0,0,0,0,0,0~
,AW22,0,0,0,0,0,0,0,0)';
      PINUSE='POWER';
      NO_LOAD_CHECK='Both';
      NO_IO_CHECK='Both';
      NO_ASSERT_CHECK='TRUE';
      NO_DIR_CHECK='TRUE';
      ALLOW_CONNECT='TRUE';
    'VSS_AW24':
      PIN_NUMBER='(0,0,0,0,0,0,0,0,0,0,0,0,0,0,0,0,0,0,0,0,0,0,0,0,0,0,0,0,0,0,0~
,AW24,0,0,0,0,0,0,0,0)';
      PINUSE='POWER';
      NO_LOAD_CHECK='Both';
      NO_IO_CHECK='Both';
      NO_ASSERT_CHECK='TRUE';
      NO_DIR_CHECK='TRUE';
      ALLOW_CONNECT='TRUE';
    'VSS_AW26':
      PIN_NUMBER='(0,0,0,0,0,0,0,0,0,0,0,0,0,0,0,0,0,0,0,0,0,0,0,0,0,0,0,0,0,0,0~
,AW26,0,0,0,0,0,0,0,0)';
      PINUSE='POWER';
      NO_LOAD_CHECK='Both';
      NO_IO_CHECK='Both';
      NO_ASSERT_CHECK='TRUE';
      NO_DIR_CHECK='TRUE';
      ALLOW_CONNECT='TRUE';
    'VSS_AW28':
      PIN_NUMBER='(0,0,0,0,0,0,0,0,0,0,0,0,0,0,0,0,0,0,0,0,0,0,0,0,0,0,0,0,0,0,0~
,AW28,0,0,0,0,0,0,0,0)';
      PINUSE='POWER';
      NO_LOAD_CHECK='Both';
      NO_IO_CHECK='Both';
      NO_ASSERT_CHECK='TRUE';
      NO_DIR_CHECK='TRUE';
      ALLOW_CONNECT='TRUE';
    'VSS_AW49':
      PIN_NUMBER='(0,0,0,0,0,0,0,0,0,0,0,0,0,0,0,0,0,0,0,0,0,0,0,0,0,0,0,0,0,0,0~
,AW49,0,0,0,0,0,0,0,0)';
      PINUSE='POWER';
      NO_LOAD_CHECK='Both';
      NO_IO_CHECK='Both';
      NO_ASSERT_CHECK='TRUE';
      NO_DIR_CHECK='TRUE';
      ALLOW_CONNECT='TRUE';
    'VSS_AW51':
      PIN_NUMBER='(0,0,0,0,0,0,0,0,0,0,0,0,0,0,0,0,0,0,0,0,0,0,0,0,0,0,0,0,0,0,0~
,AW51,0,0,0,0,0,0,0,0)';
      PINUSE='POWER';
      NO_LOAD_CHECK='Both';
      NO_IO_CHECK='Both';
      NO_ASSERT_CHECK='TRUE';
      NO_DIR_CHECK='TRUE';
      ALLOW_CONNECT='TRUE';
    'VSS_AW53':
      PIN_NUMBER='(0,0,0,0,0,0,0,0,0,0,0,0,0,0,0,0,0,0,0,0,0,0,0,0,0,0,0,0,0,0,0~
,AW53,0,0,0,0,0,0,0,0)';
      PINUSE='POWER';
      NO_LOAD_CHECK='Both';
      NO_IO_CHECK='Both';
      NO_ASSERT_CHECK='TRUE';
      NO_DIR_CHECK='TRUE';
      ALLOW_CONNECT='TRUE';
    'VSS_AW56':
      PIN_NUMBER='(0,0,0,0,0,0,0,0,0,0,0,0,0,0,0,0,0,0,0,0,0,0,0,0,0,0,0,0,0,0,0~
,AW56,0,0,0,0,0,0,0,0)';
      PINUSE='POWER';
      NO_LOAD_CHECK='Both';
      NO_IO_CHECK='Both';
      NO_ASSERT_CHECK='TRUE';
      NO_DIR_CHECK='TRUE';
      ALLOW_CONNECT='TRUE';
    'VSS_AW58':
      PIN_NUMBER='(0,0,0,0,0,0,0,0,0,0,0,0,0,0,0,0,0,0,0,0,0,0,0,0,0,0,0,0,0,0,0~
,AW58,0,0,0,0,0,0,0,0)';
      PINUSE='POWER';
      NO_LOAD_CHECK='Both';
      NO_IO_CHECK='Both';
      NO_ASSERT_CHECK='TRUE';
      NO_DIR_CHECK='TRUE';
      ALLOW_CONNECT='TRUE';
    'VSS_AW61':
      PIN_NUMBER='(0,0,0,0,0,0,0,0,0,0,0,0,0,0,0,0,0,0,0,0,0,0,0,0,0,0,0,0,0,0,0~
,AW61,0,0,0,0,0,0,0,0)';
      PINUSE='POWER';
      NO_LOAD_CHECK='Both';
      NO_IO_CHECK='Both';
      NO_ASSERT_CHECK='TRUE';
      NO_DIR_CHECK='TRUE';
      ALLOW_CONNECT='TRUE';
    'VSS_AW63':
      PIN_NUMBER='(0,0,0,0,0,0,0,0,0,0,0,0,0,0,0,0,0,0,0,0,0,0,0,0,0,0,0,0,0,0,0~
,0,AW63,0,0,0,0,0,0,0)';
      PINUSE='POWER';
      NO_LOAD_CHECK='Both';
      NO_IO_CHECK='Both';
      NO_ASSERT_CHECK='TRUE';
      NO_DIR_CHECK='TRUE';
      ALLOW_CONNECT='TRUE';
    'VSS_AW65':
      PIN_NUMBER='(0,0,0,0,0,0,0,0,0,0,0,0,0,0,0,0,0,0,0,0,0,0,0,0,0,0,0,0,0,0,0~
,0,AW65,0,0,0,0,0,0,0)';
      PINUSE='POWER';
      NO_LOAD_CHECK='Both';
      NO_IO_CHECK='Both';
      NO_ASSERT_CHECK='TRUE';
      NO_DIR_CHECK='TRUE';
      ALLOW_CONNECT='TRUE';
    'VSS_AW68':
      PIN_NUMBER='(0,0,0,0,0,0,0,0,0,0,0,0,0,0,0,0,0,0,0,0,0,0,0,0,0,0,0,0,0,0,0~
,0,AW68,0,0,0,0,0,0,0)';
      PINUSE='POWER';
      NO_LOAD_CHECK='Both';
      NO_IO_CHECK='Both';
      NO_ASSERT_CHECK='TRUE';
      NO_DIR_CHECK='TRUE';
      ALLOW_CONNECT='TRUE';
    'VSS_AW70':
      PIN_NUMBER='(0,0,0,0,0,0,0,0,0,0,0,0,0,0,0,0,0,0,0,0,0,0,0,0,0,0,0,0,0,0,0~
,0,AW70,0,0,0,0,0,0,0)';
      PINUSE='POWER';
      NO_LOAD_CHECK='Both';
      NO_IO_CHECK='Both';
      NO_ASSERT_CHECK='TRUE';
      NO_DIR_CHECK='TRUE';
      ALLOW_CONNECT='TRUE';
    'VSS_AW72':
      PIN_NUMBER='(0,0,0,0,0,0,0,0,0,0,0,0,0,0,0,0,0,0,0,0,0,0,0,0,0,0,0,0,0,0,0~
,0,AW72,0,0,0,0,0,0,0)';
      PINUSE='POWER';
      NO_LOAD_CHECK='Both';
      NO_IO_CHECK='Both';
      NO_ASSERT_CHECK='TRUE';
      NO_DIR_CHECK='TRUE';
      ALLOW_CONNECT='TRUE';
    'VSS_AW75':
      PIN_NUMBER='(0,0,0,0,0,0,0,0,0,0,0,0,0,0,0,0,0,0,0,0,0,0,0,0,0,0,0,0,0,0,0~
,0,AW75,0,0,0,0,0,0,0)';
      PINUSE='POWER';
      NO_LOAD_CHECK='Both';
      NO_IO_CHECK='Both';
      NO_ASSERT_CHECK='TRUE';
      NO_DIR_CHECK='TRUE';
      ALLOW_CONNECT='TRUE';
    'VSS_AY3':
      PIN_NUMBER='(0,0,0,0,0,0,0,0,0,0,0,0,0,0,0,0,0,0,0,0,0,0,0,0,0,0,0,0,0,0,0~
,0,AY3,0,0,0,0,0,0,0)';
      PINUSE='POWER';
      NO_LOAD_CHECK='Both';
      NO_IO_CHECK='Both';
      NO_ASSERT_CHECK='TRUE';
      NO_DIR_CHECK='TRUE';
      ALLOW_CONNECT='TRUE';
    'VSS_AY5':
      PIN_NUMBER='(0,0,0,0,0,0,0,0,0,0,0,0,0,0,0,0,0,0,0,0,0,0,0,0,0,0,0,0,0,0,0~
,0,AY5,0,0,0,0,0,0,0)';
      PINUSE='POWER';
      NO_LOAD_CHECK='Both';
      NO_IO_CHECK='Both';
      NO_ASSERT_CHECK='TRUE';
      NO_DIR_CHECK='TRUE';
      ALLOW_CONNECT='TRUE';
    'VSS_AY8':
      PIN_NUMBER='(0,0,0,0,0,0,0,0,0,0,0,0,0,0,0,0,0,0,0,0,0,0,0,0,0,0,0,0,0,0,0~
,0,AY8,0,0,0,0,0,0,0)';
      PINUSE='POWER';
      NO_LOAD_CHECK='Both';
      NO_IO_CHECK='Both';
      NO_ASSERT_CHECK='TRUE';
      NO_DIR_CHECK='TRUE';
      ALLOW_CONNECT='TRUE';
    'VSS_AY10':
      PIN_NUMBER='(0,0,0,0,0,0,0,0,0,0,0,0,0,0,0,0,0,0,0,0,0,0,0,0,0,0,0,0,0,0,0~
,0,AY10,0,0,0,0,0,0,0)';
      PINUSE='POWER';
      NO_LOAD_CHECK='Both';
      NO_IO_CHECK='Both';
      NO_ASSERT_CHECK='TRUE';
      NO_DIR_CHECK='TRUE';
      ALLOW_CONNECT='TRUE';
    'VSS_AY12':
      PIN_NUMBER='(0,0,0,0,0,0,0,0,0,0,0,0,0,0,0,0,0,0,0,0,0,0,0,0,0,0,0,0,0,0,0~
,0,AY12,0,0,0,0,0,0,0)';
      PINUSE='POWER';
      NO_LOAD_CHECK='Both';
      NO_IO_CHECK='Both';
      NO_ASSERT_CHECK='TRUE';
      NO_DIR_CHECK='TRUE';
      ALLOW_CONNECT='TRUE';
    'VSS_AY15':
      PIN_NUMBER='(0,0,0,0,0,0,0,0,0,0,0,0,0,0,0,0,0,0,0,0,0,0,0,0,0,0,0,0,0,0,0~
,0,AY15,0,0,0,0,0,0,0)';
      PINUSE='POWER';
      NO_LOAD_CHECK='Both';
      NO_IO_CHECK='Both';
      NO_ASSERT_CHECK='TRUE';
      NO_DIR_CHECK='TRUE';
      ALLOW_CONNECT='TRUE';
    'VSS_AY17':
      PIN_NUMBER='(0,0,0,0,0,0,0,0,0,0,0,0,0,0,0,0,0,0,0,0,0,0,0,0,0,0,0,0,0,0,0~
,0,AY17,0,0,0,0,0,0,0)';
      PINUSE='POWER';
      NO_LOAD_CHECK='Both';
      NO_IO_CHECK='Both';
      NO_ASSERT_CHECK='TRUE';
      NO_DIR_CHECK='TRUE';
      ALLOW_CONNECT='TRUE';
    'VSS_AY19':
      PIN_NUMBER='(0,0,0,0,0,0,0,0,0,0,0,0,0,0,0,0,0,0,0,0,0,0,0,0,0,0,0,0,0,0,0~
,0,AY19,0,0,0,0,0,0,0)';
      PINUSE='POWER';
      NO_LOAD_CHECK='Both';
      NO_IO_CHECK='Both';
      NO_ASSERT_CHECK='TRUE';
      NO_DIR_CHECK='TRUE';
      ALLOW_CONNECT='TRUE';
    'VSS_AY23':
      PIN_NUMBER='(0,0,0,0,0,0,0,0,0,0,0,0,0,0,0,0,0,0,0,0,0,0,0,0,0,0,0,0,0,0,0~
,0,AY23,0,0,0,0,0,0,0)';
      PINUSE='POWER';
      NO_LOAD_CHECK='Both';
      NO_IO_CHECK='Both';
      NO_ASSERT_CHECK='TRUE';
      NO_DIR_CHECK='TRUE';
      ALLOW_CONNECT='TRUE';
    'VSS_AY25':
      PIN_NUMBER='(0,0,0,0,0,0,0,0,0,0,0,0,0,0,0,0,0,0,0,0,0,0,0,0,0,0,0,0,0,0,0~
,0,AY25,0,0,0,0,0,0,0)';
      PINUSE='POWER';
      NO_LOAD_CHECK='Both';
      NO_IO_CHECK='Both';
      NO_ASSERT_CHECK='TRUE';
      NO_DIR_CHECK='TRUE';
      ALLOW_CONNECT='TRUE';
    'VSS_AY27':
      PIN_NUMBER='(0,0,0,0,0,0,0,0,0,0,0,0,0,0,0,0,0,0,0,0,0,0,0,0,0,0,0,0,0,0,0~
,0,AY27,0,0,0,0,0,0,0)';
      PINUSE='POWER';
      NO_LOAD_CHECK='Both';
      NO_IO_CHECK='Both';
      NO_ASSERT_CHECK='TRUE';
      NO_DIR_CHECK='TRUE';
      ALLOW_CONNECT='TRUE';
    'VSS_AY48':
      PIN_NUMBER='(0,0,0,0,0,0,0,0,0,0,0,0,0,0,0,0,0,0,0,0,0,0,0,0,0,0,0,0,0,0,0~
,0,AY48,0,0,0,0,0,0,0)';
      PINUSE='POWER';
      NO_LOAD_CHECK='Both';
      NO_IO_CHECK='Both';
      NO_ASSERT_CHECK='TRUE';
      NO_DIR_CHECK='TRUE';
      ALLOW_CONNECT='TRUE';
    'VSS_AY50':
      PIN_NUMBER='(0,0,0,0,0,0,0,0,0,0,0,0,0,0,0,0,0,0,0,0,0,0,0,0,0,0,0,0,0,0,0~
,0,AY50,0,0,0,0,0,0,0)';
      PINUSE='POWER';
      NO_LOAD_CHECK='Both';
      NO_IO_CHECK='Both';
      NO_ASSERT_CHECK='TRUE';
      NO_DIR_CHECK='TRUE';
      ALLOW_CONNECT='TRUE';
    'VSS_AY52':
      PIN_NUMBER='(0,0,0,0,0,0,0,0,0,0,0,0,0,0,0,0,0,0,0,0,0,0,0,0,0,0,0,0,0,0,0~
,0,AY52,0,0,0,0,0,0,0)';
      PINUSE='POWER';
      NO_LOAD_CHECK='Both';
      NO_IO_CHECK='Both';
      NO_ASSERT_CHECK='TRUE';
      NO_DIR_CHECK='TRUE';
      ALLOW_CONNECT='TRUE';
    'VSS_AY54':
      PIN_NUMBER='(0,0,0,0,0,0,0,0,0,0,0,0,0,0,0,0,0,0,0,0,0,0,0,0,0,0,0,0,0,0,0~
,0,AY54,0,0,0,0,0,0,0)';
      PINUSE='POWER';
      NO_LOAD_CHECK='Both';
      NO_IO_CHECK='Both';
      NO_ASSERT_CHECK='TRUE';
      NO_DIR_CHECK='TRUE';
      ALLOW_CONNECT='TRUE';
    'VSS_AY57':
      PIN_NUMBER='(0,0,0,0,0,0,0,0,0,0,0,0,0,0,0,0,0,0,0,0,0,0,0,0,0,0,0,0,0,0,0~
,0,AY57,0,0,0,0,0,0,0)';
      PINUSE='POWER';
      NO_LOAD_CHECK='Both';
      NO_IO_CHECK='Both';
      NO_ASSERT_CHECK='TRUE';
      NO_DIR_CHECK='TRUE';
      ALLOW_CONNECT='TRUE';
    'VSS_AY59':
      PIN_NUMBER='(0,0,0,0,0,0,0,0,0,0,0,0,0,0,0,0,0,0,0,0,0,0,0,0,0,0,0,0,0,0,0~
,0,AY59,0,0,0,0,0,0,0)';
      PINUSE='POWER';
      NO_LOAD_CHECK='Both';
      NO_IO_CHECK='Both';
      NO_ASSERT_CHECK='TRUE';
      NO_DIR_CHECK='TRUE';
      ALLOW_CONNECT='TRUE';
    'VSS_AY61':
      PIN_NUMBER='(0,0,0,0,0,0,0,0,0,0,0,0,0,0,0,0,0,0,0,0,0,0,0,0,0,0,0,0,0,0,0~
,0,AY61,0,0,0,0,0,0,0)';
      PINUSE='POWER';
      NO_LOAD_CHECK='Both';
      NO_IO_CHECK='Both';
      NO_ASSERT_CHECK='TRUE';
      NO_DIR_CHECK='TRUE';
      ALLOW_CONNECT='TRUE';
    'VSS_AY64':
      PIN_NUMBER='(0,0,0,0,0,0,0,0,0,0,0,0,0,0,0,0,0,0,0,0,0,0,0,0,0,0,0,0,0,0,0~
,0,AY64,0,0,0,0,0,0,0)';
      PINUSE='POWER';
      NO_LOAD_CHECK='Both';
      NO_IO_CHECK='Both';
      NO_ASSERT_CHECK='TRUE';
      NO_DIR_CHECK='TRUE';
      ALLOW_CONNECT='TRUE';
    'VSS_AY66':
      PIN_NUMBER='(0,0,0,0,0,0,0,0,0,0,0,0,0,0,0,0,0,0,0,0,0,0,0,0,0,0,0,0,0,0,0~
,0,AY66,0,0,0,0,0,0,0)';
      PINUSE='POWER';
      NO_LOAD_CHECK='Both';
      NO_IO_CHECK='Both';
      NO_ASSERT_CHECK='TRUE';
      NO_DIR_CHECK='TRUE';
      ALLOW_CONNECT='TRUE';
    'VSS_AY68':
      PIN_NUMBER='(0,0,0,0,0,0,0,0,0,0,0,0,0,0,0,0,0,0,0,0,0,0,0,0,0,0,0,0,0,0,0~
,0,AY68,0,0,0,0,0,0,0)';
      PINUSE='POWER';
      NO_LOAD_CHECK='Both';
      NO_IO_CHECK='Both';
      NO_ASSERT_CHECK='TRUE';
      NO_DIR_CHECK='TRUE';
      ALLOW_CONNECT='TRUE';
    'VSS_AY71':
      PIN_NUMBER='(0,0,0,0,0,0,0,0,0,0,0,0,0,0,0,0,0,0,0,0,0,0,0,0,0,0,0,0,0,0,0~
,0,AY71,0,0,0,0,0,0,0)';
      PINUSE='POWER';
      NO_LOAD_CHECK='Both';
      NO_IO_CHECK='Both';
      NO_ASSERT_CHECK='TRUE';
      NO_DIR_CHECK='TRUE';
      ALLOW_CONNECT='TRUE';
    'VSS_AY73':
      PIN_NUMBER='(0,0,0,0,0,0,0,0,0,0,0,0,0,0,0,0,0,0,0,0,0,0,0,0,0,0,0,0,0,0,0~
,0,AY73,0,0,0,0,0,0,0)';
      PINUSE='POWER';
      NO_LOAD_CHECK='Both';
      NO_IO_CHECK='Both';
      NO_ASSERT_CHECK='TRUE';
      NO_DIR_CHECK='TRUE';
      ALLOW_CONNECT='TRUE';
    'VSS_BA1':
      PIN_NUMBER='(0,0,0,0,0,0,0,0,0,0,0,0,0,0,0,0,0,0,0,0,0,0,0,0,0,0,0,0,0,0,0~
,0,BA1,0,0,0,0,0,0,0)';
      PINUSE='POWER';
      NO_LOAD_CHECK='Both';
      NO_IO_CHECK='Both';
      NO_ASSERT_CHECK='TRUE';
      NO_DIR_CHECK='TRUE';
      ALLOW_CONNECT='TRUE';
    'VSS_BA6':
      PIN_NUMBER='(0,0,0,0,0,0,0,0,0,0,0,0,0,0,0,0,0,0,0,0,0,0,0,0,0,0,0,0,0,0,0~
,0,BA6,0,0,0,0,0,0,0)';
      PINUSE='POWER';
      NO_LOAD_CHECK='Both';
      NO_IO_CHECK='Both';
      NO_ASSERT_CHECK='TRUE';
      NO_DIR_CHECK='TRUE';
      ALLOW_CONNECT='TRUE';
    'VSS_BA8':
      PIN_NUMBER='(0,0,0,0,0,0,0,0,0,0,0,0,0,0,0,0,0,0,0,0,0,0,0,0,0,0,0,0,0,0,0~
,0,BA8,0,0,0,0,0,0,0)';
      PINUSE='POWER';
      NO_LOAD_CHECK='Both';
      NO_IO_CHECK='Both';
      NO_ASSERT_CHECK='TRUE';
      NO_DIR_CHECK='TRUE';
      ALLOW_CONNECT='TRUE';
    'VSS_BA13':
      PIN_NUMBER='(0,0,0,0,0,0,0,0,0,0,0,0,0,0,0,0,0,0,0,0,0,0,0,0,0,0,0,0,0,0,0~
,0,BA13,0,0,0,0,0,0,0)';
      PINUSE='POWER';
      NO_LOAD_CHECK='Both';
      NO_IO_CHECK='Both';
      NO_ASSERT_CHECK='TRUE';
      NO_DIR_CHECK='TRUE';
      ALLOW_CONNECT='TRUE';
    'VSS_BA15':
      PIN_NUMBER='(0,0,0,0,0,0,0,0,0,0,0,0,0,0,0,0,0,0,0,0,0,0,0,0,0,0,0,0,0,0,0~
,0,BA15,0,0,0,0,0,0,0)';
      PINUSE='POWER';
      NO_LOAD_CHECK='Both';
      NO_IO_CHECK='Both';
      NO_ASSERT_CHECK='TRUE';
      NO_DIR_CHECK='TRUE';
      ALLOW_CONNECT='TRUE';
    'VSS_BA20':
      PIN_NUMBER='(0,0,0,0,0,0,0,0,0,0,0,0,0,0,0,0,0,0,0,0,0,0,0,0,0,0,0,0,0,0,0~
,0,BA20,0,0,0,0,0,0,0)';
      PINUSE='POWER';
      NO_LOAD_CHECK='Both';
      NO_IO_CHECK='Both';
      NO_ASSERT_CHECK='TRUE';
      NO_DIR_CHECK='TRUE';
      ALLOW_CONNECT='TRUE';
    'VSS_BA22':
      PIN_NUMBER='(0,0,0,0,0,0,0,0,0,0,0,0,0,0,0,0,0,0,0,0,0,0,0,0,0,0,0,0,0,0,0~
,0,BA22,0,0,0,0,0,0,0)';
      PINUSE='POWER';
      NO_LOAD_CHECK='Both';
      NO_IO_CHECK='Both';
      NO_ASSERT_CHECK='TRUE';
      NO_DIR_CHECK='TRUE';
      ALLOW_CONNECT='TRUE';
    'VSS_BA24':
      PIN_NUMBER='(0,0,0,0,0,0,0,0,0,0,0,0,0,0,0,0,0,0,0,0,0,0,0,0,0,0,0,0,0,0,0~
,0,BA24,0,0,0,0,0,0,0)';
      PINUSE='POWER';
      NO_LOAD_CHECK='Both';
      NO_IO_CHECK='Both';
      NO_ASSERT_CHECK='TRUE';
      NO_DIR_CHECK='TRUE';
      ALLOW_CONNECT='TRUE';
    'VSS_BA26':
      PIN_NUMBER='(0,0,0,0,0,0,0,0,0,0,0,0,0,0,0,0,0,0,0,0,0,0,0,0,0,0,0,0,0,0,0~
,0,BA26,0,0,0,0,0,0,0)';
      PINUSE='POWER';
      NO_LOAD_CHECK='Both';
      NO_IO_CHECK='Both';
      NO_ASSERT_CHECK='TRUE';
      NO_DIR_CHECK='TRUE';
      ALLOW_CONNECT='TRUE';
    'VSS_BA28':
      PIN_NUMBER='(0,0,0,0,0,0,0,0,0,0,0,0,0,0,0,0,0,0,0,0,0,0,0,0,0,0,0,0,0,0,0~
,0,BA28,0,0,0,0,0,0,0)';
      PINUSE='POWER';
      NO_LOAD_CHECK='Both';
      NO_IO_CHECK='Both';
      NO_ASSERT_CHECK='TRUE';
      NO_DIR_CHECK='TRUE';
      ALLOW_CONNECT='TRUE';
    'VSS_BA49':
      PIN_NUMBER='(0,0,0,0,0,0,0,0,0,0,0,0,0,0,0,0,0,0,0,0,0,0,0,0,0,0,0,0,0,0,0~
,0,BA49,0,0,0,0,0,0,0)';
      PINUSE='POWER';
      NO_LOAD_CHECK='Both';
      NO_IO_CHECK='Both';
      NO_ASSERT_CHECK='TRUE';
      NO_DIR_CHECK='TRUE';
      ALLOW_CONNECT='TRUE';
    'VSS_BA51':
      PIN_NUMBER='(0,0,0,0,0,0,0,0,0,0,0,0,0,0,0,0,0,0,0,0,0,0,0,0,0,0,0,0,0,0,0~
,0,BA51,0,0,0,0,0,0,0)';
      PINUSE='POWER';
      NO_LOAD_CHECK='Both';
      NO_IO_CHECK='Both';
      NO_ASSERT_CHECK='TRUE';
      NO_DIR_CHECK='TRUE';
      ALLOW_CONNECT='TRUE';
    'VSS_BA53':
      PIN_NUMBER='(0,0,0,0,0,0,0,0,0,0,0,0,0,0,0,0,0,0,0,0,0,0,0,0,0,0,0,0,0,0,0~
,0,BA53,0,0,0,0,0,0,0)';
      PINUSE='POWER';
      NO_LOAD_CHECK='Both';
      NO_IO_CHECK='Both';
      NO_ASSERT_CHECK='TRUE';
      NO_DIR_CHECK='TRUE';
      ALLOW_CONNECT='TRUE';
    'VSS_BA56':
      PIN_NUMBER='(0,0,0,0,0,0,0,0,0,0,0,0,0,0,0,0,0,0,0,0,0,0,0,0,0,0,0,0,0,0,0~
,0,BA56,0,0,0,0,0,0,0)';
      PINUSE='POWER';
      NO_LOAD_CHECK='Both';
      NO_IO_CHECK='Both';
      NO_ASSERT_CHECK='TRUE';
      NO_DIR_CHECK='TRUE';
      ALLOW_CONNECT='TRUE';
    'VSS_BA61':
      PIN_NUMBER='(0,0,0,0,0,0,0,0,0,0,0,0,0,0,0,0,0,0,0,0,0,0,0,0,0,0,0,0,0,0,0~
,0,BA61,0,0,0,0,0,0,0)';
      PINUSE='POWER';
      NO_LOAD_CHECK='Both';
      NO_IO_CHECK='Both';
      NO_ASSERT_CHECK='TRUE';
      NO_DIR_CHECK='TRUE';
      ALLOW_CONNECT='TRUE';
    'VSS_BA63':
      PIN_NUMBER='(0,0,0,0,0,0,0,0,0,0,0,0,0,0,0,0,0,0,0,0,0,0,0,0,0,0,0,0,0,0,0~
,0,BA63,0,0,0,0,0,0,0)';
      PINUSE='POWER';
      NO_LOAD_CHECK='Both';
      NO_IO_CHECK='Both';
      NO_ASSERT_CHECK='TRUE';
      NO_DIR_CHECK='TRUE';
      ALLOW_CONNECT='TRUE';
    'VSS_BA68':
      PIN_NUMBER='(0,0,0,0,0,0,0,0,0,0,0,0,0,0,0,0,0,0,0,0,0,0,0,0,0,0,0,0,0,0,0~
,0,BA68,0,0,0,0,0,0,0)';
      PINUSE='POWER';
      NO_LOAD_CHECK='Both';
      NO_IO_CHECK='Both';
      NO_ASSERT_CHECK='TRUE';
      NO_DIR_CHECK='TRUE';
      ALLOW_CONNECT='TRUE';
    'VSS_BA70':
      PIN_NUMBER='(0,0,0,0,0,0,0,0,0,0,0,0,0,0,0,0,0,0,0,0,0,0,0,0,0,0,0,0,0,0,0~
,0,BA70,0,0,0,0,0,0,0)';
      PINUSE='POWER';
      NO_LOAD_CHECK='Both';
      NO_IO_CHECK='Both';
      NO_ASSERT_CHECK='TRUE';
      NO_DIR_CHECK='TRUE';
      ALLOW_CONNECT='TRUE';
    'VSS_BA75':
      PIN_NUMBER='(0,0,0,0,0,0,0,0,0,0,0,0,0,0,0,0,0,0,0,0,0,0,0,0,0,0,0,0,0,0,0~
,0,BA75,0,0,0,0,0,0,0)';
      PINUSE='POWER';
      NO_LOAD_CHECK='Both';
      NO_IO_CHECK='Both';
      NO_ASSERT_CHECK='TRUE';
      NO_DIR_CHECK='TRUE';
      ALLOW_CONNECT='TRUE';
    'VSS_BB3':
      PIN_NUMBER='(0,0,0,0,0,0,0,0,0,0,0,0,0,0,0,0,0,0,0,0,0,0,0,0,0,0,0,0,0,0,0~
,0,BB3,0,0,0,0,0,0,0)';
      PINUSE='POWER';
      NO_LOAD_CHECK='Both';
      NO_IO_CHECK='Both';
      NO_ASSERT_CHECK='TRUE';
      NO_DIR_CHECK='TRUE';
      ALLOW_CONNECT='TRUE';
    'VSS_BB5':
      PIN_NUMBER='(0,0,0,0,0,0,0,0,0,0,0,0,0,0,0,0,0,0,0,0,0,0,0,0,0,0,0,0,0,0,0~
,0,BB5,0,0,0,0,0,0,0)';
      PINUSE='POWER';
      NO_LOAD_CHECK='Both';
      NO_IO_CHECK='Both';
      NO_ASSERT_CHECK='TRUE';
      NO_DIR_CHECK='TRUE';
      ALLOW_CONNECT='TRUE';
    'VSS_BB8':
      PIN_NUMBER='(0,0,0,0,0,0,0,0,0,0,0,0,0,0,0,0,0,0,0,0,0,0,0,0,0,0,0,0,0,0,0~
,0,BB8,0,0,0,0,0,0,0)';
      PINUSE='POWER';
      NO_LOAD_CHECK='Both';
      NO_IO_CHECK='Both';
      NO_ASSERT_CHECK='TRUE';
      NO_DIR_CHECK='TRUE';
      ALLOW_CONNECT='TRUE';
    'VSS_BB10':
      PIN_NUMBER='(0,0,0,0,0,0,0,0,0,0,0,0,0,0,0,0,0,0,0,0,0,0,0,0,0,0,0,0,0,0,0~
,0,BB10,0,0,0,0,0,0,0)';
      PINUSE='POWER';
      NO_LOAD_CHECK='Both';
      NO_IO_CHECK='Both';
      NO_ASSERT_CHECK='TRUE';
      NO_DIR_CHECK='TRUE';
      ALLOW_CONNECT='TRUE';
    'VSS_BB12':
      PIN_NUMBER='(0,0,0,0,0,0,0,0,0,0,0,0,0,0,0,0,0,0,0,0,0,0,0,0,0,0,0,0,0,0,0~
,0,BB12,0,0,0,0,0,0,0)';
      PINUSE='POWER';
      NO_LOAD_CHECK='Both';
      NO_IO_CHECK='Both';
      NO_ASSERT_CHECK='TRUE';
      NO_DIR_CHECK='TRUE';
      ALLOW_CONNECT='TRUE';
    'VSS_BB15':
      PIN_NUMBER='(0,0,0,0,0,0,0,0,0,0,0,0,0,0,0,0,0,0,0,0,0,0,0,0,0,0,0,0,0,0,0~
,0,BB15,0,0,0,0,0,0,0)';
      PINUSE='POWER';
      NO_LOAD_CHECK='Both';
      NO_IO_CHECK='Both';
      NO_ASSERT_CHECK='TRUE';
      NO_DIR_CHECK='TRUE';
      ALLOW_CONNECT='TRUE';
    'VSS_BB17':
      PIN_NUMBER='(0,0,0,0,0,0,0,0,0,0,0,0,0,0,0,0,0,0,0,0,0,0,0,0,0,0,0,0,0,0,0~
,0,BB17,0,0,0,0,0,0,0)';
      PINUSE='POWER';
      NO_LOAD_CHECK='Both';
      NO_IO_CHECK='Both';
      NO_ASSERT_CHECK='TRUE';
      NO_DIR_CHECK='TRUE';
      ALLOW_CONNECT='TRUE';
    'VSS_BB19':
      PIN_NUMBER='(0,0,0,0,0,0,0,0,0,0,0,0,0,0,0,0,0,0,0,0,0,0,0,0,0,0,0,0,0,0,0~
,0,BB19,0,0,0,0,0,0,0)';
      PINUSE='POWER';
      NO_LOAD_CHECK='Both';
      NO_IO_CHECK='Both';
      NO_ASSERT_CHECK='TRUE';
      NO_DIR_CHECK='TRUE';
      ALLOW_CONNECT='TRUE';
    'VSS_BB23':
      PIN_NUMBER='(0,0,0,0,0,0,0,0,0,0,0,0,0,0,0,0,0,0,0,0,0,0,0,0,0,0,0,0,0,0,0~
,0,BB23,0,0,0,0,0,0,0)';
      PINUSE='POWER';
      NO_LOAD_CHECK='Both';
      NO_IO_CHECK='Both';
      NO_ASSERT_CHECK='TRUE';
      NO_DIR_CHECK='TRUE';
      ALLOW_CONNECT='TRUE';
    'VSS_BB25':
      PIN_NUMBER='(0,0,0,0,0,0,0,0,0,0,0,0,0,0,0,0,0,0,0,0,0,0,0,0,0,0,0,0,0,0,0~
,0,BB25,0,0,0,0,0,0,0)';
      PINUSE='POWER';
      NO_LOAD_CHECK='Both';
      NO_IO_CHECK='Both';
      NO_ASSERT_CHECK='TRUE';
      NO_DIR_CHECK='TRUE';
      ALLOW_CONNECT='TRUE';
    'VSS_BB27':
      PIN_NUMBER='(0,0,0,0,0,0,0,0,0,0,0,0,0,0,0,0,0,0,0,0,0,0,0,0,0,0,0,0,0,0,0~
,0,BB27,0,0,0,0,0,0,0)';
      PINUSE='POWER';
      NO_LOAD_CHECK='Both';
      NO_IO_CHECK='Both';
      NO_ASSERT_CHECK='TRUE';
      NO_DIR_CHECK='TRUE';
      ALLOW_CONNECT='TRUE';
    'VSS_BB48':
      PIN_NUMBER='(0,0,0,0,0,0,0,0,0,0,0,0,0,0,0,0,0,0,0,0,0,0,0,0,0,0,0,0,0,0,0~
,0,BB48,0,0,0,0,0,0,0)';
      PINUSE='POWER';
      NO_LOAD_CHECK='Both';
      NO_IO_CHECK='Both';
      NO_ASSERT_CHECK='TRUE';
      NO_DIR_CHECK='TRUE';
      ALLOW_CONNECT='TRUE';
    'VSS_BB50':
      PIN_NUMBER='(0,0,0,0,0,0,0,0,0,0,0,0,0,0,0,0,0,0,0,0,0,0,0,0,0,0,0,0,0,0,0~
,0,BB50,0,0,0,0,0,0,0)';
      PINUSE='POWER';
      NO_LOAD_CHECK='Both';
      NO_IO_CHECK='Both';
      NO_ASSERT_CHECK='TRUE';
      NO_DIR_CHECK='TRUE';
      ALLOW_CONNECT='TRUE';
    'VSS_BB52':
      PIN_NUMBER='(0,0,0,0,0,0,0,0,0,0,0,0,0,0,0,0,0,0,0,0,0,0,0,0,0,0,0,0,0,0,0~
,0,BB52,0,0,0,0,0,0,0)';
      PINUSE='POWER';
      NO_LOAD_CHECK='Both';
      NO_IO_CHECK='Both';
      NO_ASSERT_CHECK='TRUE';
      NO_DIR_CHECK='TRUE';
      ALLOW_CONNECT='TRUE';
    'VSS_BB54':
      PIN_NUMBER='(0,0,0,0,0,0,0,0,0,0,0,0,0,0,0,0,0,0,0,0,0,0,0,0,0,0,0,0,0,0,0~
,0,BB54,0,0,0,0,0,0,0)';
      PINUSE='POWER';
      NO_LOAD_CHECK='Both';
      NO_IO_CHECK='Both';
      NO_ASSERT_CHECK='TRUE';
      NO_DIR_CHECK='TRUE';
      ALLOW_CONNECT='TRUE';
    'VSS_BB57':
      PIN_NUMBER='(0,0,0,0,0,0,0,0,0,0,0,0,0,0,0,0,0,0,0,0,0,0,0,0,0,0,0,0,0,0,0~
,0,BB57,0,0,0,0,0,0,0)';
      PINUSE='POWER';
      NO_LOAD_CHECK='Both';
      NO_IO_CHECK='Both';
      NO_ASSERT_CHECK='TRUE';
      NO_DIR_CHECK='TRUE';
      ALLOW_CONNECT='TRUE';
    'VSS_BB59':
      PIN_NUMBER='(0,0,0,0,0,0,0,0,0,0,0,0,0,0,0,0,0,0,0,0,0,0,0,0,0,0,0,0,0,0,0~
,0,BB59,0,0,0,0,0,0,0)';
      PINUSE='POWER';
      NO_LOAD_CHECK='Both';
      NO_IO_CHECK='Both';
      NO_ASSERT_CHECK='TRUE';
      NO_DIR_CHECK='TRUE';
      ALLOW_CONNECT='TRUE';
    'VSS_BB61':
      PIN_NUMBER='(0,0,0,0,0,0,0,0,0,0,0,0,0,0,0,0,0,0,0,0,0,0,0,0,0,0,0,0,0,0,0~
,0,BB61,0,0,0,0,0,0,0)';
      PINUSE='POWER';
      NO_LOAD_CHECK='Both';
      NO_IO_CHECK='Both';
      NO_ASSERT_CHECK='TRUE';
      NO_DIR_CHECK='TRUE';
      ALLOW_CONNECT='TRUE';
    'VSS_BB64':
      PIN_NUMBER='(0,0,0,0,0,0,0,0,0,0,0,0,0,0,0,0,0,0,0,0,0,0,0,0,0,0,0,0,0,0,0~
,0,BB64,0,0,0,0,0,0,0)';
      PINUSE='POWER';
      NO_LOAD_CHECK='Both';
      NO_IO_CHECK='Both';
      NO_ASSERT_CHECK='TRUE';
      NO_DIR_CHECK='TRUE';
      ALLOW_CONNECT='TRUE';
    'VSS_BB66':
      PIN_NUMBER='(0,0,0,0,0,0,0,0,0,0,0,0,0,0,0,0,0,0,0,0,0,0,0,0,0,0,0,0,0,0,0~
,0,BB66,0,0,0,0,0,0,0)';
      PINUSE='POWER';
      NO_LOAD_CHECK='Both';
      NO_IO_CHECK='Both';
      NO_ASSERT_CHECK='TRUE';
      NO_DIR_CHECK='TRUE';
      ALLOW_CONNECT='TRUE';
    'VSS_BB68':
      PIN_NUMBER='(0,0,0,0,0,0,0,0,0,0,0,0,0,0,0,0,0,0,0,0,0,0,0,0,0,0,0,0,0,0,0~
,0,BB68,0,0,0,0,0,0,0)';
      PINUSE='POWER';
      NO_LOAD_CHECK='Both';
      NO_IO_CHECK='Both';
      NO_ASSERT_CHECK='TRUE';
      NO_DIR_CHECK='TRUE';
      ALLOW_CONNECT='TRUE';
    'VSS_BB71':
      PIN_NUMBER='(0,0,0,0,0,0,0,0,0,0,0,0,0,0,0,0,0,0,0,0,0,0,0,0,0,0,0,0,0,0,0~
,0,BB71,0,0,0,0,0,0,0)';
      PINUSE='POWER';
      NO_LOAD_CHECK='Both';
      NO_IO_CHECK='Both';
      NO_ASSERT_CHECK='TRUE';
      NO_DIR_CHECK='TRUE';
      ALLOW_CONNECT='TRUE';
    'VSS_BB73':
      PIN_NUMBER='(0,0,0,0,0,0,0,0,0,0,0,0,0,0,0,0,0,0,0,0,0,0,0,0,0,0,0,0,0,0,0~
,0,BB73,0,0,0,0,0,0,0)';
      PINUSE='POWER';
      NO_LOAD_CHECK='Both';
      NO_IO_CHECK='Both';
      NO_ASSERT_CHECK='TRUE';
      NO_DIR_CHECK='TRUE';
      ALLOW_CONNECT='TRUE';
    'VSS_BC1':
      PIN_NUMBER='(0,0,0,0,0,0,0,0,0,0,0,0,0,0,0,0,0,0,0,0,0,0,0,0,0,0,0,0,0,0,0~
,0,BC1,0,0,0,0,0,0,0)';
      PINUSE='POWER';
      NO_LOAD_CHECK='Both';
      NO_IO_CHECK='Both';
      NO_ASSERT_CHECK='TRUE';
      NO_DIR_CHECK='TRUE';
      ALLOW_CONNECT='TRUE';
    'VSS_BC4':
      PIN_NUMBER='(0,0,0,0,0,0,0,0,0,0,0,0,0,0,0,0,0,0,0,0,0,0,0,0,0,0,0,0,0,0,0~
,0,BC4,0,0,0,0,0,0,0)';
      PINUSE='POWER';
      NO_LOAD_CHECK='Both';
      NO_IO_CHECK='Both';
      NO_ASSERT_CHECK='TRUE';
      NO_DIR_CHECK='TRUE';
      ALLOW_CONNECT='TRUE';
    'VSS_BC6':
      PIN_NUMBER='(0,0,0,0,0,0,0,0,0,0,0,0,0,0,0,0,0,0,0,0,0,0,0,0,0,0,0,0,0,0,0~
,0,BC6,0,0,0,0,0,0,0)';
      PINUSE='POWER';
      NO_LOAD_CHECK='Both';
      NO_IO_CHECK='Both';
      NO_ASSERT_CHECK='TRUE';
      NO_DIR_CHECK='TRUE';
      ALLOW_CONNECT='TRUE';
    'VSS_BC8':
      PIN_NUMBER='(0,0,0,0,0,0,0,0,0,0,0,0,0,0,0,0,0,0,0,0,0,0,0,0,0,0,0,0,0,0,0~
,0,BC8,0,0,0,0,0,0,0)';
      PINUSE='POWER';
      NO_LOAD_CHECK='Both';
      NO_IO_CHECK='Both';
      NO_ASSERT_CHECK='TRUE';
      NO_DIR_CHECK='TRUE';
      ALLOW_CONNECT='TRUE';
    'VSS_BC11':
      PIN_NUMBER='(0,0,0,0,0,0,0,0,0,0,0,0,0,0,0,0,0,0,0,0,0,0,0,0,0,0,0,0,0,0,0~
,0,BC11,0,0,0,0,0,0,0)';
      PINUSE='POWER';
      NO_LOAD_CHECK='Both';
      NO_IO_CHECK='Both';
      NO_ASSERT_CHECK='TRUE';
      NO_DIR_CHECK='TRUE';
      ALLOW_CONNECT='TRUE';
    'VSS_BC13':
      PIN_NUMBER='(0,0,0,0,0,0,0,0,0,0,0,0,0,0,0,0,0,0,0,0,0,0,0,0,0,0,0,0,0,0,0~
,0,BC13,0,0,0,0,0,0,0)';
      PINUSE='POWER';
      NO_LOAD_CHECK='Both';
      NO_IO_CHECK='Both';
      NO_ASSERT_CHECK='TRUE';
      NO_DIR_CHECK='TRUE';
      ALLOW_CONNECT='TRUE';
    'VSS_BC15':
      PIN_NUMBER='(0,0,0,0,0,0,0,0,0,0,0,0,0,0,0,0,0,0,0,0,0,0,0,0,0,0,0,0,0,0,0~
,0,BC15,0,0,0,0,0,0,0)';
      PINUSE='POWER';
      NO_LOAD_CHECK='Both';
      NO_IO_CHECK='Both';
      NO_ASSERT_CHECK='TRUE';
      NO_DIR_CHECK='TRUE';
      ALLOW_CONNECT='TRUE';
    'VSS_BC18':
      PIN_NUMBER='(0,0,0,0,0,0,0,0,0,0,0,0,0,0,0,0,0,0,0,0,0,0,0,0,0,0,0,0,0,0,0~
,0,BC18,0,0,0,0,0,0,0)';
      PINUSE='POWER';
      NO_LOAD_CHECK='Both';
      NO_IO_CHECK='Both';
      NO_ASSERT_CHECK='TRUE';
      NO_DIR_CHECK='TRUE';
      ALLOW_CONNECT='TRUE';
    'VSS_BC20':
      PIN_NUMBER='(0,0,0,0,0,0,0,0,0,0,0,0,0,0,0,0,0,0,0,0,0,0,0,0,0,0,0,0,0,0,0~
,0,BC20,0,0,0,0,0,0,0)';
      PINUSE='POWER';
      NO_LOAD_CHECK='Both';
      NO_IO_CHECK='Both';
      NO_ASSERT_CHECK='TRUE';
      NO_DIR_CHECK='TRUE';
      ALLOW_CONNECT='TRUE';
    'VSS_BC22':
      PIN_NUMBER='(0,0,0,0,0,0,0,0,0,0,0,0,0,0,0,0,0,0,0,0,0,0,0,0,0,0,0,0,0,0,0~
,0,BC22,0,0,0,0,0,0,0)';
      PINUSE='POWER';
      NO_LOAD_CHECK='Both';
      NO_IO_CHECK='Both';
      NO_ASSERT_CHECK='TRUE';
      NO_DIR_CHECK='TRUE';
      ALLOW_CONNECT='TRUE';
    'VSS_BC24':
      PIN_NUMBER='(0,0,0,0,0,0,0,0,0,0,0,0,0,0,0,0,0,0,0,0,0,0,0,0,0,0,0,0,0,0,0~
,0,BC24,0,0,0,0,0,0,0)';
      PINUSE='POWER';
      NO_LOAD_CHECK='Both';
      NO_IO_CHECK='Both';
      NO_ASSERT_CHECK='TRUE';
      NO_DIR_CHECK='TRUE';
      ALLOW_CONNECT='TRUE';
    'VSS_BC26':
      PIN_NUMBER='(0,0,0,0,0,0,0,0,0,0,0,0,0,0,0,0,0,0,0,0,0,0,0,0,0,0,0,0,0,0,0~
,0,BC26,0,0,0,0,0,0,0)';
      PINUSE='POWER';
      NO_LOAD_CHECK='Both';
      NO_IO_CHECK='Both';
      NO_ASSERT_CHECK='TRUE';
      NO_DIR_CHECK='TRUE';
      ALLOW_CONNECT='TRUE';
    'VSS_BC28':
      PIN_NUMBER='(0,0,0,0,0,0,0,0,0,0,0,0,0,0,0,0,0,0,0,0,0,0,0,0,0,0,0,0,0,0,0~
,0,BC28,0,0,0,0,0,0,0)';
      PINUSE='POWER';
      NO_LOAD_CHECK='Both';
      NO_IO_CHECK='Both';
      NO_ASSERT_CHECK='TRUE';
      NO_DIR_CHECK='TRUE';
      ALLOW_CONNECT='TRUE';
    'VSS_BC49':
      PIN_NUMBER='(0,0,0,0,0,0,0,0,0,0,0,0,0,0,0,0,0,0,0,0,0,0,0,0,0,0,0,0,0,0,0~
,0,BC49,0,0,0,0,0,0,0)';
      PINUSE='POWER';
      NO_LOAD_CHECK='Both';
      NO_IO_CHECK='Both';
      NO_ASSERT_CHECK='TRUE';
      NO_DIR_CHECK='TRUE';
      ALLOW_CONNECT='TRUE';
    'VSS_BC50':
      PIN_NUMBER='(0,0,0,0,0,0,0,0,0,0,0,0,0,0,0,0,0,0,0,0,0,0,0,0,0,0,0,0,0,0,0~
,0,BC50,0,0,0,0,0,0,0)';
      PINUSE='POWER';
      NO_LOAD_CHECK='Both';
      NO_IO_CHECK='Both';
      NO_ASSERT_CHECK='TRUE';
      NO_DIR_CHECK='TRUE';
      ALLOW_CONNECT='TRUE';
    'VSS_BC51':
      PIN_NUMBER='(0,0,0,0,0,0,0,0,0,0,0,0,0,0,0,0,0,0,0,0,0,0,0,0,0,0,0,0,0,0,0~
,0,BC51,0,0,0,0,0,0,0)';
      PINUSE='POWER';
      NO_LOAD_CHECK='Both';
      NO_IO_CHECK='Both';
      NO_ASSERT_CHECK='TRUE';
      NO_DIR_CHECK='TRUE';
      ALLOW_CONNECT='TRUE';
    'VSS_BC53':
      PIN_NUMBER='(0,0,0,0,0,0,0,0,0,0,0,0,0,0,0,0,0,0,0,0,0,0,0,0,0,0,0,0,0,0,0~
,0,BC53,0,0,0,0,0,0,0)';
      PINUSE='POWER';
      NO_LOAD_CHECK='Both';
      NO_IO_CHECK='Both';
      NO_ASSERT_CHECK='TRUE';
      NO_DIR_CHECK='TRUE';
      ALLOW_CONNECT='TRUE';
    'VSS_BC56':
      PIN_NUMBER='(0,0,0,0,0,0,0,0,0,0,0,0,0,0,0,0,0,0,0,0,0,0,0,0,0,0,0,0,0,0,0~
,0,BC56,0,0,0,0,0,0,0)';
      PINUSE='POWER';
      NO_LOAD_CHECK='Both';
      NO_IO_CHECK='Both';
      NO_ASSERT_CHECK='TRUE';
      NO_DIR_CHECK='TRUE';
      ALLOW_CONNECT='TRUE';
    'VSS_BC58':
      PIN_NUMBER='(0,0,0,0,0,0,0,0,0,0,0,0,0,0,0,0,0,0,0,0,0,0,0,0,0,0,0,0,0,0,0~
,0,BC58,0,0,0,0,0,0,0)';
      PINUSE='POWER';
      NO_LOAD_CHECK='Both';
      NO_IO_CHECK='Both';
      NO_ASSERT_CHECK='TRUE';
      NO_DIR_CHECK='TRUE';
      ALLOW_CONNECT='TRUE';
    'VSS_BC61':
      PIN_NUMBER='(0,0,0,0,0,0,0,0,0,0,0,0,0,0,0,0,0,0,0,0,0,0,0,0,0,0,0,0,0,0,0~
,0,BC61,0,0,0,0,0,0,0)';
      PINUSE='POWER';
      NO_LOAD_CHECK='Both';
      NO_IO_CHECK='Both';
      NO_ASSERT_CHECK='TRUE';
      NO_DIR_CHECK='TRUE';
      ALLOW_CONNECT='TRUE';
    'VSS_BC63':
      PIN_NUMBER='(0,0,0,0,0,0,0,0,0,0,0,0,0,0,0,0,0,0,0,0,0,0,0,0,0,0,0,0,0,0,0~
,0,BC63,0,0,0,0,0,0,0)';
      PINUSE='POWER';
      NO_LOAD_CHECK='Both';
      NO_IO_CHECK='Both';
      NO_ASSERT_CHECK='TRUE';
      NO_DIR_CHECK='TRUE';
      ALLOW_CONNECT='TRUE';
    'VSS_BC65':
      PIN_NUMBER='(0,0,0,0,0,0,0,0,0,0,0,0,0,0,0,0,0,0,0,0,0,0,0,0,0,0,0,0,0,0,0~
,0,BC65,0,0,0,0,0,0,0)';
      PINUSE='POWER';
      NO_LOAD_CHECK='Both';
      NO_IO_CHECK='Both';
      NO_ASSERT_CHECK='TRUE';
      NO_DIR_CHECK='TRUE';
      ALLOW_CONNECT='TRUE';
    'VSS_BC68':
      PIN_NUMBER='(0,0,0,0,0,0,0,0,0,0,0,0,0,0,0,0,0,0,0,0,0,0,0,0,0,0,0,0,0,0,0~
,0,BC68,0,0,0,0,0,0,0)';
      PINUSE='POWER';
      NO_LOAD_CHECK='Both';
      NO_IO_CHECK='Both';
      NO_ASSERT_CHECK='TRUE';
      NO_DIR_CHECK='TRUE';
      ALLOW_CONNECT='TRUE';
    'VSS_BC70':
      PIN_NUMBER='(0,0,0,0,0,0,0,0,0,0,0,0,0,0,0,0,0,0,0,0,0,0,0,0,0,0,0,0,0,0,0~
,0,BC70,0,0,0,0,0,0,0)';
      PINUSE='POWER';
      NO_LOAD_CHECK='Both';
      NO_IO_CHECK='Both';
      NO_ASSERT_CHECK='TRUE';
      NO_DIR_CHECK='TRUE';
      ALLOW_CONNECT='TRUE';
    'VSS_BC72':
      PIN_NUMBER='(0,0,0,0,0,0,0,0,0,0,0,0,0,0,0,0,0,0,0,0,0,0,0,0,0,0,0,0,0,0,0~
,0,BC72,0,0,0,0,0,0,0)';
      PINUSE='POWER';
      NO_LOAD_CHECK='Both';
      NO_IO_CHECK='Both';
      NO_ASSERT_CHECK='TRUE';
      NO_DIR_CHECK='TRUE';
      ALLOW_CONNECT='TRUE';
    'VSS_BC75':
      PIN_NUMBER='(0,0,0,0,0,0,0,0,0,0,0,0,0,0,0,0,0,0,0,0,0,0,0,0,0,0,0,0,0,0,0~
,0,BC75,0,0,0,0,0,0,0)';
      PINUSE='POWER';
      NO_LOAD_CHECK='Both';
      NO_IO_CHECK='Both';
      NO_ASSERT_CHECK='TRUE';
      NO_DIR_CHECK='TRUE';
      ALLOW_CONNECT='TRUE';
    'VSS_BD3':
      PIN_NUMBER='(0,0,0,0,0,0,0,0,0,0,0,0,0,0,0,0,0,0,0,0,0,0,0,0,0,0,0,0,0,0,0~
,0,BD3,0,0,0,0,0,0,0)';
      PINUSE='POWER';
      NO_LOAD_CHECK='Both';
      NO_IO_CHECK='Both';
      NO_ASSERT_CHECK='TRUE';
      NO_DIR_CHECK='TRUE';
      ALLOW_CONNECT='TRUE';
    'VSS_BD8':
      PIN_NUMBER='(0,0,0,0,0,0,0,0,0,0,0,0,0,0,0,0,0,0,0,0,0,0,0,0,0,0,0,0,0,0,0~
,0,BD8,0,0,0,0,0,0,0)';
      PINUSE='POWER';
      NO_LOAD_CHECK='Both';
      NO_IO_CHECK='Both';
      NO_ASSERT_CHECK='TRUE';
      NO_DIR_CHECK='TRUE';
      ALLOW_CONNECT='TRUE';
    'VSS_BD10':
      PIN_NUMBER='(0,0,0,0,0,0,0,0,0,0,0,0,0,0,0,0,0,0,0,0,0,0,0,0,0,0,0,0,0,0,0~
,0,BD10,0,0,0,0,0,0,0)';
      PINUSE='POWER';
      NO_LOAD_CHECK='Both';
      NO_IO_CHECK='Both';
      NO_ASSERT_CHECK='TRUE';
      NO_DIR_CHECK='TRUE';
      ALLOW_CONNECT='TRUE';
    'VSS_BD15':
      PIN_NUMBER='(0,0,0,0,0,0,0,0,0,0,0,0,0,0,0,0,0,0,0,0,0,0,0,0,0,0,0,0,0,0,0~
,0,BD15,0,0,0,0,0,0,0)';
      PINUSE='POWER';
      NO_LOAD_CHECK='Both';
      NO_IO_CHECK='Both';
      NO_ASSERT_CHECK='TRUE';
      NO_DIR_CHECK='TRUE';
      ALLOW_CONNECT='TRUE';
    'VSS_BD17':
      PIN_NUMBER='(0,0,0,0,0,0,0,0,0,0,0,0,0,0,0,0,0,0,0,0,0,0,0,0,0,0,0,0,0,0,0~
,0,BD17,0,0,0,0,0,0,0)';
      PINUSE='POWER';
      NO_LOAD_CHECK='Both';
      NO_IO_CHECK='Both';
      NO_ASSERT_CHECK='TRUE';
      NO_DIR_CHECK='TRUE';
      ALLOW_CONNECT='TRUE';
    'VSS_BD23':
      PIN_NUMBER='(0,0,0,0,0,0,0,0,0,0,0,0,0,0,0,0,0,0,0,0,0,0,0,0,0,0,0,0,0,0,0~
,0,BD23,0,0,0,0,0,0,0)';
      PINUSE='POWER';
      NO_LOAD_CHECK='Both';
      NO_IO_CHECK='Both';
      NO_ASSERT_CHECK='TRUE';
      NO_DIR_CHECK='TRUE';
      ALLOW_CONNECT='TRUE';
    'VSS_BD25':
      PIN_NUMBER='(0,0,0,0,0,0,0,0,0,0,0,0,0,0,0,0,0,0,0,0,0,0,0,0,0,0,0,0,0,0,0~
,0,BD25,0,0,0,0,0,0,0)';
      PINUSE='POWER';
      NO_LOAD_CHECK='Both';
      NO_IO_CHECK='Both';
      NO_ASSERT_CHECK='TRUE';
      NO_DIR_CHECK='TRUE';
      ALLOW_CONNECT='TRUE';
    'VSS_BD27':
      PIN_NUMBER='(0,0,0,0,0,0,0,0,0,0,0,0,0,0,0,0,0,0,0,0,0,0,0,0,0,0,0,0,0,0,0~
,0,BD27,0,0,0,0,0,0,0)';
      PINUSE='POWER';
      NO_LOAD_CHECK='Both';
      NO_IO_CHECK='Both';
      NO_ASSERT_CHECK='TRUE';
      NO_DIR_CHECK='TRUE';
      ALLOW_CONNECT='TRUE';
    'VSS_BD49':
      PIN_NUMBER='(0,0,0,0,0,0,0,0,0,0,0,0,0,0,0,0,0,0,0,0,0,0,0,0,0,0,0,0,0,0,0~
,0,BD49,0,0,0,0,0,0,0)';
      PINUSE='POWER';
      NO_LOAD_CHECK='Both';
      NO_IO_CHECK='Both';
      NO_ASSERT_CHECK='TRUE';
      NO_DIR_CHECK='TRUE';
      ALLOW_CONNECT='TRUE';
    'VSS_BD51':
      PIN_NUMBER='(0,0,0,0,0,0,0,0,0,0,0,0,0,0,0,0,0,0,0,0,0,0,0,0,0,0,0,0,0,0,0~
,0,BD51,0,0,0,0,0,0,0)';
      PINUSE='POWER';
      NO_LOAD_CHECK='Both';
      NO_IO_CHECK='Both';
      NO_ASSERT_CHECK='TRUE';
      NO_DIR_CHECK='TRUE';
      ALLOW_CONNECT='TRUE';
    'VSS_BD53':
      PIN_NUMBER='(0,0,0,0,0,0,0,0,0,0,0,0,0,0,0,0,0,0,0,0,0,0,0,0,0,0,0,0,0,0,0~
,0,BD53,0,0,0,0,0,0,0)';
      PINUSE='POWER';
      NO_LOAD_CHECK='Both';
      NO_IO_CHECK='Both';
      NO_ASSERT_CHECK='TRUE';
      NO_DIR_CHECK='TRUE';
      ALLOW_CONNECT='TRUE';
    'VSS_BD57':
      PIN_NUMBER='(0,0,0,0,0,0,0,0,0,0,0,0,0,0,0,0,0,0,0,0,0,0,0,0,0,0,0,0,0,0,0~
,0,BD57,0,0,0,0,0,0,0)';
      PINUSE='POWER';
      NO_LOAD_CHECK='Both';
      NO_IO_CHECK='Both';
      NO_ASSERT_CHECK='TRUE';
      NO_DIR_CHECK='TRUE';
      ALLOW_CONNECT='TRUE';
    'VSS_BD59':
      PIN_NUMBER='(0,0,0,0,0,0,0,0,0,0,0,0,0,0,0,0,0,0,0,0,0,0,0,0,0,0,0,0,0,0,0~
,0,BD59,0,0,0,0,0,0,0)';
      PINUSE='POWER';
      NO_LOAD_CHECK='Both';
      NO_IO_CHECK='Both';
      NO_ASSERT_CHECK='TRUE';
      NO_DIR_CHECK='TRUE';
      ALLOW_CONNECT='TRUE';
    'VSS_BD61':
      PIN_NUMBER='(0,0,0,0,0,0,0,0,0,0,0,0,0,0,0,0,0,0,0,0,0,0,0,0,0,0,0,0,0,0,0~
,0,BD61,0,0,0,0,0,0,0)';
      PINUSE='POWER';
      NO_LOAD_CHECK='Both';
      NO_IO_CHECK='Both';
      NO_ASSERT_CHECK='TRUE';
      NO_DIR_CHECK='TRUE';
      ALLOW_CONNECT='TRUE';
    'VSS_BD64':
      PIN_NUMBER='(0,0,0,0,0,0,0,0,0,0,0,0,0,0,0,0,0,0,0,0,0,0,0,0,0,0,0,0,0,0,0~
,0,BD64,0,0,0,0,0,0,0)';
      PINUSE='POWER';
      NO_LOAD_CHECK='Both';
      NO_IO_CHECK='Both';
      NO_ASSERT_CHECK='TRUE';
      NO_DIR_CHECK='TRUE';
      ALLOW_CONNECT='TRUE';
    'VSS_BD66':
      PIN_NUMBER='(0,0,0,0,0,0,0,0,0,0,0,0,0,0,0,0,0,0,0,0,0,0,0,0,0,0,0,0,0,0,0~
,0,BD66,0,0,0,0,0,0,0)';
      PINUSE='POWER';
      NO_LOAD_CHECK='Both';
      NO_IO_CHECK='Both';
      NO_ASSERT_CHECK='TRUE';
      NO_DIR_CHECK='TRUE';
      ALLOW_CONNECT='TRUE';
    'VSS_BD68':
      PIN_NUMBER='(0,0,0,0,0,0,0,0,0,0,0,0,0,0,0,0,0,0,0,0,0,0,0,0,0,0,0,0,0,0,0~
,0,BD68,0,0,0,0,0,0,0)';
      PINUSE='POWER';
      NO_LOAD_CHECK='Both';
      NO_IO_CHECK='Both';
      NO_ASSERT_CHECK='TRUE';
      NO_DIR_CHECK='TRUE';
      ALLOW_CONNECT='TRUE';
    'VSS_BD71':
      PIN_NUMBER='(0,0,0,0,0,0,0,0,0,0,0,0,0,0,0,0,0,0,0,0,0,0,0,0,0,0,0,0,0,0,0~
,0,BD71,0,0,0,0,0,0,0)';
      PINUSE='POWER';
      NO_LOAD_CHECK='Both';
      NO_IO_CHECK='Both';
      NO_ASSERT_CHECK='TRUE';
      NO_DIR_CHECK='TRUE';
      ALLOW_CONNECT='TRUE';
    'VSS_BD73':
      PIN_NUMBER='(0,0,0,0,0,0,0,0,0,0,0,0,0,0,0,0,0,0,0,0,0,0,0,0,0,0,0,0,0,0,0~
,0,BD73,0,0,0,0,0,0,0)';
      PINUSE='POWER';
      NO_LOAD_CHECK='Both';
      NO_IO_CHECK='Both';
      NO_ASSERT_CHECK='TRUE';
      NO_DIR_CHECK='TRUE';
      ALLOW_CONNECT='TRUE';
    'VSS_BF3':
      PIN_NUMBER='(0,0,0,0,0,0,0,0,0,0,0,0,0,0,0,0,0,0,0,0,0,0,0,0,0,0,0,0,0,0,0~
,0,BF3,0,0,0,0,0,0,0)';
      PINUSE='POWER';
      NO_LOAD_CHECK='Both';
      NO_IO_CHECK='Both';
      NO_ASSERT_CHECK='TRUE';
      NO_DIR_CHECK='TRUE';
      ALLOW_CONNECT='TRUE';
    'VSS_BF5':
      PIN_NUMBER='(0,0,0,0,0,0,0,0,0,0,0,0,0,0,0,0,0,0,0,0,0,0,0,0,0,0,0,0,0,0,0~
,0,BF5,0,0,0,0,0,0,0)';
      PINUSE='POWER';
      NO_LOAD_CHECK='Both';
      NO_IO_CHECK='Both';
      NO_ASSERT_CHECK='TRUE';
      NO_DIR_CHECK='TRUE';
      ALLOW_CONNECT='TRUE';
    'VSS_BF8':
      PIN_NUMBER='(0,0,0,0,0,0,0,0,0,0,0,0,0,0,0,0,0,0,0,0,0,0,0,0,0,0,0,0,0,0,0~
,0,BF8,0,0,0,0,0,0,0)';
      PINUSE='POWER';
      NO_LOAD_CHECK='Both';
      NO_IO_CHECK='Both';
      NO_ASSERT_CHECK='TRUE';
      NO_DIR_CHECK='TRUE';
      ALLOW_CONNECT='TRUE';
    'VSS_BF10':
      PIN_NUMBER='(0,0,0,0,0,0,0,0,0,0,0,0,0,0,0,0,0,0,0,0,0,0,0,0,0,0,0,0,0,0,0~
,0,BF10,0,0,0,0,0,0,0)';
      PINUSE='POWER';
      NO_LOAD_CHECK='Both';
      NO_IO_CHECK='Both';
      NO_ASSERT_CHECK='TRUE';
      NO_DIR_CHECK='TRUE';
      ALLOW_CONNECT='TRUE';
    'VSS_BF12':
      PIN_NUMBER='(0,0,0,0,0,0,0,0,0,0,0,0,0,0,0,0,0,0,0,0,0,0,0,0,0,0,0,0,0,0,0~
,0,BF12,0,0,0,0,0,0,0)';
      PINUSE='POWER';
      NO_LOAD_CHECK='Both';
      NO_IO_CHECK='Both';
      NO_ASSERT_CHECK='TRUE';
      NO_DIR_CHECK='TRUE';
      ALLOW_CONNECT='TRUE';
    'VSS_BF15':
      PIN_NUMBER='(0,0,0,0,0,0,0,0,0,0,0,0,0,0,0,0,0,0,0,0,0,0,0,0,0,0,0,0,0,0,0~
,0,BF15,0,0,0,0,0,0,0)';
      PINUSE='POWER';
      NO_LOAD_CHECK='Both';
      NO_IO_CHECK='Both';
      NO_ASSERT_CHECK='TRUE';
      NO_DIR_CHECK='TRUE';
      ALLOW_CONNECT='TRUE';
    'VSS_BF17':
      PIN_NUMBER='(0,0,0,0,0,0,0,0,0,0,0,0,0,0,0,0,0,0,0,0,0,0,0,0,0,0,0,0,0,0,0~
,0,BF17,0,0,0,0,0,0,0)';
      PINUSE='POWER';
      NO_LOAD_CHECK='Both';
      NO_IO_CHECK='Both';
      NO_ASSERT_CHECK='TRUE';
      NO_DIR_CHECK='TRUE';
      ALLOW_CONNECT='TRUE';
    'VSS_BF19':
      PIN_NUMBER='(0,0,0,0,0,0,0,0,0,0,0,0,0,0,0,0,0,0,0,0,0,0,0,0,0,0,0,0,0,0,0~
,0,BF19,0,0,0,0,0,0,0)';
      PINUSE='POWER';
      NO_LOAD_CHECK='Both';
      NO_IO_CHECK='Both';
      NO_ASSERT_CHECK='TRUE';
      NO_DIR_CHECK='TRUE';
      ALLOW_CONNECT='TRUE';
    'VSS_BF22':
      PIN_NUMBER='(0,0,0,0,0,0,0,0,0,0,0,0,0,0,0,0,0,0,0,0,0,0,0,0,0,0,0,0,0,0,0~
,0,BF22,0,0,0,0,0,0,0)';
      PINUSE='POWER';
      NO_LOAD_CHECK='Both';
      NO_IO_CHECK='Both';
      NO_ASSERT_CHECK='TRUE';
      NO_DIR_CHECK='TRUE';
      ALLOW_CONNECT='TRUE';
    'VSS_BF24':
      PIN_NUMBER='(0,0,0,0,0,0,0,0,0,0,0,0,0,0,0,0,0,0,0,0,0,0,0,0,0,0,0,0,0,0,0~
,0,BF24,0,0,0,0,0,0,0)';
      PINUSE='POWER';
      NO_LOAD_CHECK='Both';
      NO_IO_CHECK='Both';
      NO_ASSERT_CHECK='TRUE';
      NO_DIR_CHECK='TRUE';
      ALLOW_CONNECT='TRUE';
    'VSS_BF26':
      PIN_NUMBER='(0,0,0,0,0,0,0,0,0,0,0,0,0,0,0,0,0,0,0,0,0,0,0,0,0,0,0,0,0,0,0~
,0,BF26,0,0,0,0,0,0,0)';
      PINUSE='POWER';
      NO_LOAD_CHECK='Both';
      NO_IO_CHECK='Both';
      NO_ASSERT_CHECK='TRUE';
      NO_DIR_CHECK='TRUE';
      ALLOW_CONNECT='TRUE';
    'VSS_BF28':
      PIN_NUMBER='(0,0,0,0,0,0,0,0,0,0,0,0,0,0,0,0,0,0,0,0,0,0,0,0,0,0,0,0,0,0,0~
,0,BF28,0,0,0,0,0,0,0)';
      PINUSE='POWER';
      NO_LOAD_CHECK='Both';
      NO_IO_CHECK='Both';
      NO_ASSERT_CHECK='TRUE';
      NO_DIR_CHECK='TRUE';
      ALLOW_CONNECT='TRUE';
    'VSS_BF49':
      PIN_NUMBER='(0,0,0,0,0,0,0,0,0,0,0,0,0,0,0,0,0,0,0,0,0,0,0,0,0,0,0,0,0,0,0~
,0,BF49,0,0,0,0,0,0,0)';
      PINUSE='POWER';
      NO_LOAD_CHECK='Both';
      NO_IO_CHECK='Both';
      NO_ASSERT_CHECK='TRUE';
      NO_DIR_CHECK='TRUE';
      ALLOW_CONNECT='TRUE';
    'VSS_BF50':
      PIN_NUMBER='(0,0,0,0,0,0,0,0,0,0,0,0,0,0,0,0,0,0,0,0,0,0,0,0,0,0,0,0,0,0,0~
,0,BF50,0,0,0,0,0,0,0)';
      PINUSE='POWER';
      NO_LOAD_CHECK='Both';
      NO_IO_CHECK='Both';
      NO_ASSERT_CHECK='TRUE';
      NO_DIR_CHECK='TRUE';
      ALLOW_CONNECT='TRUE';
    'VSS_BF52':
      PIN_NUMBER='(0,0,0,0,0,0,0,0,0,0,0,0,0,0,0,0,0,0,0,0,0,0,0,0,0,0,0,0,0,0,0~
,0,BF52,0,0,0,0,0,0,0)';
      PINUSE='POWER';
      NO_LOAD_CHECK='Both';
      NO_IO_CHECK='Both';
      NO_ASSERT_CHECK='TRUE';
      NO_DIR_CHECK='TRUE';
      ALLOW_CONNECT='TRUE';
    'VSS_BF54':
      PIN_NUMBER='(0,0,0,0,0,0,0,0,0,0,0,0,0,0,0,0,0,0,0,0,0,0,0,0,0,0,0,0,0,0,0~
,0,BF54,0,0,0,0,0,0,0)';
      PINUSE='POWER';
      NO_LOAD_CHECK='Both';
      NO_IO_CHECK='Both';
      NO_ASSERT_CHECK='TRUE';
      NO_DIR_CHECK='TRUE';
      ALLOW_CONNECT='TRUE';
    'VSS_BF59':
      PIN_NUMBER='(0,0,0,0,0,0,0,0,0,0,0,0,0,0,0,0,0,0,0,0,0,0,0,0,0,0,0,0,0,0,0~
,0,BF59,0,0,0,0,0,0,0)';
      PINUSE='POWER';
      NO_LOAD_CHECK='Both';
      NO_IO_CHECK='Both';
      NO_ASSERT_CHECK='TRUE';
      NO_DIR_CHECK='TRUE';
      ALLOW_CONNECT='TRUE';
    'VSS_BF61':
      PIN_NUMBER='(0,0,0,0,0,0,0,0,0,0,0,0,0,0,0,0,0,0,0,0,0,0,0,0,0,0,0,0,0,0,0~
,0,BF61,0,0,0,0,0,0,0)';
      PINUSE='POWER';
      NO_LOAD_CHECK='Both';
      NO_IO_CHECK='Both';
      NO_ASSERT_CHECK='TRUE';
      NO_DIR_CHECK='TRUE';
      ALLOW_CONNECT='TRUE';
    'VSS_BF66':
      PIN_NUMBER='(0,0,0,0,0,0,0,0,0,0,0,0,0,0,0,0,0,0,0,0,0,0,0,0,0,0,0,0,0,0,0~
,0,BF66,0,0,0,0,0,0,0)';
      PINUSE='POWER';
      NO_LOAD_CHECK='Both';
      NO_IO_CHECK='Both';
      NO_ASSERT_CHECK='TRUE';
      NO_DIR_CHECK='TRUE';
      ALLOW_CONNECT='TRUE';
    'VSS_BF68':
      PIN_NUMBER='(0,0,0,0,0,0,0,0,0,0,0,0,0,0,0,0,0,0,0,0,0,0,0,0,0,0,0,0,0,0,0~
,0,BF68,0,0,0,0,0,0,0)';
      PINUSE='POWER';
      NO_LOAD_CHECK='Both';
      NO_IO_CHECK='Both';
      NO_ASSERT_CHECK='TRUE';
      NO_DIR_CHECK='TRUE';
      ALLOW_CONNECT='TRUE';
    'VSS_BF73':
      PIN_NUMBER='(0,0,0,0,0,0,0,0,0,0,0,0,0,0,0,0,0,0,0,0,0,0,0,0,0,0,0,0,0,0,0~
,0,BF73,0,0,0,0,0,0,0)';
      PINUSE='POWER';
      NO_LOAD_CHECK='Both';
      NO_IO_CHECK='Both';
      NO_ASSERT_CHECK='TRUE';
      NO_DIR_CHECK='TRUE';
      ALLOW_CONNECT='TRUE';
    'VSS_BG1':
      PIN_NUMBER='(0,0,0,0,0,0,0,0,0,0,0,0,0,0,0,0,0,0,0,0,0,0,0,0,0,0,0,0,0,0,0~
,0,BG1,0,0,0,0,0,0,0)';
      PINUSE='POWER';
      NO_LOAD_CHECK='Both';
      NO_IO_CHECK='Both';
      NO_ASSERT_CHECK='TRUE';
      NO_DIR_CHECK='TRUE';
      ALLOW_CONNECT='TRUE';
    'VSS_BG4':
      PIN_NUMBER='(0,0,0,0,0,0,0,0,0,0,0,0,0,0,0,0,0,0,0,0,0,0,0,0,0,0,0,0,0,0,0~
,0,BG4,0,0,0,0,0,0,0)';
      PINUSE='POWER';
      NO_LOAD_CHECK='Both';
      NO_IO_CHECK='Both';
      NO_ASSERT_CHECK='TRUE';
      NO_DIR_CHECK='TRUE';
      ALLOW_CONNECT='TRUE';
    'VSS_BG6':
      PIN_NUMBER='(0,0,0,0,0,0,0,0,0,0,0,0,0,0,0,0,0,0,0,0,0,0,0,0,0,0,0,0,0,0,0~
,0,BG6,0,0,0,0,0,0,0)';
      PINUSE='POWER';
      NO_LOAD_CHECK='Both';
      NO_IO_CHECK='Both';
      NO_ASSERT_CHECK='TRUE';
      NO_DIR_CHECK='TRUE';
      ALLOW_CONNECT='TRUE';
    'VSS_BG8':
      PIN_NUMBER='(0,0,0,0,0,0,0,0,0,0,0,0,0,0,0,0,0,0,0,0,0,0,0,0,0,0,0,0,0,0,0~
,0,BG8,0,0,0,0,0,0,0)';
      PINUSE='POWER';
      NO_LOAD_CHECK='Both';
      NO_IO_CHECK='Both';
      NO_ASSERT_CHECK='TRUE';
      NO_DIR_CHECK='TRUE';
      ALLOW_CONNECT='TRUE';
    'VSS_BG11':
      PIN_NUMBER='(0,0,0,0,0,0,0,0,0,0,0,0,0,0,0,0,0,0,0,0,0,0,0,0,0,0,0,0,0,0,0~
,0,BG11,0,0,0,0,0,0,0)';
      PINUSE='POWER';
      NO_LOAD_CHECK='Both';
      NO_IO_CHECK='Both';
      NO_ASSERT_CHECK='TRUE';
      NO_DIR_CHECK='TRUE';
      ALLOW_CONNECT='TRUE';
    'VSS_BG13':
      PIN_NUMBER='(0,0,0,0,0,0,0,0,0,0,0,0,0,0,0,0,0,0,0,0,0,0,0,0,0,0,0,0,0,0,0~
,0,BG13,0,0,0,0,0,0,0)';
      PINUSE='POWER';
      NO_LOAD_CHECK='Both';
      NO_IO_CHECK='Both';
      NO_ASSERT_CHECK='TRUE';
      NO_DIR_CHECK='TRUE';
      ALLOW_CONNECT='TRUE';
    'VSS_BG15':
      PIN_NUMBER='(0,0,0,0,0,0,0,0,0,0,0,0,0,0,0,0,0,0,0,0,0,0,0,0,0,0,0,0,0,0,0~
,0,BG15,0,0,0,0,0,0,0)';
      PINUSE='POWER';
      NO_LOAD_CHECK='Both';
      NO_IO_CHECK='Both';
      NO_ASSERT_CHECK='TRUE';
      NO_DIR_CHECK='TRUE';
      ALLOW_CONNECT='TRUE';
    'VSS_BG18':
      PIN_NUMBER='(0,0,0,0,0,0,0,0,0,0,0,0,0,0,0,0,0,0,0,0,0,0,0,0,0,0,0,0,0,0,0~
,0,BG18,0,0,0,0,0,0,0)';
      PINUSE='POWER';
      NO_LOAD_CHECK='Both';
      NO_IO_CHECK='Both';
      NO_ASSERT_CHECK='TRUE';
      NO_DIR_CHECK='TRUE';
      ALLOW_CONNECT='TRUE';
    'VSS_BG20':
      PIN_NUMBER='(0,0,0,0,0,0,0,0,0,0,0,0,0,0,0,0,0,0,0,0,0,0,0,0,0,0,0,0,0,0,0~
,0,BG20,0,0,0,0,0,0,0)';
      PINUSE='POWER';
      NO_LOAD_CHECK='Both';
      NO_IO_CHECK='Both';
      NO_ASSERT_CHECK='TRUE';
      NO_DIR_CHECK='TRUE';
      ALLOW_CONNECT='TRUE';
    'VSS_BG23':
      PIN_NUMBER='(0,0,0,0,0,0,0,0,0,0,0,0,0,0,0,0,0,0,0,0,0,0,0,0,0,0,0,0,0,0,0~
,0,BG23,0,0,0,0,0,0,0)';
      PINUSE='POWER';
      NO_LOAD_CHECK='Both';
      NO_IO_CHECK='Both';
      NO_ASSERT_CHECK='TRUE';
      NO_DIR_CHECK='TRUE';
      ALLOW_CONNECT='TRUE';
    'VSS_BG25':
      PIN_NUMBER='(0,0,0,0,0,0,0,0,0,0,0,0,0,0,0,0,0,0,0,0,0,0,0,0,0,0,0,0,0,0,0~
,0,BG25,0,0,0,0,0,0,0)';
      PINUSE='POWER';
      NO_LOAD_CHECK='Both';
      NO_IO_CHECK='Both';
      NO_ASSERT_CHECK='TRUE';
      NO_DIR_CHECK='TRUE';
      ALLOW_CONNECT='TRUE';
    'VSS_BG27':
      PIN_NUMBER='(0,0,0,0,0,0,0,0,0,0,0,0,0,0,0,0,0,0,0,0,0,0,0,0,0,0,0,0,0,0,0~
,0,BG27,0,0,0,0,0,0,0)';
      PINUSE='POWER';
      NO_LOAD_CHECK='Both';
      NO_IO_CHECK='Both';
      NO_ASSERT_CHECK='TRUE';
      NO_DIR_CHECK='TRUE';
      ALLOW_CONNECT='TRUE';
    'VSS_BG49':
      PIN_NUMBER='(0,0,0,0,0,0,0,0,0,0,0,0,0,0,0,0,0,0,0,0,0,0,0,0,0,0,0,0,0,0,0~
,0,BG49,0,0,0,0,0,0,0)';
      PINUSE='POWER';
      NO_LOAD_CHECK='Both';
      NO_IO_CHECK='Both';
      NO_ASSERT_CHECK='TRUE';
      NO_DIR_CHECK='TRUE';
      ALLOW_CONNECT='TRUE';
    'VSS_BG51':
      PIN_NUMBER='(0,0,0,0,0,0,0,0,0,0,0,0,0,0,0,0,0,0,0,0,0,0,0,0,0,0,0,0,0,0,0~
,0,BG51,0,0,0,0,0,0,0)';
      PINUSE='POWER';
      NO_LOAD_CHECK='Both';
      NO_IO_CHECK='Both';
      NO_ASSERT_CHECK='TRUE';
      NO_DIR_CHECK='TRUE';
      ALLOW_CONNECT='TRUE';
    'VSS_BG53':
      PIN_NUMBER='(0,0,0,0,0,0,0,0,0,0,0,0,0,0,0,0,0,0,0,0,0,0,0,0,0,0,0,0,0,0,0~
,0,BG53,0,0,0,0,0,0,0)';
      PINUSE='POWER';
      NO_LOAD_CHECK='Both';
      NO_IO_CHECK='Both';
      NO_ASSERT_CHECK='TRUE';
      NO_DIR_CHECK='TRUE';
      ALLOW_CONNECT='TRUE';
    'VSS_BG56':
      PIN_NUMBER='(0,0,0,0,0,0,0,0,0,0,0,0,0,0,0,0,0,0,0,0,0,0,0,0,0,0,0,0,0,0,0~
,0,BG56,0,0,0,0,0,0,0)';
      PINUSE='POWER';
      NO_LOAD_CHECK='Both';
      NO_IO_CHECK='Both';
      NO_ASSERT_CHECK='TRUE';
      NO_DIR_CHECK='TRUE';
      ALLOW_CONNECT='TRUE';
    'VSS_BG58':
      PIN_NUMBER='(0,0,0,0,0,0,0,0,0,0,0,0,0,0,0,0,0,0,0,0,0,0,0,0,0,0,0,0,0,0,0~
,0,BG58,0,0,0,0,0,0,0)';
      PINUSE='POWER';
      NO_LOAD_CHECK='Both';
      NO_IO_CHECK='Both';
      NO_ASSERT_CHECK='TRUE';
      NO_DIR_CHECK='TRUE';
      ALLOW_CONNECT='TRUE';
    'VSS_BG61':
      PIN_NUMBER='(0,0,0,0,0,0,0,0,0,0,0,0,0,0,0,0,0,0,0,0,0,0,0,0,0,0,0,0,0,0,0~
,0,BG61,0,0,0,0,0,0,0)';
      PINUSE='POWER';
      NO_LOAD_CHECK='Both';
      NO_IO_CHECK='Both';
      NO_ASSERT_CHECK='TRUE';
      NO_DIR_CHECK='TRUE';
      ALLOW_CONNECT='TRUE';
    'VSS_BG63':
      PIN_NUMBER='(0,0,0,0,0,0,0,0,0,0,0,0,0,0,0,0,0,0,0,0,0,0,0,0,0,0,0,0,0,0,0~
,0,BG63,0,0,0,0,0,0,0)';
      PINUSE='POWER';
      NO_LOAD_CHECK='Both';
      NO_IO_CHECK='Both';
      NO_ASSERT_CHECK='TRUE';
      NO_DIR_CHECK='TRUE';
      ALLOW_CONNECT='TRUE';
    'VSS_BG65':
      PIN_NUMBER='(0,0,0,0,0,0,0,0,0,0,0,0,0,0,0,0,0,0,0,0,0,0,0,0,0,0,0,0,0,0,0~
,0,BG65,0,0,0,0,0,0,0)';
      PINUSE='POWER';
      NO_LOAD_CHECK='Both';
      NO_IO_CHECK='Both';
      NO_ASSERT_CHECK='TRUE';
      NO_DIR_CHECK='TRUE';
      ALLOW_CONNECT='TRUE';
    'VSS_BG68':
      PIN_NUMBER='(0,0,0,0,0,0,0,0,0,0,0,0,0,0,0,0,0,0,0,0,0,0,0,0,0,0,0,0,0,0,0~
,0,BG68,0,0,0,0,0,0,0)';
      PINUSE='POWER';
      NO_LOAD_CHECK='Both';
      NO_IO_CHECK='Both';
      NO_ASSERT_CHECK='TRUE';
      NO_DIR_CHECK='TRUE';
      ALLOW_CONNECT='TRUE';
    'VSS_BG70':
      PIN_NUMBER='(0,0,0,0,0,0,0,0,0,0,0,0,0,0,0,0,0,0,0,0,0,0,0,0,0,0,0,0,0,0,0~
,0,BG70,0,0,0,0,0,0,0)';
      PINUSE='POWER';
      NO_LOAD_CHECK='Both';
      NO_IO_CHECK='Both';
      NO_ASSERT_CHECK='TRUE';
      NO_DIR_CHECK='TRUE';
      ALLOW_CONNECT='TRUE';
    'VSS_BG72':
      PIN_NUMBER='(0,0,0,0,0,0,0,0,0,0,0,0,0,0,0,0,0,0,0,0,0,0,0,0,0,0,0,0,0,0,0~
,0,BG72,0,0,0,0,0,0,0)';
      PINUSE='POWER';
      NO_LOAD_CHECK='Both';
      NO_IO_CHECK='Both';
      NO_ASSERT_CHECK='TRUE';
      NO_DIR_CHECK='TRUE';
      ALLOW_CONNECT='TRUE';
    'VSS_BG75':
      PIN_NUMBER='(0,0,0,0,0,0,0,0,0,0,0,0,0,0,0,0,0,0,0,0,0,0,0,0,0,0,0,0,0,0,0~
,0,BG75,0,0,0,0,0,0,0)';
      PINUSE='POWER';
      NO_LOAD_CHECK='Both';
      NO_IO_CHECK='Both';
      NO_ASSERT_CHECK='TRUE';
      NO_DIR_CHECK='TRUE';
      ALLOW_CONNECT='TRUE';
    'VSS_BH3':
      PIN_NUMBER='(0,0,0,0,0,0,0,0,0,0,0,0,0,0,0,0,0,0,0,0,0,0,0,0,0,0,0,0,0,0,0~
,0,BH3,0,0,0,0,0,0,0)';
      PINUSE='POWER';
      NO_LOAD_CHECK='Both';
      NO_IO_CHECK='Both';
      NO_ASSERT_CHECK='TRUE';
      NO_DIR_CHECK='TRUE';
      ALLOW_CONNECT='TRUE';
    'VSS_BH5':
      PIN_NUMBER='(0,0,0,0,0,0,0,0,0,0,0,0,0,0,0,0,0,0,0,0,0,0,0,0,0,0,0,0,0,0,0~
,0,BH5,0,0,0,0,0,0,0)';
      PINUSE='POWER';
      NO_LOAD_CHECK='Both';
      NO_IO_CHECK='Both';
      NO_ASSERT_CHECK='TRUE';
      NO_DIR_CHECK='TRUE';
      ALLOW_CONNECT='TRUE';
    'VSS_BH8':
      PIN_NUMBER='(0,0,0,0,0,0,0,0,0,0,0,0,0,0,0,0,0,0,0,0,0,0,0,0,0,0,0,0,0,0,0~
,0,BH8,0,0,0,0,0,0,0)';
      PINUSE='POWER';
      NO_LOAD_CHECK='Both';
      NO_IO_CHECK='Both';
      NO_ASSERT_CHECK='TRUE';
      NO_DIR_CHECK='TRUE';
      ALLOW_CONNECT='TRUE';
    'VSS_BH10':
      PIN_NUMBER='(0,0,0,0,0,0,0,0,0,0,0,0,0,0,0,0,0,0,0,0,0,0,0,0,0,0,0,0,0,0,0~
,0,BH10,0,0,0,0,0,0,0)';
      PINUSE='POWER';
      NO_LOAD_CHECK='Both';
      NO_IO_CHECK='Both';
      NO_ASSERT_CHECK='TRUE';
      NO_DIR_CHECK='TRUE';
      ALLOW_CONNECT='TRUE';
    'VSS_BH12':
      PIN_NUMBER='(0,0,0,0,0,0,0,0,0,0,0,0,0,0,0,0,0,0,0,0,0,0,0,0,0,0,0,0,0,0,0~
,0,BH12,0,0,0,0,0,0,0)';
      PINUSE='POWER';
      NO_LOAD_CHECK='Both';
      NO_IO_CHECK='Both';
      NO_ASSERT_CHECK='TRUE';
      NO_DIR_CHECK='TRUE';
      ALLOW_CONNECT='TRUE';
    'VSS_BH15':
      PIN_NUMBER='(0,0,0,0,0,0,0,0,0,0,0,0,0,0,0,0,0,0,0,0,0,0,0,0,0,0,0,0,0,0,0~
,0,BH15,0,0,0,0,0,0,0)';
      PINUSE='POWER';
      NO_LOAD_CHECK='Both';
      NO_IO_CHECK='Both';
      NO_ASSERT_CHECK='TRUE';
      NO_DIR_CHECK='TRUE';
      ALLOW_CONNECT='TRUE';
    'VSS_BH17':
      PIN_NUMBER='(0,0,0,0,0,0,0,0,0,0,0,0,0,0,0,0,0,0,0,0,0,0,0,0,0,0,0,0,0,0,0~
,0,BH17,0,0,0,0,0,0,0)';
      PINUSE='POWER';
      NO_LOAD_CHECK='Both';
      NO_IO_CHECK='Both';
      NO_ASSERT_CHECK='TRUE';
      NO_DIR_CHECK='TRUE';
      ALLOW_CONNECT='TRUE';
    'VSS_BH19':
      PIN_NUMBER='(0,0,0,0,0,0,0,0,0,0,0,0,0,0,0,0,0,0,0,0,0,0,0,0,0,0,0,0,0,0,0~
,0,BH19,0,0,0,0,0,0,0)';
      PINUSE='POWER';
      NO_LOAD_CHECK='Both';
      NO_IO_CHECK='Both';
      NO_ASSERT_CHECK='TRUE';
      NO_DIR_CHECK='TRUE';
      ALLOW_CONNECT='TRUE';
    'VSS_BH22':
      PIN_NUMBER='(0,0,0,0,0,0,0,0,0,0,0,0,0,0,0,0,0,0,0,0,0,0,0,0,0,0,0,0,0,0,0~
,0,BH22,0,0,0,0,0,0,0)';
      PINUSE='POWER';
      NO_LOAD_CHECK='Both';
      NO_IO_CHECK='Both';
      NO_ASSERT_CHECK='TRUE';
      NO_DIR_CHECK='TRUE';
      ALLOW_CONNECT='TRUE';
    'VSS_BH24':
      PIN_NUMBER='(0,0,0,0,0,0,0,0,0,0,0,0,0,0,0,0,0,0,0,0,0,0,0,0,0,0,0,0,0,0,0~
,0,BH24,0,0,0,0,0,0,0)';
      PINUSE='POWER';
      NO_LOAD_CHECK='Both';
      NO_IO_CHECK='Both';
      NO_ASSERT_CHECK='TRUE';
      NO_DIR_CHECK='TRUE';
      ALLOW_CONNECT='TRUE';
    'VSS_BH26':
      PIN_NUMBER='(0,0,0,0,0,0,0,0,0,0,0,0,0,0,0,0,0,0,0,0,0,0,0,0,0,0,0,0,0,0,0~
,0,BH26,0,0,0,0,0,0,0)';
      PINUSE='POWER';
      NO_LOAD_CHECK='Both';
      NO_IO_CHECK='Both';
      NO_ASSERT_CHECK='TRUE';
      NO_DIR_CHECK='TRUE';
      ALLOW_CONNECT='TRUE';
    'VSS_BH28':
      PIN_NUMBER='(0,0,0,0,0,0,0,0,0,0,0,0,0,0,0,0,0,0,0,0,0,0,0,0,0,0,0,0,0,0,0~
,0,BH28,0,0,0,0,0,0,0)';
      PINUSE='POWER';
      NO_LOAD_CHECK='Both';
      NO_IO_CHECK='Both';
      NO_ASSERT_CHECK='TRUE';
      NO_DIR_CHECK='TRUE';
      ALLOW_CONNECT='TRUE';
    'VSS_BH49':
      PIN_NUMBER='(0,0,0,0,0,0,0,0,0,0,0,0,0,0,0,0,0,0,0,0,0,0,0,0,0,0,0,0,0,0,0~
,0,BH49,0,0,0,0,0,0,0)';
      PINUSE='POWER';
      NO_LOAD_CHECK='Both';
      NO_IO_CHECK='Both';
      NO_ASSERT_CHECK='TRUE';
      NO_DIR_CHECK='TRUE';
      ALLOW_CONNECT='TRUE';
    'VSS_BH50':
      PIN_NUMBER='(0,0,0,0,0,0,0,0,0,0,0,0,0,0,0,0,0,0,0,0,0,0,0,0,0,0,0,0,0,0,0~
,0,BH50,0,0,0,0,0,0,0)';
      PINUSE='POWER';
      NO_LOAD_CHECK='Both';
      NO_IO_CHECK='Both';
      NO_ASSERT_CHECK='TRUE';
      NO_DIR_CHECK='TRUE';
      ALLOW_CONNECT='TRUE';
    'VSS_BH52':
      PIN_NUMBER='(0,0,0,0,0,0,0,0,0,0,0,0,0,0,0,0,0,0,0,0,0,0,0,0,0,0,0,0,0,0,0~
,0,BH52,0,0,0,0,0,0,0)';
      PINUSE='POWER';
      NO_LOAD_CHECK='Both';
      NO_IO_CHECK='Both';
      NO_ASSERT_CHECK='TRUE';
      NO_DIR_CHECK='TRUE';
      ALLOW_CONNECT='TRUE';
    'VSS_BH54':
      PIN_NUMBER='(0,0,0,0,0,0,0,0,0,0,0,0,0,0,0,0,0,0,0,0,0,0,0,0,0,0,0,0,0,0,0~
,0,BH54,0,0,0,0,0,0,0)';
      PINUSE='POWER';
      NO_LOAD_CHECK='Both';
      NO_IO_CHECK='Both';
      NO_ASSERT_CHECK='TRUE';
      NO_DIR_CHECK='TRUE';
      ALLOW_CONNECT='TRUE';
    'VSS_BH57':
      PIN_NUMBER='(0,0,0,0,0,0,0,0,0,0,0,0,0,0,0,0,0,0,0,0,0,0,0,0,0,0,0,0,0,0,0~
,0,BH57,0,0,0,0,0,0,0)';
      PINUSE='POWER';
      NO_LOAD_CHECK='Both';
      NO_IO_CHECK='Both';
      NO_ASSERT_CHECK='TRUE';
      NO_DIR_CHECK='TRUE';
      ALLOW_CONNECT='TRUE';
    'VSS_BH59':
      PIN_NUMBER='(0,0,0,0,0,0,0,0,0,0,0,0,0,0,0,0,0,0,0,0,0,0,0,0,0,0,0,0,0,0,0~
,0,BH59,0,0,0,0,0,0,0)';
      PINUSE='POWER';
      NO_LOAD_CHECK='Both';
      NO_IO_CHECK='Both';
      NO_ASSERT_CHECK='TRUE';
      NO_DIR_CHECK='TRUE';
      ALLOW_CONNECT='TRUE';
    'VSS_BH61':
      PIN_NUMBER='(0,0,0,0,0,0,0,0,0,0,0,0,0,0,0,0,0,0,0,0,0,0,0,0,0,0,0,0,0,0,0~
,0,BH61,0,0,0,0,0,0,0)';
      PINUSE='POWER';
      NO_LOAD_CHECK='Both';
      NO_IO_CHECK='Both';
      NO_ASSERT_CHECK='TRUE';
      NO_DIR_CHECK='TRUE';
      ALLOW_CONNECT='TRUE';
    'VSS_BH64':
      PIN_NUMBER='(0,0,0,0,0,0,0,0,0,0,0,0,0,0,0,0,0,0,0,0,0,0,0,0,0,0,0,0,0,0,0~
,0,BH64,0,0,0,0,0,0,0)';
      PINUSE='POWER';
      NO_LOAD_CHECK='Both';
      NO_IO_CHECK='Both';
      NO_ASSERT_CHECK='TRUE';
      NO_DIR_CHECK='TRUE';
      ALLOW_CONNECT='TRUE';
    'VSS_BH66':
      PIN_NUMBER='(0,0,0,0,0,0,0,0,0,0,0,0,0,0,0,0,0,0,0,0,0,0,0,0,0,0,0,0,0,0,0~
,0,BH66,0,0,0,0,0,0,0)';
      PINUSE='POWER';
      NO_LOAD_CHECK='Both';
      NO_IO_CHECK='Both';
      NO_ASSERT_CHECK='TRUE';
      NO_DIR_CHECK='TRUE';
      ALLOW_CONNECT='TRUE';
    'VSS_BH68':
      PIN_NUMBER='(0,0,0,0,0,0,0,0,0,0,0,0,0,0,0,0,0,0,0,0,0,0,0,0,0,0,0,0,0,0,0~
,0,BH68,0,0,0,0,0,0,0)';
      PINUSE='POWER';
      NO_LOAD_CHECK='Both';
      NO_IO_CHECK='Both';
      NO_ASSERT_CHECK='TRUE';
      NO_DIR_CHECK='TRUE';
      ALLOW_CONNECT='TRUE';
    'VSS_BH71':
      PIN_NUMBER='(0,0,0,0,0,0,0,0,0,0,0,0,0,0,0,0,0,0,0,0,0,0,0,0,0,0,0,0,0,0,0~
,0,BH71,0,0,0,0,0,0,0)';
      PINUSE='POWER';
      NO_LOAD_CHECK='Both';
      NO_IO_CHECK='Both';
      NO_ASSERT_CHECK='TRUE';
      NO_DIR_CHECK='TRUE';
      ALLOW_CONNECT='TRUE';
    'VSS_BH73':
      PIN_NUMBER='(0,0,0,0,0,0,0,0,0,0,0,0,0,0,0,0,0,0,0,0,0,0,0,0,0,0,0,0,0,0,0~
,0,BH73,0,0,0,0,0,0,0)';
      PINUSE='POWER';
      NO_LOAD_CHECK='Both';
      NO_IO_CHECK='Both';
      NO_ASSERT_CHECK='TRUE';
      NO_DIR_CHECK='TRUE';
      ALLOW_CONNECT='TRUE';
    'VSS_BJ1':
      PIN_NUMBER='(0,0,0,0,0,0,0,0,0,0,0,0,0,0,0,0,0,0,0,0,0,0,0,0,0,0,0,0,0,0,0~
,0,BJ1,0,0,0,0,0,0,0)';
      PINUSE='POWER';
      NO_LOAD_CHECK='Both';
      NO_IO_CHECK='Both';
      NO_ASSERT_CHECK='TRUE';
      NO_DIR_CHECK='TRUE';
      ALLOW_CONNECT='TRUE';
    'VSS_BJ6':
      PIN_NUMBER='(0,0,0,0,0,0,0,0,0,0,0,0,0,0,0,0,0,0,0,0,0,0,0,0,0,0,0,0,0,0,0~
,0,BJ6,0,0,0,0,0,0,0)';
      PINUSE='POWER';
      NO_LOAD_CHECK='Both';
      NO_IO_CHECK='Both';
      NO_ASSERT_CHECK='TRUE';
      NO_DIR_CHECK='TRUE';
      ALLOW_CONNECT='TRUE';
    'VSS_BJ8':
      PIN_NUMBER='(0,0,0,0,0,0,0,0,0,0,0,0,0,0,0,0,0,0,0,0,0,0,0,0,0,0,0,0,0,0,0~
,0,BJ8,0,0,0,0,0,0,0)';
      PINUSE='POWER';
      NO_LOAD_CHECK='Both';
      NO_IO_CHECK='Both';
      NO_ASSERT_CHECK='TRUE';
      NO_DIR_CHECK='TRUE';
      ALLOW_CONNECT='TRUE';
    'VSS_BJ13':
      PIN_NUMBER='(0,0,0,0,0,0,0,0,0,0,0,0,0,0,0,0,0,0,0,0,0,0,0,0,0,0,0,0,0,0,0~
,0,BJ13,0,0,0,0,0,0,0)';
      PINUSE='POWER';
      NO_LOAD_CHECK='Both';
      NO_IO_CHECK='Both';
      NO_ASSERT_CHECK='TRUE';
      NO_DIR_CHECK='TRUE';
      ALLOW_CONNECT='TRUE';
    'VSS_BJ15':
      PIN_NUMBER='(0,0,0,0,0,0,0,0,0,0,0,0,0,0,0,0,0,0,0,0,0,0,0,0,0,0,0,0,0,0,0~
,0,BJ15,0,0,0,0,0,0,0)';
      PINUSE='POWER';
      NO_LOAD_CHECK='Both';
      NO_IO_CHECK='Both';
      NO_ASSERT_CHECK='TRUE';
      NO_DIR_CHECK='TRUE';
      ALLOW_CONNECT='TRUE';
    'VSS_BJ20':
      PIN_NUMBER='(0,0,0,0,0,0,0,0,0,0,0,0,0,0,0,0,0,0,0,0,0,0,0,0,0,0,0,0,0,0,0~
,0,BJ20,0,0,0,0,0,0,0)';
      PINUSE='POWER';
      NO_LOAD_CHECK='Both';
      NO_IO_CHECK='Both';
      NO_ASSERT_CHECK='TRUE';
      NO_DIR_CHECK='TRUE';
      ALLOW_CONNECT='TRUE';
    'VSS_BJ22':
      PIN_NUMBER='(0,0,0,0,0,0,0,0,0,0,0,0,0,0,0,0,0,0,0,0,0,0,0,0,0,0,0,0,0,0,0~
,0,BJ22,0,0,0,0,0,0,0)';
      PINUSE='POWER';
      NO_LOAD_CHECK='Both';
      NO_IO_CHECK='Both';
      NO_ASSERT_CHECK='TRUE';
      NO_DIR_CHECK='TRUE';
      ALLOW_CONNECT='TRUE';
    'VSS_BJ24':
      PIN_NUMBER='(0,0,0,0,0,0,0,0,0,0,0,0,0,0,0,0,0,0,0,0,0,0,0,0,0,0,0,0,0,0,0~
,0,BJ24,0,0,0,0,0,0,0)';
      PINUSE='POWER';
      NO_LOAD_CHECK='Both';
      NO_IO_CHECK='Both';
      NO_ASSERT_CHECK='TRUE';
      NO_DIR_CHECK='TRUE';
      ALLOW_CONNECT='TRUE';
    'VSS_BJ26':
      PIN_NUMBER='(0,0,0,0,0,0,0,0,0,0,0,0,0,0,0,0,0,0,0,0,0,0,0,0,0,0,0,0,0,0,0~
,0,BJ26,0,0,0,0,0,0,0)';
      PINUSE='POWER';
      NO_LOAD_CHECK='Both';
      NO_IO_CHECK='Both';
      NO_ASSERT_CHECK='TRUE';
      NO_DIR_CHECK='TRUE';
      ALLOW_CONNECT='TRUE';
    'VSS_BJ28':
      PIN_NUMBER='(0,0,0,0,0,0,0,0,0,0,0,0,0,0,0,0,0,0,0,0,0,0,0,0,0,0,0,0,0,0,0~
,0,BJ28,0,0,0,0,0,0,0)';
      PINUSE='POWER';
      NO_LOAD_CHECK='Both';
      NO_IO_CHECK='Both';
      NO_ASSERT_CHECK='TRUE';
      NO_DIR_CHECK='TRUE';
      ALLOW_CONNECT='TRUE';
    'VSS_BJ49':
      PIN_NUMBER='(0,0,0,0,0,0,0,0,0,0,0,0,0,0,0,0,0,0,0,0,0,0,0,0,0,0,0,0,0,0,0~
,0,BJ49,0,0,0,0,0,0,0)';
      PINUSE='POWER';
      NO_LOAD_CHECK='Both';
      NO_IO_CHECK='Both';
      NO_ASSERT_CHECK='TRUE';
      NO_DIR_CHECK='TRUE';
      ALLOW_CONNECT='TRUE';
    'VSS_BJ51':
      PIN_NUMBER='(0,0,0,0,0,0,0,0,0,0,0,0,0,0,0,0,0,0,0,0,0,0,0,0,0,0,0,0,0,0,0~
,0,BJ51,0,0,0,0,0,0,0)';
      PINUSE='POWER';
      NO_LOAD_CHECK='Both';
      NO_IO_CHECK='Both';
      NO_ASSERT_CHECK='TRUE';
      NO_DIR_CHECK='TRUE';
      ALLOW_CONNECT='TRUE';
    'VSS_BJ53':
      PIN_NUMBER='(0,0,0,0,0,0,0,0,0,0,0,0,0,0,0,0,0,0,0,0,0,0,0,0,0,0,0,0,0,0,0~
,0,BJ53,0,0,0,0,0,0,0)';
      PINUSE='POWER';
      NO_LOAD_CHECK='Both';
      NO_IO_CHECK='Both';
      NO_ASSERT_CHECK='TRUE';
      NO_DIR_CHECK='TRUE';
      ALLOW_CONNECT='TRUE';
    'VSS_BJ56':
      PIN_NUMBER='(0,0,0,0,0,0,0,0,0,0,0,0,0,0,0,0,0,0,0,0,0,0,0,0,0,0,0,0,0,0,0~
,0,BJ56,0,0,0,0,0,0,0)';
      PINUSE='POWER';
      NO_LOAD_CHECK='Both';
      NO_IO_CHECK='Both';
      NO_ASSERT_CHECK='TRUE';
      NO_DIR_CHECK='TRUE';
      ALLOW_CONNECT='TRUE';
    'VSS_BJ61':
      PIN_NUMBER='(0,0,0,0,0,0,0,0,0,0,0,0,0,0,0,0,0,0,0,0,0,0,0,0,0,0,0,0,0,0,0~
,0,BJ61,0,0,0,0,0,0,0)';
      PINUSE='POWER';
      NO_LOAD_CHECK='Both';
      NO_IO_CHECK='Both';
      NO_ASSERT_CHECK='TRUE';
      NO_DIR_CHECK='TRUE';
      ALLOW_CONNECT='TRUE';
    'VSS_BJ63':
      PIN_NUMBER='(0,0,0,0,0,0,0,0,0,0,0,0,0,0,0,0,0,0,0,0,0,0,0,0,0,0,0,0,0,0,0~
,0,BJ63,0,0,0,0,0,0,0)';
      PINUSE='POWER';
      NO_LOAD_CHECK='Both';
      NO_IO_CHECK='Both';
      NO_ASSERT_CHECK='TRUE';
      NO_DIR_CHECK='TRUE';
      ALLOW_CONNECT='TRUE';
    'VSS_BJ68':
      PIN_NUMBER='(0,0,0,0,0,0,0,0,0,0,0,0,0,0,0,0,0,0,0,0,0,0,0,0,0,0,0,0,0,0,0~
,0,BJ68,0,0,0,0,0,0,0)';
      PINUSE='POWER';
      NO_LOAD_CHECK='Both';
      NO_IO_CHECK='Both';
      NO_ASSERT_CHECK='TRUE';
      NO_DIR_CHECK='TRUE';
      ALLOW_CONNECT='TRUE';
    'VSS_BJ70':
      PIN_NUMBER='(0,0,0,0,0,0,0,0,0,0,0,0,0,0,0,0,0,0,0,0,0,0,0,0,0,0,0,0,0,0,0~
,0,BJ70,0,0,0,0,0,0,0)';
      PINUSE='POWER';
      NO_LOAD_CHECK='Both';
      NO_IO_CHECK='Both';
      NO_ASSERT_CHECK='TRUE';
      NO_DIR_CHECK='TRUE';
      ALLOW_CONNECT='TRUE';
    'VSS_BJ75':
      PIN_NUMBER='(0,0,0,0,0,0,0,0,0,0,0,0,0,0,0,0,0,0,0,0,0,0,0,0,0,0,0,0,0,0,0~
,0,BJ75,0,0,0,0,0,0,0)';
      PINUSE='POWER';
      NO_LOAD_CHECK='Both';
      NO_IO_CHECK='Both';
      NO_ASSERT_CHECK='TRUE';
      NO_DIR_CHECK='TRUE';
      ALLOW_CONNECT='TRUE';
    'VSS_BK3':
      PIN_NUMBER='(0,0,0,0,0,0,0,0,0,0,0,0,0,0,0,0,0,0,0,0,0,0,0,0,0,0,0,0,0,0,0~
,0,BK3,0,0,0,0,0,0,0)';
      PINUSE='POWER';
      NO_LOAD_CHECK='Both';
      NO_IO_CHECK='Both';
      NO_ASSERT_CHECK='TRUE';
      NO_DIR_CHECK='TRUE';
      ALLOW_CONNECT='TRUE';
    'VSS_BK5':
      PIN_NUMBER='(0,0,0,0,0,0,0,0,0,0,0,0,0,0,0,0,0,0,0,0,0,0,0,0,0,0,0,0,0,0,0~
,0,BK5,0,0,0,0,0,0,0)';
      PINUSE='POWER';
      NO_LOAD_CHECK='Both';
      NO_IO_CHECK='Both';
      NO_ASSERT_CHECK='TRUE';
      NO_DIR_CHECK='TRUE';
      ALLOW_CONNECT='TRUE';
    'VSS_BK8':
      PIN_NUMBER='(0,0,0,0,0,0,0,0,0,0,0,0,0,0,0,0,0,0,0,0,0,0,0,0,0,0,0,0,0,0,0~
,0,BK8,0,0,0,0,0,0,0)';
      PINUSE='POWER';
      NO_LOAD_CHECK='Both';
      NO_IO_CHECK='Both';
      NO_ASSERT_CHECK='TRUE';
      NO_DIR_CHECK='TRUE';
      ALLOW_CONNECT='TRUE';
    'VSS_BK10':
      PIN_NUMBER='(0,0,0,0,0,0,0,0,0,0,0,0,0,0,0,0,0,0,0,0,0,0,0,0,0,0,0,0,0,0,0~
,0,BK10,0,0,0,0,0,0,0)';
      PINUSE='POWER';
      NO_LOAD_CHECK='Both';
      NO_IO_CHECK='Both';
      NO_ASSERT_CHECK='TRUE';
      NO_DIR_CHECK='TRUE';
      ALLOW_CONNECT='TRUE';
    'VSS_BK12':
      PIN_NUMBER='(0,0,0,0,0,0,0,0,0,0,0,0,0,0,0,0,0,0,0,0,0,0,0,0,0,0,0,0,0,0,0~
,0,BK12,0,0,0,0,0,0,0)';
      PINUSE='POWER';
      NO_LOAD_CHECK='Both';
      NO_IO_CHECK='Both';
      NO_ASSERT_CHECK='TRUE';
      NO_DIR_CHECK='TRUE';
      ALLOW_CONNECT='TRUE';
    'VSS_BK15':
      PIN_NUMBER='(0,0,0,0,0,0,0,0,0,0,0,0,0,0,0,0,0,0,0,0,0,0,0,0,0,0,0,0,0,0,0~
,0,BK15,0,0,0,0,0,0,0)';
      PINUSE='POWER';
      NO_LOAD_CHECK='Both';
      NO_IO_CHECK='Both';
      NO_ASSERT_CHECK='TRUE';
      NO_DIR_CHECK='TRUE';
      ALLOW_CONNECT='TRUE';
    'VSS_BK17':
      PIN_NUMBER='(0,0,0,0,0,0,0,0,0,0,0,0,0,0,0,0,0,0,0,0,0,0,0,0,0,0,0,0,0,0,0~
,0,BK17,0,0,0,0,0,0,0)';
      PINUSE='POWER';
      NO_LOAD_CHECK='Both';
      NO_IO_CHECK='Both';
      NO_ASSERT_CHECK='TRUE';
      NO_DIR_CHECK='TRUE';
      ALLOW_CONNECT='TRUE';
    'VSS_BK19':
      PIN_NUMBER='(0,0,0,0,0,0,0,0,0,0,0,0,0,0,0,0,0,0,0,0,0,0,0,0,0,0,0,0,0,0,0~
,0,BK19,0,0,0,0,0,0,0)';
      PINUSE='POWER';
      NO_LOAD_CHECK='Both';
      NO_IO_CHECK='Both';
      NO_ASSERT_CHECK='TRUE';
      NO_DIR_CHECK='TRUE';
      ALLOW_CONNECT='TRUE';
    'VSS_BK23':
      PIN_NUMBER='(0,0,0,0,0,0,0,0,0,0,0,0,0,0,0,0,0,0,0,0,0,0,0,0,0,0,0,0,0,0,0~
,0,BK23,0,0,0,0,0,0,0)';
      PINUSE='POWER';
      NO_LOAD_CHECK='Both';
      NO_IO_CHECK='Both';
      NO_ASSERT_CHECK='TRUE';
      NO_DIR_CHECK='TRUE';
      ALLOW_CONNECT='TRUE';
    'VSS_BK25':
      PIN_NUMBER='(0,0,0,0,0,0,0,0,0,0,0,0,0,0,0,0,0,0,0,0,0,0,0,0,0,0,0,0,0,0,0~
,0,BK25,0,0,0,0,0,0,0)';
      PINUSE='POWER';
      NO_LOAD_CHECK='Both';
      NO_IO_CHECK='Both';
      NO_ASSERT_CHECK='TRUE';
      NO_DIR_CHECK='TRUE';
      ALLOW_CONNECT='TRUE';
    'VSS_BK27':
      PIN_NUMBER='(0,0,0,0,0,0,0,0,0,0,0,0,0,0,0,0,0,0,0,0,0,0,0,0,0,0,0,0,0,0,0~
,0,BK27,0,0,0,0,0,0,0)';
      PINUSE='POWER';
      NO_LOAD_CHECK='Both';
      NO_IO_CHECK='Both';
      NO_ASSERT_CHECK='TRUE';
      NO_DIR_CHECK='TRUE';
      ALLOW_CONNECT='TRUE';
    'VSS_BK48':
      PIN_NUMBER='(0,0,0,0,0,0,0,0,0,0,0,0,0,0,0,0,0,0,0,0,0,0,0,0,0,0,0,0,0,0,0~
,0,BK48,0,0,0,0,0,0,0)';
      PINUSE='POWER';
      NO_LOAD_CHECK='Both';
      NO_IO_CHECK='Both';
      NO_ASSERT_CHECK='TRUE';
      NO_DIR_CHECK='TRUE';
      ALLOW_CONNECT='TRUE';
    'VSS_BK50':
      PIN_NUMBER='(0,0,0,0,0,0,0,0,0,0,0,0,0,0,0,0,0,0,0,0,0,0,0,0,0,0,0,0,0,0,0~
,0,BK50,0,0,0,0,0,0,0)';
      PINUSE='POWER';
      NO_LOAD_CHECK='Both';
      NO_IO_CHECK='Both';
      NO_ASSERT_CHECK='TRUE';
      NO_DIR_CHECK='TRUE';
      ALLOW_CONNECT='TRUE';
    'VSS_BK52':
      PIN_NUMBER='(0,0,0,0,0,0,0,0,0,0,0,0,0,0,0,0,0,0,0,0,0,0,0,0,0,0,0,0,0,0,0~
,0,BK52,0,0,0,0,0,0,0)';
      PINUSE='POWER';
      NO_LOAD_CHECK='Both';
      NO_IO_CHECK='Both';
      NO_ASSERT_CHECK='TRUE';
      NO_DIR_CHECK='TRUE';
      ALLOW_CONNECT='TRUE';
    'VSS_BK54':
      PIN_NUMBER='(0,0,0,0,0,0,0,0,0,0,0,0,0,0,0,0,0,0,0,0,0,0,0,0,0,0,0,0,0,0,0~
,0,BK54,0,0,0,0,0,0,0)';
      PINUSE='POWER';
      NO_LOAD_CHECK='Both';
      NO_IO_CHECK='Both';
      NO_ASSERT_CHECK='TRUE';
      NO_DIR_CHECK='TRUE';
      ALLOW_CONNECT='TRUE';
    'VSS_BK57':
      PIN_NUMBER='(0,0,0,0,0,0,0,0,0,0,0,0,0,0,0,0,0,0,0,0,0,0,0,0,0,0,0,0,0,0,0~
,0,BK57,0,0,0,0,0,0,0)';
      PINUSE='POWER';
      NO_LOAD_CHECK='Both';
      NO_IO_CHECK='Both';
      NO_ASSERT_CHECK='TRUE';
      NO_DIR_CHECK='TRUE';
      ALLOW_CONNECT='TRUE';
    'VSS_BK59':
      PIN_NUMBER='(0,0,0,0,0,0,0,0,0,0,0,0,0,0,0,0,0,0,0,0,0,0,0,0,0,0,0,0,0,0,0~
,0,BK59,0,0,0,0,0,0,0)';
      PINUSE='POWER';
      NO_LOAD_CHECK='Both';
      NO_IO_CHECK='Both';
      NO_ASSERT_CHECK='TRUE';
      NO_DIR_CHECK='TRUE';
      ALLOW_CONNECT='TRUE';
    'VSS_BK61':
      PIN_NUMBER='(0,0,0,0,0,0,0,0,0,0,0,0,0,0,0,0,0,0,0,0,0,0,0,0,0,0,0,0,0,0,0~
,0,BK61,0,0,0,0,0,0,0)';
      PINUSE='POWER';
      NO_LOAD_CHECK='Both';
      NO_IO_CHECK='Both';
      NO_ASSERT_CHECK='TRUE';
      NO_DIR_CHECK='TRUE';
      ALLOW_CONNECT='TRUE';
    'VSS_BK64':
      PIN_NUMBER='(0,0,0,0,0,0,0,0,0,0,0,0,0,0,0,0,0,0,0,0,0,0,0,0,0,0,0,0,0,0,0~
,0,BK64,0,0,0,0,0,0,0)';
      PINUSE='POWER';
      NO_LOAD_CHECK='Both';
      NO_IO_CHECK='Both';
      NO_ASSERT_CHECK='TRUE';
      NO_DIR_CHECK='TRUE';
      ALLOW_CONNECT='TRUE';
    'VSS_BK66':
      PIN_NUMBER='(0,0,0,0,0,0,0,0,0,0,0,0,0,0,0,0,0,0,0,0,0,0,0,0,0,0,0,0,0,0,0~
,0,BK66,0,0,0,0,0,0,0)';
      PINUSE='POWER';
      NO_LOAD_CHECK='Both';
      NO_IO_CHECK='Both';
      NO_ASSERT_CHECK='TRUE';
      NO_DIR_CHECK='TRUE';
      ALLOW_CONNECT='TRUE';
    'VSS_BK68':
      PIN_NUMBER='(0,0,0,0,0,0,0,0,0,0,0,0,0,0,0,0,0,0,0,0,0,0,0,0,0,0,0,0,0,0,0~
,0,BK68,0,0,0,0,0,0,0)';
      PINUSE='POWER';
      NO_LOAD_CHECK='Both';
      NO_IO_CHECK='Both';
      NO_ASSERT_CHECK='TRUE';
      NO_DIR_CHECK='TRUE';
      ALLOW_CONNECT='TRUE';
    'VSS_BK71':
      PIN_NUMBER='(0,0,0,0,0,0,0,0,0,0,0,0,0,0,0,0,0,0,0,0,0,0,0,0,0,0,0,0,0,0,0~
,0,BK71,0,0,0,0,0,0,0)';
      PINUSE='POWER';
      NO_LOAD_CHECK='Both';
      NO_IO_CHECK='Both';
      NO_ASSERT_CHECK='TRUE';
      NO_DIR_CHECK='TRUE';
      ALLOW_CONNECT='TRUE';
    'VSS_BK73':
      PIN_NUMBER='(0,0,0,0,0,0,0,0,0,0,0,0,0,0,0,0,0,0,0,0,0,0,0,0,0,0,0,0,0,0,0~
,0,BK73,0,0,0,0,0,0,0)';
      PINUSE='POWER';
      NO_LOAD_CHECK='Both';
      NO_IO_CHECK='Both';
      NO_ASSERT_CHECK='TRUE';
      NO_DIR_CHECK='TRUE';
      ALLOW_CONNECT='TRUE';
    'VSS_BL1':
      PIN_NUMBER='(0,0,0,0,0,0,0,0,0,0,0,0,0,0,0,0,0,0,0,0,0,0,0,0,0,0,0,0,0,0,0~
,0,BL1,0,0,0,0,0,0,0)';
      PINUSE='POWER';
      NO_LOAD_CHECK='Both';
      NO_IO_CHECK='Both';
      NO_ASSERT_CHECK='TRUE';
      NO_DIR_CHECK='TRUE';
      ALLOW_CONNECT='TRUE';
    'VSS_BL4':
      PIN_NUMBER='(0,0,0,0,0,0,0,0,0,0,0,0,0,0,0,0,0,0,0,0,0,0,0,0,0,0,0,0,0,0,0~
,0,BL4,0,0,0,0,0,0,0)';
      PINUSE='POWER';
      NO_LOAD_CHECK='Both';
      NO_IO_CHECK='Both';
      NO_ASSERT_CHECK='TRUE';
      NO_DIR_CHECK='TRUE';
      ALLOW_CONNECT='TRUE';
    'VSS_BL6':
      PIN_NUMBER='(0,0,0,0,0,0,0,0,0,0,0,0,0,0,0,0,0,0,0,0,0,0,0,0,0,0,0,0,0,0,0~
,0,BL6,0,0,0,0,0,0,0)';
      PINUSE='POWER';
      NO_LOAD_CHECK='Both';
      NO_IO_CHECK='Both';
      NO_ASSERT_CHECK='TRUE';
      NO_DIR_CHECK='TRUE';
      ALLOW_CONNECT='TRUE';
    'VSS_BL8':
      PIN_NUMBER='(0,0,0,0,0,0,0,0,0,0,0,0,0,0,0,0,0,0,0,0,0,0,0,0,0,0,0,0,0,0,0~
,0,BL8,0,0,0,0,0,0,0)';
      PINUSE='POWER';
      NO_LOAD_CHECK='Both';
      NO_IO_CHECK='Both';
      NO_ASSERT_CHECK='TRUE';
      NO_DIR_CHECK='TRUE';
      ALLOW_CONNECT='TRUE';
    'VSS_BL11':
      PIN_NUMBER='(0,0,0,0,0,0,0,0,0,0,0,0,0,0,0,0,0,0,0,0,0,0,0,0,0,0,0,0,0,0,0~
,0,BL11,0,0,0,0,0,0,0)';
      PINUSE='POWER';
      NO_LOAD_CHECK='Both';
      NO_IO_CHECK='Both';
      NO_ASSERT_CHECK='TRUE';
      NO_DIR_CHECK='TRUE';
      ALLOW_CONNECT='TRUE';
    'VSS_BL13':
      PIN_NUMBER='(0,0,0,0,0,0,0,0,0,0,0,0,0,0,0,0,0,0,0,0,0,0,0,0,0,0,0,0,0,0,0~
,0,BL13,0,0,0,0,0,0,0)';
      PINUSE='POWER';
      NO_LOAD_CHECK='Both';
      NO_IO_CHECK='Both';
      NO_ASSERT_CHECK='TRUE';
      NO_DIR_CHECK='TRUE';
      ALLOW_CONNECT='TRUE';
    'VSS_BL15':
      PIN_NUMBER='(0,0,0,0,0,0,0,0,0,0,0,0,0,0,0,0,0,0,0,0,0,0,0,0,0,0,0,0,0,0,0~
,0,BL15,0,0,0,0,0,0,0)';
      PINUSE='POWER';
      NO_LOAD_CHECK='Both';
      NO_IO_CHECK='Both';
      NO_ASSERT_CHECK='TRUE';
      NO_DIR_CHECK='TRUE';
      ALLOW_CONNECT='TRUE';
    'VSS_BL18':
      PIN_NUMBER='(0,0,0,0,0,0,0,0,0,0,0,0,0,0,0,0,0,0,0,0,0,0,0,0,0,0,0,0,0,0,0~
,0,BL18,0,0,0,0,0,0,0)';
      PINUSE='POWER';
      NO_LOAD_CHECK='Both';
      NO_IO_CHECK='Both';
      NO_ASSERT_CHECK='TRUE';
      NO_DIR_CHECK='TRUE';
      ALLOW_CONNECT='TRUE';
    'VSS_BL20':
      PIN_NUMBER='(0,0,0,0,0,0,0,0,0,0,0,0,0,0,0,0,0,0,0,0,0,0,0,0,0,0,0,0,0,0,0~
,0,BL20,0,0,0,0,0,0,0)';
      PINUSE='POWER';
      NO_LOAD_CHECK='Both';
      NO_IO_CHECK='Both';
      NO_ASSERT_CHECK='TRUE';
      NO_DIR_CHECK='TRUE';
      ALLOW_CONNECT='TRUE';
    'VSS_BL22':
      PIN_NUMBER='(0,0,0,0,0,0,0,0,0,0,0,0,0,0,0,0,0,0,0,0,0,0,0,0,0,0,0,0,0,0,0~
,0,BL22,0,0,0,0,0,0,0)';
      PINUSE='POWER';
      NO_LOAD_CHECK='Both';
      NO_IO_CHECK='Both';
      NO_ASSERT_CHECK='TRUE';
      NO_DIR_CHECK='TRUE';
      ALLOW_CONNECT='TRUE';
    'VSS_BL24':
      PIN_NUMBER='(0,0,0,0,0,0,0,0,0,0,0,0,0,0,0,0,0,0,0,0,0,0,0,0,0,0,0,0,0,0,0~
,0,BL24,0,0,0,0,0,0,0)';
      PINUSE='POWER';
      NO_LOAD_CHECK='Both';
      NO_IO_CHECK='Both';
      NO_ASSERT_CHECK='TRUE';
      NO_DIR_CHECK='TRUE';
      ALLOW_CONNECT='TRUE';
    'VSS_BV37':
      PIN_NUMBER='(0,0,0,0,0,0,0,0,0,0,0,0,0,0,0,0,0,0,0,0,0,0,0,0,0,0,0,0,0,0,0~
,0,0,BV37,0,0,0,0,0,0)';
      PINUSE='POWER';
      NO_LOAD_CHECK='Both';
      NO_IO_CHECK='Both';
      NO_ASSERT_CHECK='TRUE';
      NO_DIR_CHECK='TRUE';
      ALLOW_CONNECT='TRUE';
    'VSS_BL26':
      PIN_NUMBER='(0,0,0,0,0,0,0,0,0,0,0,0,0,0,0,0,0,0,0,0,0,0,0,0,0,0,0,0,0,0,0~
,0,0,BL26,0,0,0,0,0,0)';
      PINUSE='POWER';
      NO_LOAD_CHECK='Both';
      NO_IO_CHECK='Both';
      NO_ASSERT_CHECK='TRUE';
      NO_DIR_CHECK='TRUE';
      ALLOW_CONNECT='TRUE';
    'VSS_BL28':
      PIN_NUMBER='(0,0,0,0,0,0,0,0,0,0,0,0,0,0,0,0,0,0,0,0,0,0,0,0,0,0,0,0,0,0,0~
,0,0,BL28,0,0,0,0,0,0)';
      PINUSE='POWER';
      NO_LOAD_CHECK='Both';
      NO_IO_CHECK='Both';
      NO_ASSERT_CHECK='TRUE';
      NO_DIR_CHECK='TRUE';
      ALLOW_CONNECT='TRUE';
    'VSS_BL49':
      PIN_NUMBER='(0,0,0,0,0,0,0,0,0,0,0,0,0,0,0,0,0,0,0,0,0,0,0,0,0,0,0,0,0,0,0~
,0,0,BL49,0,0,0,0,0,0)';
      PINUSE='POWER';
      NO_LOAD_CHECK='Both';
      NO_IO_CHECK='Both';
      NO_ASSERT_CHECK='TRUE';
      NO_DIR_CHECK='TRUE';
      ALLOW_CONNECT='TRUE';
    'VSS_BL51':
      PIN_NUMBER='(0,0,0,0,0,0,0,0,0,0,0,0,0,0,0,0,0,0,0,0,0,0,0,0,0,0,0,0,0,0,0~
,0,0,BL51,0,0,0,0,0,0)';
      PINUSE='POWER';
      NO_LOAD_CHECK='Both';
      NO_IO_CHECK='Both';
      NO_ASSERT_CHECK='TRUE';
      NO_DIR_CHECK='TRUE';
      ALLOW_CONNECT='TRUE';
    'VSS_BL53':
      PIN_NUMBER='(0,0,0,0,0,0,0,0,0,0,0,0,0,0,0,0,0,0,0,0,0,0,0,0,0,0,0,0,0,0,0~
,0,0,BL53,0,0,0,0,0,0)';
      PINUSE='POWER';
      NO_LOAD_CHECK='Both';
      NO_IO_CHECK='Both';
      NO_ASSERT_CHECK='TRUE';
      NO_DIR_CHECK='TRUE';
      ALLOW_CONNECT='TRUE';
    'VSS_BL56':
      PIN_NUMBER='(0,0,0,0,0,0,0,0,0,0,0,0,0,0,0,0,0,0,0,0,0,0,0,0,0,0,0,0,0,0,0~
,0,0,BL56,0,0,0,0,0,0)';
      PINUSE='POWER';
      NO_LOAD_CHECK='Both';
      NO_IO_CHECK='Both';
      NO_ASSERT_CHECK='TRUE';
      NO_DIR_CHECK='TRUE';
      ALLOW_CONNECT='TRUE';
    'VSS_BL58':
      PIN_NUMBER='(0,0,0,0,0,0,0,0,0,0,0,0,0,0,0,0,0,0,0,0,0,0,0,0,0,0,0,0,0,0,0~
,0,0,BL58,0,0,0,0,0,0)';
      PINUSE='POWER';
      NO_LOAD_CHECK='Both';
      NO_IO_CHECK='Both';
      NO_ASSERT_CHECK='TRUE';
      NO_DIR_CHECK='TRUE';
      ALLOW_CONNECT='TRUE';
    'VSS_BL61':
      PIN_NUMBER='(0,0,0,0,0,0,0,0,0,0,0,0,0,0,0,0,0,0,0,0,0,0,0,0,0,0,0,0,0,0,0~
,0,0,BL61,0,0,0,0,0,0)';
      PINUSE='POWER';
      NO_LOAD_CHECK='Both';
      NO_IO_CHECK='Both';
      NO_ASSERT_CHECK='TRUE';
      NO_DIR_CHECK='TRUE';
      ALLOW_CONNECT='TRUE';
    'VSS_BL63':
      PIN_NUMBER='(0,0,0,0,0,0,0,0,0,0,0,0,0,0,0,0,0,0,0,0,0,0,0,0,0,0,0,0,0,0,0~
,0,0,BL63,0,0,0,0,0,0)';
      PINUSE='POWER';
      NO_LOAD_CHECK='Both';
      NO_IO_CHECK='Both';
      NO_ASSERT_CHECK='TRUE';
      NO_DIR_CHECK='TRUE';
      ALLOW_CONNECT='TRUE';
    'VSS_BL65':
      PIN_NUMBER='(0,0,0,0,0,0,0,0,0,0,0,0,0,0,0,0,0,0,0,0,0,0,0,0,0,0,0,0,0,0,0~
,0,0,BL65,0,0,0,0,0,0)';
      PINUSE='POWER';
      NO_LOAD_CHECK='Both';
      NO_IO_CHECK='Both';
      NO_ASSERT_CHECK='TRUE';
      NO_DIR_CHECK='TRUE';
      ALLOW_CONNECT='TRUE';
    'VSS_BL68':
      PIN_NUMBER='(0,0,0,0,0,0,0,0,0,0,0,0,0,0,0,0,0,0,0,0,0,0,0,0,0,0,0,0,0,0,0~
,0,0,BL68,0,0,0,0,0,0)';
      PINUSE='POWER';
      NO_LOAD_CHECK='Both';
      NO_IO_CHECK='Both';
      NO_ASSERT_CHECK='TRUE';
      NO_DIR_CHECK='TRUE';
      ALLOW_CONNECT='TRUE';
    'VSS_BL70':
      PIN_NUMBER='(0,0,0,0,0,0,0,0,0,0,0,0,0,0,0,0,0,0,0,0,0,0,0,0,0,0,0,0,0,0,0~
,0,0,BL70,0,0,0,0,0,0)';
      PINUSE='POWER';
      NO_LOAD_CHECK='Both';
      NO_IO_CHECK='Both';
      NO_ASSERT_CHECK='TRUE';
      NO_DIR_CHECK='TRUE';
      ALLOW_CONNECT='TRUE';
    'VSS_BL72':
      PIN_NUMBER='(0,0,0,0,0,0,0,0,0,0,0,0,0,0,0,0,0,0,0,0,0,0,0,0,0,0,0,0,0,0,0~
,0,0,BL72,0,0,0,0,0,0)';
      PINUSE='POWER';
      NO_LOAD_CHECK='Both';
      NO_IO_CHECK='Both';
      NO_ASSERT_CHECK='TRUE';
      NO_DIR_CHECK='TRUE';
      ALLOW_CONNECT='TRUE';
    'VSS_BL75':
      PIN_NUMBER='(0,0,0,0,0,0,0,0,0,0,0,0,0,0,0,0,0,0,0,0,0,0,0,0,0,0,0,0,0,0,0~
,0,0,BL75,0,0,0,0,0,0)';
      PINUSE='POWER';
      NO_LOAD_CHECK='Both';
      NO_IO_CHECK='Both';
      NO_ASSERT_CHECK='TRUE';
      NO_DIR_CHECK='TRUE';
      ALLOW_CONNECT='TRUE';
    'VSS_BM3':
      PIN_NUMBER='(0,0,0,0,0,0,0,0,0,0,0,0,0,0,0,0,0,0,0,0,0,0,0,0,0,0,0,0,0,0,0~
,0,0,BM3,0,0,0,0,0,0)';
      PINUSE='POWER';
      NO_LOAD_CHECK='Both';
      NO_IO_CHECK='Both';
      NO_ASSERT_CHECK='TRUE';
      NO_DIR_CHECK='TRUE';
      ALLOW_CONNECT='TRUE';
    'VSS_BM8':
      PIN_NUMBER='(0,0,0,0,0,0,0,0,0,0,0,0,0,0,0,0,0,0,0,0,0,0,0,0,0,0,0,0,0,0,0~
,0,0,BM8,0,0,0,0,0,0)';
      PINUSE='POWER';
      NO_LOAD_CHECK='Both';
      NO_IO_CHECK='Both';
      NO_ASSERT_CHECK='TRUE';
      NO_DIR_CHECK='TRUE';
      ALLOW_CONNECT='TRUE';
    'VSS_BM10':
      PIN_NUMBER='(0,0,0,0,0,0,0,0,0,0,0,0,0,0,0,0,0,0,0,0,0,0,0,0,0,0,0,0,0,0,0~
,0,0,BM10,0,0,0,0,0,0)';
      PINUSE='POWER';
      NO_LOAD_CHECK='Both';
      NO_IO_CHECK='Both';
      NO_ASSERT_CHECK='TRUE';
      NO_DIR_CHECK='TRUE';
      ALLOW_CONNECT='TRUE';
    'VSS_BM15':
      PIN_NUMBER='(0,0,0,0,0,0,0,0,0,0,0,0,0,0,0,0,0,0,0,0,0,0,0,0,0,0,0,0,0,0,0~
,0,0,BM15,0,0,0,0,0,0)';
      PINUSE='POWER';
      NO_LOAD_CHECK='Both';
      NO_IO_CHECK='Both';
      NO_ASSERT_CHECK='TRUE';
      NO_DIR_CHECK='TRUE';
      ALLOW_CONNECT='TRUE';
    'VSS_BM17':
      PIN_NUMBER='(0,0,0,0,0,0,0,0,0,0,0,0,0,0,0,0,0,0,0,0,0,0,0,0,0,0,0,0,0,0,0~
,0,0,BM17,0,0,0,0,0,0)';
      PINUSE='POWER';
      NO_LOAD_CHECK='Both';
      NO_IO_CHECK='Both';
      NO_ASSERT_CHECK='TRUE';
      NO_DIR_CHECK='TRUE';
      ALLOW_CONNECT='TRUE';
    'VSS_BM23':
      PIN_NUMBER='(0,0,0,0,0,0,0,0,0,0,0,0,0,0,0,0,0,0,0,0,0,0,0,0,0,0,0,0,0,0,0~
,0,0,BM23,0,0,0,0,0,0)';
      PINUSE='POWER';
      NO_LOAD_CHECK='Both';
      NO_IO_CHECK='Both';
      NO_ASSERT_CHECK='TRUE';
      NO_DIR_CHECK='TRUE';
      ALLOW_CONNECT='TRUE';
    'VSS_BM25':
      PIN_NUMBER='(0,0,0,0,0,0,0,0,0,0,0,0,0,0,0,0,0,0,0,0,0,0,0,0,0,0,0,0,0,0,0~
,0,0,BM25,0,0,0,0,0,0)';
      PINUSE='POWER';
      NO_LOAD_CHECK='Both';
      NO_IO_CHECK='Both';
      NO_ASSERT_CHECK='TRUE';
      NO_DIR_CHECK='TRUE';
      ALLOW_CONNECT='TRUE';
    'VSS_BM27':
      PIN_NUMBER='(0,0,0,0,0,0,0,0,0,0,0,0,0,0,0,0,0,0,0,0,0,0,0,0,0,0,0,0,0,0,0~
,0,0,BM27,0,0,0,0,0,0)';
      PINUSE='POWER';
      NO_LOAD_CHECK='Both';
      NO_IO_CHECK='Both';
      NO_ASSERT_CHECK='TRUE';
      NO_DIR_CHECK='TRUE';
      ALLOW_CONNECT='TRUE';
    'VSS_BM29':
      PIN_NUMBER='(0,0,0,0,0,0,0,0,0,0,0,0,0,0,0,0,0,0,0,0,0,0,0,0,0,0,0,0,0,0,0~
,0,0,BM29,0,0,0,0,0,0)';
      PINUSE='POWER';
      NO_LOAD_CHECK='Both';
      NO_IO_CHECK='Both';
      NO_ASSERT_CHECK='TRUE';
      NO_DIR_CHECK='TRUE';
      ALLOW_CONNECT='TRUE';
    'VSS_BM31':
      PIN_NUMBER='(0,0,0,0,0,0,0,0,0,0,0,0,0,0,0,0,0,0,0,0,0,0,0,0,0,0,0,0,0,0,0~
,0,0,BM31,0,0,0,0,0,0)';
      PINUSE='POWER';
      NO_LOAD_CHECK='Both';
      NO_IO_CHECK='Both';
      NO_ASSERT_CHECK='TRUE';
      NO_DIR_CHECK='TRUE';
      ALLOW_CONNECT='TRUE';
    'VSS_BM33':
      PIN_NUMBER='(0,0,0,0,0,0,0,0,0,0,0,0,0,0,0,0,0,0,0,0,0,0,0,0,0,0,0,0,0,0,0~
,0,0,BM33,0,0,0,0,0,0)';
      PINUSE='POWER';
      NO_LOAD_CHECK='Both';
      NO_IO_CHECK='Both';
      NO_ASSERT_CHECK='TRUE';
      NO_DIR_CHECK='TRUE';
      ALLOW_CONNECT='TRUE';
    'VSS_BM35':
      PIN_NUMBER='(0,0,0,0,0,0,0,0,0,0,0,0,0,0,0,0,0,0,0,0,0,0,0,0,0,0,0,0,0,0,0~
,0,0,BM35,0,0,0,0,0,0)';
      PINUSE='POWER';
      NO_LOAD_CHECK='Both';
      NO_IO_CHECK='Both';
      NO_ASSERT_CHECK='TRUE';
      NO_DIR_CHECK='TRUE';
      ALLOW_CONNECT='TRUE';
    'VSS_BM37':
      PIN_NUMBER='(0,0,0,0,0,0,0,0,0,0,0,0,0,0,0,0,0,0,0,0,0,0,0,0,0,0,0,0,0,0,0~
,0,0,BM37,0,0,0,0,0,0)';
      PINUSE='POWER';
      NO_LOAD_CHECK='Both';
      NO_IO_CHECK='Both';
      NO_ASSERT_CHECK='TRUE';
      NO_DIR_CHECK='TRUE';
      ALLOW_CONNECT='TRUE';
    'VSS_BM40':
      PIN_NUMBER='(0,0,0,0,0,0,0,0,0,0,0,0,0,0,0,0,0,0,0,0,0,0,0,0,0,0,0,0,0,0,0~
,0,0,BM40,0,0,0,0,0,0)';
      PINUSE='POWER';
      NO_LOAD_CHECK='Both';
      NO_IO_CHECK='Both';
      NO_ASSERT_CHECK='TRUE';
      NO_DIR_CHECK='TRUE';
      ALLOW_CONNECT='TRUE';
    'VSS_BM42':
      PIN_NUMBER='(0,0,0,0,0,0,0,0,0,0,0,0,0,0,0,0,0,0,0,0,0,0,0,0,0,0,0,0,0,0,0~
,0,0,BM42,0,0,0,0,0,0)';
      PINUSE='POWER';
      NO_LOAD_CHECK='Both';
      NO_IO_CHECK='Both';
      NO_ASSERT_CHECK='TRUE';
      NO_DIR_CHECK='TRUE';
      ALLOW_CONNECT='TRUE';
    'VSS_BM44':
      PIN_NUMBER='(0,0,0,0,0,0,0,0,0,0,0,0,0,0,0,0,0,0,0,0,0,0,0,0,0,0,0,0,0,0,0~
,0,0,BM44,0,0,0,0,0,0)';
      PINUSE='POWER';
      NO_LOAD_CHECK='Both';
      NO_IO_CHECK='Both';
      NO_ASSERT_CHECK='TRUE';
      NO_DIR_CHECK='TRUE';
      ALLOW_CONNECT='TRUE';
    'VSS_BM46':
      PIN_NUMBER='(0,0,0,0,0,0,0,0,0,0,0,0,0,0,0,0,0,0,0,0,0,0,0,0,0,0,0,0,0,0,0~
,0,0,BM46,0,0,0,0,0,0)';
      PINUSE='POWER';
      NO_LOAD_CHECK='Both';
      NO_IO_CHECK='Both';
      NO_ASSERT_CHECK='TRUE';
      NO_DIR_CHECK='TRUE';
      ALLOW_CONNECT='TRUE';
    'VSS_BM48':
      PIN_NUMBER='(0,0,0,0,0,0,0,0,0,0,0,0,0,0,0,0,0,0,0,0,0,0,0,0,0,0,0,0,0,0,0~
,0,0,BM48,0,0,0,0,0,0)';
      PINUSE='POWER';
      NO_LOAD_CHECK='Both';
      NO_IO_CHECK='Both';
      NO_ASSERT_CHECK='TRUE';
      NO_DIR_CHECK='TRUE';
      ALLOW_CONNECT='TRUE';
    'VSS_BM50':
      PIN_NUMBER='(0,0,0,0,0,0,0,0,0,0,0,0,0,0,0,0,0,0,0,0,0,0,0,0,0,0,0,0,0,0,0~
,0,0,BM50,0,0,0,0,0,0)';
      PINUSE='POWER';
      NO_LOAD_CHECK='Both';
      NO_IO_CHECK='Both';
      NO_ASSERT_CHECK='TRUE';
      NO_DIR_CHECK='TRUE';
      ALLOW_CONNECT='TRUE';
    'VSS_BM52':
      PIN_NUMBER='(0,0,0,0,0,0,0,0,0,0,0,0,0,0,0,0,0,0,0,0,0,0,0,0,0,0,0,0,0,0,0~
,0,0,BM52,0,0,0,0,0,0)';
      PINUSE='POWER';
      NO_LOAD_CHECK='Both';
      NO_IO_CHECK='Both';
      NO_ASSERT_CHECK='TRUE';
      NO_DIR_CHECK='TRUE';
      ALLOW_CONNECT='TRUE';
    'VSS_BM54':
      PIN_NUMBER='(0,0,0,0,0,0,0,0,0,0,0,0,0,0,0,0,0,0,0,0,0,0,0,0,0,0,0,0,0,0,0~
,0,0,BM54,0,0,0,0,0,0)';
      PINUSE='POWER';
      NO_LOAD_CHECK='Both';
      NO_IO_CHECK='Both';
      NO_ASSERT_CHECK='TRUE';
      NO_DIR_CHECK='TRUE';
      ALLOW_CONNECT='TRUE';
    'VSS_BM59':
      PIN_NUMBER='(0,0,0,0,0,0,0,0,0,0,0,0,0,0,0,0,0,0,0,0,0,0,0,0,0,0,0,0,0,0,0~
,0,0,BM59,0,0,0,0,0,0)';
      PINUSE='POWER';
      NO_LOAD_CHECK='Both';
      NO_IO_CHECK='Both';
      NO_ASSERT_CHECK='TRUE';
      NO_DIR_CHECK='TRUE';
      ALLOW_CONNECT='TRUE';
    'VSS_BM61':
      PIN_NUMBER='(0,0,0,0,0,0,0,0,0,0,0,0,0,0,0,0,0,0,0,0,0,0,0,0,0,0,0,0,0,0,0~
,0,0,BM61,0,0,0,0,0,0)';
      PINUSE='POWER';
      NO_LOAD_CHECK='Both';
      NO_IO_CHECK='Both';
      NO_ASSERT_CHECK='TRUE';
      NO_DIR_CHECK='TRUE';
      ALLOW_CONNECT='TRUE';
    'VSS_BM66':
      PIN_NUMBER='(0,0,0,0,0,0,0,0,0,0,0,0,0,0,0,0,0,0,0,0,0,0,0,0,0,0,0,0,0,0,0~
,0,0,BM66,0,0,0,0,0,0)';
      PINUSE='POWER';
      NO_LOAD_CHECK='Both';
      NO_IO_CHECK='Both';
      NO_ASSERT_CHECK='TRUE';
      NO_DIR_CHECK='TRUE';
      ALLOW_CONNECT='TRUE';
    'VSS_BM68':
      PIN_NUMBER='(0,0,0,0,0,0,0,0,0,0,0,0,0,0,0,0,0,0,0,0,0,0,0,0,0,0,0,0,0,0,0~
,0,0,BM68,0,0,0,0,0,0)';
      PINUSE='POWER';
      NO_LOAD_CHECK='Both';
      NO_IO_CHECK='Both';
      NO_ASSERT_CHECK='TRUE';
      NO_DIR_CHECK='TRUE';
      ALLOW_CONNECT='TRUE';
    'VSS_BM73':
      PIN_NUMBER='(0,0,0,0,0,0,0,0,0,0,0,0,0,0,0,0,0,0,0,0,0,0,0,0,0,0,0,0,0,0,0~
,0,0,BM73,0,0,0,0,0,0)';
      PINUSE='POWER';
      NO_LOAD_CHECK='Both';
      NO_IO_CHECK='Both';
      NO_ASSERT_CHECK='TRUE';
      NO_DIR_CHECK='TRUE';
      ALLOW_CONNECT='TRUE';
    'VSS_BN1':
      PIN_NUMBER='(0,0,0,0,0,0,0,0,0,0,0,0,0,0,0,0,0,0,0,0,0,0,0,0,0,0,0,0,0,0,0~
,0,0,BN1,0,0,0,0,0,0)';
      PINUSE='POWER';
      NO_LOAD_CHECK='Both';
      NO_IO_CHECK='Both';
      NO_ASSERT_CHECK='TRUE';
      NO_DIR_CHECK='TRUE';
      ALLOW_CONNECT='TRUE';
    'VSS_BN4':
      PIN_NUMBER='(0,0,0,0,0,0,0,0,0,0,0,0,0,0,0,0,0,0,0,0,0,0,0,0,0,0,0,0,0,0,0~
,0,0,BN4,0,0,0,0,0,0)';
      PINUSE='POWER';
      NO_LOAD_CHECK='Both';
      NO_IO_CHECK='Both';
      NO_ASSERT_CHECK='TRUE';
      NO_DIR_CHECK='TRUE';
      ALLOW_CONNECT='TRUE';
    'VSS_BN6':
      PIN_NUMBER='(0,0,0,0,0,0,0,0,0,0,0,0,0,0,0,0,0,0,0,0,0,0,0,0,0,0,0,0,0,0,0~
,0,0,BN6,0,0,0,0,0,0)';
      PINUSE='POWER';
      NO_LOAD_CHECK='Both';
      NO_IO_CHECK='Both';
      NO_ASSERT_CHECK='TRUE';
      NO_DIR_CHECK='TRUE';
      ALLOW_CONNECT='TRUE';
    'VSS_BN8':
      PIN_NUMBER='(0,0,0,0,0,0,0,0,0,0,0,0,0,0,0,0,0,0,0,0,0,0,0,0,0,0,0,0,0,0,0~
,0,0,BN8,0,0,0,0,0,0)';
      PINUSE='POWER';
      NO_LOAD_CHECK='Both';
      NO_IO_CHECK='Both';
      NO_ASSERT_CHECK='TRUE';
      NO_DIR_CHECK='TRUE';
      ALLOW_CONNECT='TRUE';
    'VSS_BN11':
      PIN_NUMBER='(0,0,0,0,0,0,0,0,0,0,0,0,0,0,0,0,0,0,0,0,0,0,0,0,0,0,0,0,0,0,0~
,0,0,BN11,0,0,0,0,0,0)';
      PINUSE='POWER';
      NO_LOAD_CHECK='Both';
      NO_IO_CHECK='Both';
      NO_ASSERT_CHECK='TRUE';
      NO_DIR_CHECK='TRUE';
      ALLOW_CONNECT='TRUE';
    'VSS_BN13':
      PIN_NUMBER='(0,0,0,0,0,0,0,0,0,0,0,0,0,0,0,0,0,0,0,0,0,0,0,0,0,0,0,0,0,0,0~
,0,0,BN13,0,0,0,0,0,0)';
      PINUSE='POWER';
      NO_LOAD_CHECK='Both';
      NO_IO_CHECK='Both';
      NO_ASSERT_CHECK='TRUE';
      NO_DIR_CHECK='TRUE';
      ALLOW_CONNECT='TRUE';
    'VSS_BN15':
      PIN_NUMBER='(0,0,0,0,0,0,0,0,0,0,0,0,0,0,0,0,0,0,0,0,0,0,0,0,0,0,0,0,0,0,0~
,0,0,BN15,0,0,0,0,0,0)';
      PINUSE='POWER';
      NO_LOAD_CHECK='Both';
      NO_IO_CHECK='Both';
      NO_ASSERT_CHECK='TRUE';
      NO_DIR_CHECK='TRUE';
      ALLOW_CONNECT='TRUE';
    'VSS_BN18':
      PIN_NUMBER='(0,0,0,0,0,0,0,0,0,0,0,0,0,0,0,0,0,0,0,0,0,0,0,0,0,0,0,0,0,0,0~
,0,0,BN18,0,0,0,0,0,0)';
      PINUSE='POWER';
      NO_LOAD_CHECK='Both';
      NO_IO_CHECK='Both';
      NO_ASSERT_CHECK='TRUE';
      NO_DIR_CHECK='TRUE';
      ALLOW_CONNECT='TRUE';
    'VSS_BN20':
      PIN_NUMBER='(0,0,0,0,0,0,0,0,0,0,0,0,0,0,0,0,0,0,0,0,0,0,0,0,0,0,0,0,0,0,0~
,0,0,BN20,0,0,0,0,0,0)';
      PINUSE='POWER';
      NO_LOAD_CHECK='Both';
      NO_IO_CHECK='Both';
      NO_ASSERT_CHECK='TRUE';
      NO_DIR_CHECK='TRUE';
      ALLOW_CONNECT='TRUE';
    'VSS_BN22':
      PIN_NUMBER='(0,0,0,0,0,0,0,0,0,0,0,0,0,0,0,0,0,0,0,0,0,0,0,0,0,0,0,0,0,0,0~
,0,0,BN22,0,0,0,0,0,0)';
      PINUSE='POWER';
      NO_LOAD_CHECK='Both';
      NO_IO_CHECK='Both';
      NO_ASSERT_CHECK='TRUE';
      NO_DIR_CHECK='TRUE';
      ALLOW_CONNECT='TRUE';
    'VSS_BN24':
      PIN_NUMBER='(0,0,0,0,0,0,0,0,0,0,0,0,0,0,0,0,0,0,0,0,0,0,0,0,0,0,0,0,0,0,0~
,0,0,BN24,0,0,0,0,0,0)';
      PINUSE='POWER';
      NO_LOAD_CHECK='Both';
      NO_IO_CHECK='Both';
      NO_ASSERT_CHECK='TRUE';
      NO_DIR_CHECK='TRUE';
      ALLOW_CONNECT='TRUE';
    'VSS_BN26':
      PIN_NUMBER='(0,0,0,0,0,0,0,0,0,0,0,0,0,0,0,0,0,0,0,0,0,0,0,0,0,0,0,0,0,0,0~
,0,0,BN26,0,0,0,0,0,0)';
      PINUSE='POWER';
      NO_LOAD_CHECK='Both';
      NO_IO_CHECK='Both';
      NO_ASSERT_CHECK='TRUE';
      NO_DIR_CHECK='TRUE';
      ALLOW_CONNECT='TRUE';
    'VSS_BN28':
      PIN_NUMBER='(0,0,0,0,0,0,0,0,0,0,0,0,0,0,0,0,0,0,0,0,0,0,0,0,0,0,0,0,0,0,0~
,0,0,BN28,0,0,0,0,0,0)';
      PINUSE='POWER';
      NO_LOAD_CHECK='Both';
      NO_IO_CHECK='Both';
      NO_ASSERT_CHECK='TRUE';
      NO_DIR_CHECK='TRUE';
      ALLOW_CONNECT='TRUE';
    'VSS_BN30':
      PIN_NUMBER='(0,0,0,0,0,0,0,0,0,0,0,0,0,0,0,0,0,0,0,0,0,0,0,0,0,0,0,0,0,0,0~
,0,0,BN30,0,0,0,0,0,0)';
      PINUSE='POWER';
      NO_LOAD_CHECK='Both';
      NO_IO_CHECK='Both';
      NO_ASSERT_CHECK='TRUE';
      NO_DIR_CHECK='TRUE';
      ALLOW_CONNECT='TRUE';
    'VSS_BN32':
      PIN_NUMBER='(0,0,0,0,0,0,0,0,0,0,0,0,0,0,0,0,0,0,0,0,0,0,0,0,0,0,0,0,0,0,0~
,0,0,BN32,0,0,0,0,0,0)';
      PINUSE='POWER';
      NO_LOAD_CHECK='Both';
      NO_IO_CHECK='Both';
      NO_ASSERT_CHECK='TRUE';
      NO_DIR_CHECK='TRUE';
      ALLOW_CONNECT='TRUE';
    'VSS_BN34':
      PIN_NUMBER='(0,0,0,0,0,0,0,0,0,0,0,0,0,0,0,0,0,0,0,0,0,0,0,0,0,0,0,0,0,0,0~
,0,0,BN34,0,0,0,0,0,0)';
      PINUSE='POWER';
      NO_LOAD_CHECK='Both';
      NO_IO_CHECK='Both';
      NO_ASSERT_CHECK='TRUE';
      NO_DIR_CHECK='TRUE';
      ALLOW_CONNECT='TRUE';
    'VSS_BN36':
      PIN_NUMBER='(0,0,0,0,0,0,0,0,0,0,0,0,0,0,0,0,0,0,0,0,0,0,0,0,0,0,0,0,0,0,0~
,0,0,BN36,0,0,0,0,0,0)';
      PINUSE='POWER';
      NO_LOAD_CHECK='Both';
      NO_IO_CHECK='Both';
      NO_ASSERT_CHECK='TRUE';
      NO_DIR_CHECK='TRUE';
      ALLOW_CONNECT='TRUE';
    'VSS_BN41':
      PIN_NUMBER='(0,0,0,0,0,0,0,0,0,0,0,0,0,0,0,0,0,0,0,0,0,0,0,0,0,0,0,0,0,0,0~
,0,0,BN41,0,0,0,0,0,0)';
      PINUSE='POWER';
      NO_LOAD_CHECK='Both';
      NO_IO_CHECK='Both';
      NO_ASSERT_CHECK='TRUE';
      NO_DIR_CHECK='TRUE';
      ALLOW_CONNECT='TRUE';
    'VSS_BN43':
      PIN_NUMBER='(0,0,0,0,0,0,0,0,0,0,0,0,0,0,0,0,0,0,0,0,0,0,0,0,0,0,0,0,0,0,0~
,0,0,BN43,0,0,0,0,0,0)';
      PINUSE='POWER';
      NO_LOAD_CHECK='Both';
      NO_IO_CHECK='Both';
      NO_ASSERT_CHECK='TRUE';
      NO_DIR_CHECK='TRUE';
      ALLOW_CONNECT='TRUE';
    'VSS_BN45':
      PIN_NUMBER='(0,0,0,0,0,0,0,0,0,0,0,0,0,0,0,0,0,0,0,0,0,0,0,0,0,0,0,0,0,0,0~
,0,0,BN45,0,0,0,0,0,0)';
      PINUSE='POWER';
      NO_LOAD_CHECK='Both';
      NO_IO_CHECK='Both';
      NO_ASSERT_CHECK='TRUE';
      NO_DIR_CHECK='TRUE';
      ALLOW_CONNECT='TRUE';
    'VSS_BN47':
      PIN_NUMBER='(0,0,0,0,0,0,0,0,0,0,0,0,0,0,0,0,0,0,0,0,0,0,0,0,0,0,0,0,0,0,0~
,0,0,BN47,0,0,0,0,0,0)';
      PINUSE='POWER';
      NO_LOAD_CHECK='Both';
      NO_IO_CHECK='Both';
      NO_ASSERT_CHECK='TRUE';
      NO_DIR_CHECK='TRUE';
      ALLOW_CONNECT='TRUE';
    'VSS_BN49':
      PIN_NUMBER='(0,0,0,0,0,0,0,0,0,0,0,0,0,0,0,0,0,0,0,0,0,0,0,0,0,0,0,0,0,0,0~
,0,0,BN49,0,0,0,0,0,0)';
      PINUSE='POWER';
      NO_LOAD_CHECK='Both';
      NO_IO_CHECK='Both';
      NO_ASSERT_CHECK='TRUE';
      NO_DIR_CHECK='TRUE';
      ALLOW_CONNECT='TRUE';
    'VSS_BN51':
      PIN_NUMBER='(0,0,0,0,0,0,0,0,0,0,0,0,0,0,0,0,0,0,0,0,0,0,0,0,0,0,0,0,0,0,0~
,0,0,BN51,0,0,0,0,0,0)';
      PINUSE='POWER';
      NO_LOAD_CHECK='Both';
      NO_IO_CHECK='Both';
      NO_ASSERT_CHECK='TRUE';
      NO_DIR_CHECK='TRUE';
      ALLOW_CONNECT='TRUE';
    'VSS_BN53':
      PIN_NUMBER='(0,0,0,0,0,0,0,0,0,0,0,0,0,0,0,0,0,0,0,0,0,0,0,0,0,0,0,0,0,0,0~
,0,0,BN53,0,0,0,0,0,0)';
      PINUSE='POWER';
      NO_LOAD_CHECK='Both';
      NO_IO_CHECK='Both';
      NO_ASSERT_CHECK='TRUE';
      NO_DIR_CHECK='TRUE';
      ALLOW_CONNECT='TRUE';
    'VSS_BN56':
      PIN_NUMBER='(0,0,0,0,0,0,0,0,0,0,0,0,0,0,0,0,0,0,0,0,0,0,0,0,0,0,0,0,0,0,0~
,0,0,BN56,0,0,0,0,0,0)';
      PINUSE='POWER';
      NO_LOAD_CHECK='Both';
      NO_IO_CHECK='Both';
      NO_ASSERT_CHECK='TRUE';
      NO_DIR_CHECK='TRUE';
      ALLOW_CONNECT='TRUE';
    'VSS_BN58':
      PIN_NUMBER='(0,0,0,0,0,0,0,0,0,0,0,0,0,0,0,0,0,0,0,0,0,0,0,0,0,0,0,0,0,0,0~
,0,0,BN58,0,0,0,0,0,0)';
      PINUSE='POWER';
      NO_LOAD_CHECK='Both';
      NO_IO_CHECK='Both';
      NO_ASSERT_CHECK='TRUE';
      NO_DIR_CHECK='TRUE';
      ALLOW_CONNECT='TRUE';
    'VSS_BN61':
      PIN_NUMBER='(0,0,0,0,0,0,0,0,0,0,0,0,0,0,0,0,0,0,0,0,0,0,0,0,0,0,0,0,0,0,0~
,0,0,BN61,0,0,0,0,0,0)';
      PINUSE='POWER';
      NO_LOAD_CHECK='Both';
      NO_IO_CHECK='Both';
      NO_ASSERT_CHECK='TRUE';
      NO_DIR_CHECK='TRUE';
      ALLOW_CONNECT='TRUE';
    'VSS_BN63':
      PIN_NUMBER='(0,0,0,0,0,0,0,0,0,0,0,0,0,0,0,0,0,0,0,0,0,0,0,0,0,0,0,0,0,0,0~
,0,0,BN63,0,0,0,0,0,0)';
      PINUSE='POWER';
      NO_LOAD_CHECK='Both';
      NO_IO_CHECK='Both';
      NO_ASSERT_CHECK='TRUE';
      NO_DIR_CHECK='TRUE';
      ALLOW_CONNECT='TRUE';
    'VSS_BN65':
      PIN_NUMBER='(0,0,0,0,0,0,0,0,0,0,0,0,0,0,0,0,0,0,0,0,0,0,0,0,0,0,0,0,0,0,0~
,0,0,BN65,0,0,0,0,0,0)';
      PINUSE='POWER';
      NO_LOAD_CHECK='Both';
      NO_IO_CHECK='Both';
      NO_ASSERT_CHECK='TRUE';
      NO_DIR_CHECK='TRUE';
      ALLOW_CONNECT='TRUE';
    'VSS_BN68':
      PIN_NUMBER='(0,0,0,0,0,0,0,0,0,0,0,0,0,0,0,0,0,0,0,0,0,0,0,0,0,0,0,0,0,0,0~
,0,0,BN68,0,0,0,0,0,0)';
      PINUSE='POWER';
      NO_LOAD_CHECK='Both';
      NO_IO_CHECK='Both';
      NO_ASSERT_CHECK='TRUE';
      NO_DIR_CHECK='TRUE';
      ALLOW_CONNECT='TRUE';
    'VSS_BN70':
      PIN_NUMBER='(0,0,0,0,0,0,0,0,0,0,0,0,0,0,0,0,0,0,0,0,0,0,0,0,0,0,0,0,0,0,0~
,0,0,BN70,0,0,0,0,0,0)';
      PINUSE='POWER';
      NO_LOAD_CHECK='Both';
      NO_IO_CHECK='Both';
      NO_ASSERT_CHECK='TRUE';
      NO_DIR_CHECK='TRUE';
      ALLOW_CONNECT='TRUE';
    'VSS_BN72':
      PIN_NUMBER='(0,0,0,0,0,0,0,0,0,0,0,0,0,0,0,0,0,0,0,0,0,0,0,0,0,0,0,0,0,0,0~
,0,0,BN72,0,0,0,0,0,0)';
      PINUSE='POWER';
      NO_LOAD_CHECK='Both';
      NO_IO_CHECK='Both';
      NO_ASSERT_CHECK='TRUE';
      NO_DIR_CHECK='TRUE';
      ALLOW_CONNECT='TRUE';
    'VSS_BN75':
      PIN_NUMBER='(0,0,0,0,0,0,0,0,0,0,0,0,0,0,0,0,0,0,0,0,0,0,0,0,0,0,0,0,0,0,0~
,0,0,BN75,0,0,0,0,0,0)';
      PINUSE='POWER';
      NO_LOAD_CHECK='Both';
      NO_IO_CHECK='Both';
      NO_ASSERT_CHECK='TRUE';
      NO_DIR_CHECK='TRUE';
      ALLOW_CONNECT='TRUE';
    'VSS_BP3':
      PIN_NUMBER='(0,0,0,0,0,0,0,0,0,0,0,0,0,0,0,0,0,0,0,0,0,0,0,0,0,0,0,0,0,0,0~
,0,0,BP3,0,0,0,0,0,0)';
      PINUSE='POWER';
      NO_LOAD_CHECK='Both';
      NO_IO_CHECK='Both';
      NO_ASSERT_CHECK='TRUE';
      NO_DIR_CHECK='TRUE';
      ALLOW_CONNECT='TRUE';
    'VSS_BP5':
      PIN_NUMBER='(0,0,0,0,0,0,0,0,0,0,0,0,0,0,0,0,0,0,0,0,0,0,0,0,0,0,0,0,0,0,0~
,0,0,BP5,0,0,0,0,0,0)';
      PINUSE='POWER';
      NO_LOAD_CHECK='Both';
      NO_IO_CHECK='Both';
      NO_ASSERT_CHECK='TRUE';
      NO_DIR_CHECK='TRUE';
      ALLOW_CONNECT='TRUE';
    'VSS_BP8':
      PIN_NUMBER='(0,0,0,0,0,0,0,0,0,0,0,0,0,0,0,0,0,0,0,0,0,0,0,0,0,0,0,0,0,0,0~
,0,0,BP8,0,0,0,0,0,0)';
      PINUSE='POWER';
      NO_LOAD_CHECK='Both';
      NO_IO_CHECK='Both';
      NO_ASSERT_CHECK='TRUE';
      NO_DIR_CHECK='TRUE';
      ALLOW_CONNECT='TRUE';
    'VSS_BP10':
      PIN_NUMBER='(0,0,0,0,0,0,0,0,0,0,0,0,0,0,0,0,0,0,0,0,0,0,0,0,0,0,0,0,0,0,0~
,0,0,BP10,0,0,0,0,0,0)';
      PINUSE='POWER';
      NO_LOAD_CHECK='Both';
      NO_IO_CHECK='Both';
      NO_ASSERT_CHECK='TRUE';
      NO_DIR_CHECK='TRUE';
      ALLOW_CONNECT='TRUE';
    'VSS_BP12':
      PIN_NUMBER='(0,0,0,0,0,0,0,0,0,0,0,0,0,0,0,0,0,0,0,0,0,0,0,0,0,0,0,0,0,0,0~
,0,0,BP12,0,0,0,0,0,0)';
      PINUSE='POWER';
      NO_LOAD_CHECK='Both';
      NO_IO_CHECK='Both';
      NO_ASSERT_CHECK='TRUE';
      NO_DIR_CHECK='TRUE';
      ALLOW_CONNECT='TRUE';
    'VSS_BP15':
      PIN_NUMBER='(0,0,0,0,0,0,0,0,0,0,0,0,0,0,0,0,0,0,0,0,0,0,0,0,0,0,0,0,0,0,0~
,0,0,BP15,0,0,0,0,0,0)';
      PINUSE='POWER';
      NO_LOAD_CHECK='Both';
      NO_IO_CHECK='Both';
      NO_ASSERT_CHECK='TRUE';
      NO_DIR_CHECK='TRUE';
      ALLOW_CONNECT='TRUE';
    'VSS_BP17':
      PIN_NUMBER='(0,0,0,0,0,0,0,0,0,0,0,0,0,0,0,0,0,0,0,0,0,0,0,0,0,0,0,0,0,0,0~
,0,0,BP17,0,0,0,0,0,0)';
      PINUSE='POWER';
      NO_LOAD_CHECK='Both';
      NO_IO_CHECK='Both';
      NO_ASSERT_CHECK='TRUE';
      NO_DIR_CHECK='TRUE';
      ALLOW_CONNECT='TRUE';
    'VSS_BP19':
      PIN_NUMBER='(0,0,0,0,0,0,0,0,0,0,0,0,0,0,0,0,0,0,0,0,0,0,0,0,0,0,0,0,0,0,0~
,0,0,BP19,0,0,0,0,0,0)';
      PINUSE='POWER';
      NO_LOAD_CHECK='Both';
      NO_IO_CHECK='Both';
      NO_ASSERT_CHECK='TRUE';
      NO_DIR_CHECK='TRUE';
      ALLOW_CONNECT='TRUE';
    'VSS_BP23':
      PIN_NUMBER='(0,0,0,0,0,0,0,0,0,0,0,0,0,0,0,0,0,0,0,0,0,0,0,0,0,0,0,0,0,0,0~
,0,0,BP23,0,0,0,0,0,0)';
      PINUSE='POWER';
      NO_LOAD_CHECK='Both';
      NO_IO_CHECK='Both';
      NO_ASSERT_CHECK='TRUE';
      NO_DIR_CHECK='TRUE';
      ALLOW_CONNECT='TRUE';
    'VSS_BP25':
      PIN_NUMBER='(0,0,0,0,0,0,0,0,0,0,0,0,0,0,0,0,0,0,0,0,0,0,0,0,0,0,0,0,0,0,0~
,0,0,BP25,0,0,0,0,0,0)';
      PINUSE='POWER';
      NO_LOAD_CHECK='Both';
      NO_IO_CHECK='Both';
      NO_ASSERT_CHECK='TRUE';
      NO_DIR_CHECK='TRUE';
      ALLOW_CONNECT='TRUE';
    'VSS_BP27':
      PIN_NUMBER='(0,0,0,0,0,0,0,0,0,0,0,0,0,0,0,0,0,0,0,0,0,0,0,0,0,0,0,0,0,0,0~
,0,0,BP27,0,0,0,0,0,0)';
      PINUSE='POWER';
      NO_LOAD_CHECK='Both';
      NO_IO_CHECK='Both';
      NO_ASSERT_CHECK='TRUE';
      NO_DIR_CHECK='TRUE';
      ALLOW_CONNECT='TRUE';
    'VSS_BP29':
      PIN_NUMBER='(0,0,0,0,0,0,0,0,0,0,0,0,0,0,0,0,0,0,0,0,0,0,0,0,0,0,0,0,0,0,0~
,0,0,BP29,0,0,0,0,0,0)';
      PINUSE='POWER';
      NO_LOAD_CHECK='Both';
      NO_IO_CHECK='Both';
      NO_ASSERT_CHECK='TRUE';
      NO_DIR_CHECK='TRUE';
      ALLOW_CONNECT='TRUE';
    'VSS_BP31':
      PIN_NUMBER='(0,0,0,0,0,0,0,0,0,0,0,0,0,0,0,0,0,0,0,0,0,0,0,0,0,0,0,0,0,0,0~
,0,0,BP31,0,0,0,0,0,0)';
      PINUSE='POWER';
      NO_LOAD_CHECK='Both';
      NO_IO_CHECK='Both';
      NO_ASSERT_CHECK='TRUE';
      NO_DIR_CHECK='TRUE';
      ALLOW_CONNECT='TRUE';
    'VSS_BP33':
      PIN_NUMBER='(0,0,0,0,0,0,0,0,0,0,0,0,0,0,0,0,0,0,0,0,0,0,0,0,0,0,0,0,0,0,0~
,0,0,BP33,0,0,0,0,0,0)';
      PINUSE='POWER';
      NO_LOAD_CHECK='Both';
      NO_IO_CHECK='Both';
      NO_ASSERT_CHECK='TRUE';
      NO_DIR_CHECK='TRUE';
      ALLOW_CONNECT='TRUE';
    'VSS_BP35':
      PIN_NUMBER='(0,0,0,0,0,0,0,0,0,0,0,0,0,0,0,0,0,0,0,0,0,0,0,0,0,0,0,0,0,0,0~
,0,0,BP35,0,0,0,0,0,0)';
      PINUSE='POWER';
      NO_LOAD_CHECK='Both';
      NO_IO_CHECK='Both';
      NO_ASSERT_CHECK='TRUE';
      NO_DIR_CHECK='TRUE';
      ALLOW_CONNECT='TRUE';
    'VSS_BP37':
      PIN_NUMBER='(0,0,0,0,0,0,0,0,0,0,0,0,0,0,0,0,0,0,0,0,0,0,0,0,0,0,0,0,0,0,0~
,0,0,BP37,0,0,0,0,0,0)';
      PINUSE='POWER';
      NO_LOAD_CHECK='Both';
      NO_IO_CHECK='Both';
      NO_ASSERT_CHECK='TRUE';
      NO_DIR_CHECK='TRUE';
      ALLOW_CONNECT='TRUE';
    'VSS_BP40':
      PIN_NUMBER='(0,0,0,0,0,0,0,0,0,0,0,0,0,0,0,0,0,0,0,0,0,0,0,0,0,0,0,0,0,0,0~
,0,0,BP40,0,0,0,0,0,0)';
      PINUSE='POWER';
      NO_LOAD_CHECK='Both';
      NO_IO_CHECK='Both';
      NO_ASSERT_CHECK='TRUE';
      NO_DIR_CHECK='TRUE';
      ALLOW_CONNECT='TRUE';
    'VSS_BP42':
      PIN_NUMBER='(0,0,0,0,0,0,0,0,0,0,0,0,0,0,0,0,0,0,0,0,0,0,0,0,0,0,0,0,0,0,0~
,0,0,BP42,0,0,0,0,0,0)';
      PINUSE='POWER';
      NO_LOAD_CHECK='Both';
      NO_IO_CHECK='Both';
      NO_ASSERT_CHECK='TRUE';
      NO_DIR_CHECK='TRUE';
      ALLOW_CONNECT='TRUE';
    'VSS_BP44':
      PIN_NUMBER='(0,0,0,0,0,0,0,0,0,0,0,0,0,0,0,0,0,0,0,0,0,0,0,0,0,0,0,0,0,0,0~
,0,0,BP44,0,0,0,0,0,0)';
      PINUSE='POWER';
      NO_LOAD_CHECK='Both';
      NO_IO_CHECK='Both';
      NO_ASSERT_CHECK='TRUE';
      NO_DIR_CHECK='TRUE';
      ALLOW_CONNECT='TRUE';
    'VSS_BP46':
      PIN_NUMBER='(0,0,0,0,0,0,0,0,0,0,0,0,0,0,0,0,0,0,0,0,0,0,0,0,0,0,0,0,0,0,0~
,0,0,BP46,0,0,0,0,0,0)';
      PINUSE='POWER';
      NO_LOAD_CHECK='Both';
      NO_IO_CHECK='Both';
      NO_ASSERT_CHECK='TRUE';
      NO_DIR_CHECK='TRUE';
      ALLOW_CONNECT='TRUE';
    'VSS_BP48':
      PIN_NUMBER='(0,0,0,0,0,0,0,0,0,0,0,0,0,0,0,0,0,0,0,0,0,0,0,0,0,0,0,0,0,0,0~
,0,0,BP48,0,0,0,0,0,0)';
      PINUSE='POWER';
      NO_LOAD_CHECK='Both';
      NO_IO_CHECK='Both';
      NO_ASSERT_CHECK='TRUE';
      NO_DIR_CHECK='TRUE';
      ALLOW_CONNECT='TRUE';
    'VSS_BP50':
      PIN_NUMBER='(0,0,0,0,0,0,0,0,0,0,0,0,0,0,0,0,0,0,0,0,0,0,0,0,0,0,0,0,0,0,0~
,0,0,BP50,0,0,0,0,0,0)';
      PINUSE='POWER';
      NO_LOAD_CHECK='Both';
      NO_IO_CHECK='Both';
      NO_ASSERT_CHECK='TRUE';
      NO_DIR_CHECK='TRUE';
      ALLOW_CONNECT='TRUE';
    'VSS_BP52':
      PIN_NUMBER='(0,0,0,0,0,0,0,0,0,0,0,0,0,0,0,0,0,0,0,0,0,0,0,0,0,0,0,0,0,0,0~
,0,0,BP52,0,0,0,0,0,0)';
      PINUSE='POWER';
      NO_LOAD_CHECK='Both';
      NO_IO_CHECK='Both';
      NO_ASSERT_CHECK='TRUE';
      NO_DIR_CHECK='TRUE';
      ALLOW_CONNECT='TRUE';
    'VSS_BP54':
      PIN_NUMBER='(0,0,0,0,0,0,0,0,0,0,0,0,0,0,0,0,0,0,0,0,0,0,0,0,0,0,0,0,0,0,0~
,0,0,BP54,0,0,0,0,0,0)';
      PINUSE='POWER';
      NO_LOAD_CHECK='Both';
      NO_IO_CHECK='Both';
      NO_ASSERT_CHECK='TRUE';
      NO_DIR_CHECK='TRUE';
      ALLOW_CONNECT='TRUE';
    'VSS_BP57':
      PIN_NUMBER='(0,0,0,0,0,0,0,0,0,0,0,0,0,0,0,0,0,0,0,0,0,0,0,0,0,0,0,0,0,0,0~
,0,0,BP57,0,0,0,0,0,0)';
      PINUSE='POWER';
      NO_LOAD_CHECK='Both';
      NO_IO_CHECK='Both';
      NO_ASSERT_CHECK='TRUE';
      NO_DIR_CHECK='TRUE';
      ALLOW_CONNECT='TRUE';
    'VSS_BP59':
      PIN_NUMBER='(0,0,0,0,0,0,0,0,0,0,0,0,0,0,0,0,0,0,0,0,0,0,0,0,0,0,0,0,0,0,0~
,0,0,BP59,0,0,0,0,0,0)';
      PINUSE='POWER';
      NO_LOAD_CHECK='Both';
      NO_IO_CHECK='Both';
      NO_ASSERT_CHECK='TRUE';
      NO_DIR_CHECK='TRUE';
      ALLOW_CONNECT='TRUE';
    'VSS_BP61':
      PIN_NUMBER='(0,0,0,0,0,0,0,0,0,0,0,0,0,0,0,0,0,0,0,0,0,0,0,0,0,0,0,0,0,0,0~
,0,0,BP61,0,0,0,0,0,0)';
      PINUSE='POWER';
      NO_LOAD_CHECK='Both';
      NO_IO_CHECK='Both';
      NO_ASSERT_CHECK='TRUE';
      NO_DIR_CHECK='TRUE';
      ALLOW_CONNECT='TRUE';
    'VSS_BP64':
      PIN_NUMBER='(0,0,0,0,0,0,0,0,0,0,0,0,0,0,0,0,0,0,0,0,0,0,0,0,0,0,0,0,0,0,0~
,0,0,BP64,0,0,0,0,0,0)';
      PINUSE='POWER';
      NO_LOAD_CHECK='Both';
      NO_IO_CHECK='Both';
      NO_ASSERT_CHECK='TRUE';
      NO_DIR_CHECK='TRUE';
      ALLOW_CONNECT='TRUE';
    'VSS_BP66':
      PIN_NUMBER='(0,0,0,0,0,0,0,0,0,0,0,0,0,0,0,0,0,0,0,0,0,0,0,0,0,0,0,0,0,0,0~
,0,0,BP66,0,0,0,0,0,0)';
      PINUSE='POWER';
      NO_LOAD_CHECK='Both';
      NO_IO_CHECK='Both';
      NO_ASSERT_CHECK='TRUE';
      NO_DIR_CHECK='TRUE';
      ALLOW_CONNECT='TRUE';
    'VSS_BP68':
      PIN_NUMBER='(0,0,0,0,0,0,0,0,0,0,0,0,0,0,0,0,0,0,0,0,0,0,0,0,0,0,0,0,0,0,0~
,0,0,BP68,0,0,0,0,0,0)';
      PINUSE='POWER';
      NO_LOAD_CHECK='Both';
      NO_IO_CHECK='Both';
      NO_ASSERT_CHECK='TRUE';
      NO_DIR_CHECK='TRUE';
      ALLOW_CONNECT='TRUE';
    'VSS_BP71':
      PIN_NUMBER='(0,0,0,0,0,0,0,0,0,0,0,0,0,0,0,0,0,0,0,0,0,0,0,0,0,0,0,0,0,0,0~
,0,0,BP71,0,0,0,0,0,0)';
      PINUSE='POWER';
      NO_LOAD_CHECK='Both';
      NO_IO_CHECK='Both';
      NO_ASSERT_CHECK='TRUE';
      NO_DIR_CHECK='TRUE';
      ALLOW_CONNECT='TRUE';
    'VSS_BP73':
      PIN_NUMBER='(0,0,0,0,0,0,0,0,0,0,0,0,0,0,0,0,0,0,0,0,0,0,0,0,0,0,0,0,0,0,0~
,0,0,BP73,0,0,0,0,0,0)';
      PINUSE='POWER';
      NO_LOAD_CHECK='Both';
      NO_IO_CHECK='Both';
      NO_ASSERT_CHECK='TRUE';
      NO_DIR_CHECK='TRUE';
      ALLOW_CONNECT='TRUE';
    'VSS_BR1':
      PIN_NUMBER='(0,0,0,0,0,0,0,0,0,0,0,0,0,0,0,0,0,0,0,0,0,0,0,0,0,0,0,0,0,0,0~
,0,0,BR1,0,0,0,0,0,0)';
      PINUSE='POWER';
      NO_LOAD_CHECK='Both';
      NO_IO_CHECK='Both';
      NO_ASSERT_CHECK='TRUE';
      NO_DIR_CHECK='TRUE';
      ALLOW_CONNECT='TRUE';
    'VSS_BR3':
      PIN_NUMBER='(0,0,0,0,0,0,0,0,0,0,0,0,0,0,0,0,0,0,0,0,0,0,0,0,0,0,0,0,0,0,0~
,0,0,BR3,0,0,0,0,0,0)';
      PINUSE='POWER';
      NO_LOAD_CHECK='Both';
      NO_IO_CHECK='Both';
      NO_ASSERT_CHECK='TRUE';
      NO_DIR_CHECK='TRUE';
      ALLOW_CONNECT='TRUE';
    'VSS_BR6':
      PIN_NUMBER='(0,0,0,0,0,0,0,0,0,0,0,0,0,0,0,0,0,0,0,0,0,0,0,0,0,0,0,0,0,0,0~
,0,0,BR6,0,0,0,0,0,0)';
      PINUSE='POWER';
      NO_LOAD_CHECK='Both';
      NO_IO_CHECK='Both';
      NO_ASSERT_CHECK='TRUE';
      NO_DIR_CHECK='TRUE';
      ALLOW_CONNECT='TRUE';
    'VSS_BR7':
      PIN_NUMBER='(0,0,0,0,0,0,0,0,0,0,0,0,0,0,0,0,0,0,0,0,0,0,0,0,0,0,0,0,0,0,0~
,0,0,BR7,0,0,0,0,0,0)';
      PINUSE='POWER';
      NO_LOAD_CHECK='Both';
      NO_IO_CHECK='Both';
      NO_ASSERT_CHECK='TRUE';
      NO_DIR_CHECK='TRUE';
      ALLOW_CONNECT='TRUE';
    'VSS_BR8':
      PIN_NUMBER='(0,0,0,0,0,0,0,0,0,0,0,0,0,0,0,0,0,0,0,0,0,0,0,0,0,0,0,0,0,0,0~
,0,0,BR8,0,0,0,0,0,0)';
      PINUSE='POWER';
      NO_LOAD_CHECK='Both';
      NO_IO_CHECK='Both';
      NO_ASSERT_CHECK='TRUE';
      NO_DIR_CHECK='TRUE';
      ALLOW_CONNECT='TRUE';
    'VSS_BR10':
      PIN_NUMBER='(0,0,0,0,0,0,0,0,0,0,0,0,0,0,0,0,0,0,0,0,0,0,0,0,0,0,0,0,0,0,0~
,0,0,BR10,0,0,0,0,0,0)';
      PINUSE='POWER';
      NO_LOAD_CHECK='Both';
      NO_IO_CHECK='Both';
      NO_ASSERT_CHECK='TRUE';
      NO_DIR_CHECK='TRUE';
      ALLOW_CONNECT='TRUE';
    'VSS_BR13':
      PIN_NUMBER='(0,0,0,0,0,0,0,0,0,0,0,0,0,0,0,0,0,0,0,0,0,0,0,0,0,0,0,0,0,0,0~
,0,0,BR13,0,0,0,0,0,0)';
      PINUSE='POWER';
      NO_LOAD_CHECK='Both';
      NO_IO_CHECK='Both';
      NO_ASSERT_CHECK='TRUE';
      NO_DIR_CHECK='TRUE';
      ALLOW_CONNECT='TRUE';
    'VSS_BR14':
      PIN_NUMBER='(0,0,0,0,0,0,0,0,0,0,0,0,0,0,0,0,0,0,0,0,0,0,0,0,0,0,0,0,0,0,0~
,0,0,BR14,0,0,0,0,0,0)';
      PINUSE='POWER';
      NO_LOAD_CHECK='Both';
      NO_IO_CHECK='Both';
      NO_ASSERT_CHECK='TRUE';
      NO_DIR_CHECK='TRUE';
      ALLOW_CONNECT='TRUE';
    'VSS_BR15':
      PIN_NUMBER='(0,0,0,0,0,0,0,0,0,0,0,0,0,0,0,0,0,0,0,0,0,0,0,0,0,0,0,0,0,0,0~
,0,0,BR15,0,0,0,0,0,0)';
      PINUSE='POWER';
      NO_LOAD_CHECK='Both';
      NO_IO_CHECK='Both';
      NO_ASSERT_CHECK='TRUE';
      NO_DIR_CHECK='TRUE';
      ALLOW_CONNECT='TRUE';
    'VSS_BR17':
      PIN_NUMBER='(0,0,0,0,0,0,0,0,0,0,0,0,0,0,0,0,0,0,0,0,0,0,0,0,0,0,0,0,0,0,0~
,0,0,BR17,0,0,0,0,0,0)';
      PINUSE='POWER';
      NO_LOAD_CHECK='Both';
      NO_IO_CHECK='Both';
      NO_ASSERT_CHECK='TRUE';
      NO_DIR_CHECK='TRUE';
      ALLOW_CONNECT='TRUE';
    'VSS_BR20':
      PIN_NUMBER='(0,0,0,0,0,0,0,0,0,0,0,0,0,0,0,0,0,0,0,0,0,0,0,0,0,0,0,0,0,0,0~
,0,0,BR20,0,0,0,0,0,0)';
      PINUSE='POWER';
      NO_LOAD_CHECK='Both';
      NO_IO_CHECK='Both';
      NO_ASSERT_CHECK='TRUE';
      NO_DIR_CHECK='TRUE';
      ALLOW_CONNECT='TRUE';
    'VSS_BR21':
      PIN_NUMBER='(0,0,0,0,0,0,0,0,0,0,0,0,0,0,0,0,0,0,0,0,0,0,0,0,0,0,0,0,0,0,0~
,0,0,BR21,0,0,0,0,0,0)';
      PINUSE='POWER';
      NO_LOAD_CHECK='Both';
      NO_IO_CHECK='Both';
      NO_ASSERT_CHECK='TRUE';
      NO_DIR_CHECK='TRUE';
      ALLOW_CONNECT='TRUE';
    'VSS_BR22':
      PIN_NUMBER='(0,0,0,0,0,0,0,0,0,0,0,0,0,0,0,0,0,0,0,0,0,0,0,0,0,0,0,0,0,0,0~
,0,0,BR22,0,0,0,0,0,0)';
      PINUSE='POWER';
      NO_LOAD_CHECK='Both';
      NO_IO_CHECK='Both';
      NO_ASSERT_CHECK='TRUE';
      NO_DIR_CHECK='TRUE';
      ALLOW_CONNECT='TRUE';
    'VSS_BR24':
      PIN_NUMBER='(0,0,0,0,0,0,0,0,0,0,0,0,0,0,0,0,0,0,0,0,0,0,0,0,0,0,0,0,0,0,0~
,0,0,BR24,0,0,0,0,0,0)';
      PINUSE='POWER';
      NO_LOAD_CHECK='Both';
      NO_IO_CHECK='Both';
      NO_ASSERT_CHECK='TRUE';
      NO_DIR_CHECK='TRUE';
      ALLOW_CONNECT='TRUE';
    'VSS_BR26':
      PIN_NUMBER='(0,0,0,0,0,0,0,0,0,0,0,0,0,0,0,0,0,0,0,0,0,0,0,0,0,0,0,0,0,0,0~
,0,0,BR26,0,0,0,0,0,0)';
      PINUSE='POWER';
      NO_LOAD_CHECK='Both';
      NO_IO_CHECK='Both';
      NO_ASSERT_CHECK='TRUE';
      NO_DIR_CHECK='TRUE';
      ALLOW_CONNECT='TRUE';
    'VSS_BR28':
      PIN_NUMBER='(0,0,0,0,0,0,0,0,0,0,0,0,0,0,0,0,0,0,0,0,0,0,0,0,0,0,0,0,0,0,0~
,0,0,BR28,0,0,0,0,0,0)';
      PINUSE='POWER';
      NO_LOAD_CHECK='Both';
      NO_IO_CHECK='Both';
      NO_ASSERT_CHECK='TRUE';
      NO_DIR_CHECK='TRUE';
      ALLOW_CONNECT='TRUE';
    'VSS_BR30':
      PIN_NUMBER='(0,0,0,0,0,0,0,0,0,0,0,0,0,0,0,0,0,0,0,0,0,0,0,0,0,0,0,0,0,0,0~
,0,0,BR30,0,0,0,0,0,0)';
      PINUSE='POWER';
      NO_LOAD_CHECK='Both';
      NO_IO_CHECK='Both';
      NO_ASSERT_CHECK='TRUE';
      NO_DIR_CHECK='TRUE';
      ALLOW_CONNECT='TRUE';
    'VSS_BR32':
      PIN_NUMBER='(0,0,0,0,0,0,0,0,0,0,0,0,0,0,0,0,0,0,0,0,0,0,0,0,0,0,0,0,0,0,0~
,0,0,BR32,0,0,0,0,0,0)';
      PINUSE='POWER';
      NO_LOAD_CHECK='Both';
      NO_IO_CHECK='Both';
      NO_ASSERT_CHECK='TRUE';
      NO_DIR_CHECK='TRUE';
      ALLOW_CONNECT='TRUE';
    'VSS_BR34':
      PIN_NUMBER='(0,0,0,0,0,0,0,0,0,0,0,0,0,0,0,0,0,0,0,0,0,0,0,0,0,0,0,0,0,0,0~
,0,0,BR34,0,0,0,0,0,0)';
      PINUSE='POWER';
      NO_LOAD_CHECK='Both';
      NO_IO_CHECK='Both';
      NO_ASSERT_CHECK='TRUE';
      NO_DIR_CHECK='TRUE';
      ALLOW_CONNECT='TRUE';
    'VSS_BR36':
      PIN_NUMBER='(0,0,0,0,0,0,0,0,0,0,0,0,0,0,0,0,0,0,0,0,0,0,0,0,0,0,0,0,0,0,0~
,0,0,BR36,0,0,0,0,0,0)';
      PINUSE='POWER';
      NO_LOAD_CHECK='Both';
      NO_IO_CHECK='Both';
      NO_ASSERT_CHECK='TRUE';
      NO_DIR_CHECK='TRUE';
      ALLOW_CONNECT='TRUE';
    'VSS_BR41':
      PIN_NUMBER='(0,0,0,0,0,0,0,0,0,0,0,0,0,0,0,0,0,0,0,0,0,0,0,0,0,0,0,0,0,0,0~
,0,0,BR41,0,0,0,0,0,0)';
      PINUSE='POWER';
      NO_LOAD_CHECK='Both';
      NO_IO_CHECK='Both';
      NO_ASSERT_CHECK='TRUE';
      NO_DIR_CHECK='TRUE';
      ALLOW_CONNECT='TRUE';
    'VSS_BR43':
      PIN_NUMBER='(0,0,0,0,0,0,0,0,0,0,0,0,0,0,0,0,0,0,0,0,0,0,0,0,0,0,0,0,0,0,0~
,0,0,BR43,0,0,0,0,0,0)';
      PINUSE='POWER';
      NO_LOAD_CHECK='Both';
      NO_IO_CHECK='Both';
      NO_ASSERT_CHECK='TRUE';
      NO_DIR_CHECK='TRUE';
      ALLOW_CONNECT='TRUE';
    'VSS_BR45':
      PIN_NUMBER='(0,0,0,0,0,0,0,0,0,0,0,0,0,0,0,0,0,0,0,0,0,0,0,0,0,0,0,0,0,0,0~
,0,0,BR45,0,0,0,0,0,0)';
      PINUSE='POWER';
      NO_LOAD_CHECK='Both';
      NO_IO_CHECK='Both';
      NO_ASSERT_CHECK='TRUE';
      NO_DIR_CHECK='TRUE';
      ALLOW_CONNECT='TRUE';
    'VSS_BR47':
      PIN_NUMBER='(0,0,0,0,0,0,0,0,0,0,0,0,0,0,0,0,0,0,0,0,0,0,0,0,0,0,0,0,0,0,0~
,0,0,BR47,0,0,0,0,0,0)';
      PINUSE='POWER';
      NO_LOAD_CHECK='Both';
      NO_IO_CHECK='Both';
      NO_ASSERT_CHECK='TRUE';
      NO_DIR_CHECK='TRUE';
      ALLOW_CONNECT='TRUE';
    'VSS_BR49':
      PIN_NUMBER='(0,0,0,0,0,0,0,0,0,0,0,0,0,0,0,0,0,0,0,0,0,0,0,0,0,0,0,0,0,0,0~
,0,0,BR49,0,0,0,0,0,0)';
      PINUSE='POWER';
      NO_LOAD_CHECK='Both';
      NO_IO_CHECK='Both';
      NO_ASSERT_CHECK='TRUE';
      NO_DIR_CHECK='TRUE';
      ALLOW_CONNECT='TRUE';
    'VSS_BR51':
      PIN_NUMBER='(0,0,0,0,0,0,0,0,0,0,0,0,0,0,0,0,0,0,0,0,0,0,0,0,0,0,0,0,0,0,0~
,0,0,BR51,0,0,0,0,0,0)';
      PINUSE='POWER';
      NO_LOAD_CHECK='Both';
      NO_IO_CHECK='Both';
      NO_ASSERT_CHECK='TRUE';
      NO_DIR_CHECK='TRUE';
      ALLOW_CONNECT='TRUE';
    'VSS_BR55':
      PIN_NUMBER='(0,0,0,0,0,0,0,0,0,0,0,0,0,0,0,0,0,0,0,0,0,0,0,0,0,0,0,0,0,0,0~
,0,0,BR55,0,0,0,0,0,0)';
      PINUSE='POWER';
      NO_LOAD_CHECK='Both';
      NO_IO_CHECK='Both';
      NO_ASSERT_CHECK='TRUE';
      NO_DIR_CHECK='TRUE';
      ALLOW_CONNECT='TRUE';
    'VSS_BR56':
      PIN_NUMBER='(0,0,0,0,0,0,0,0,0,0,0,0,0,0,0,0,0,0,0,0,0,0,0,0,0,0,0,0,0,0,0~
,0,0,BR56,0,0,0,0,0,0)';
      PINUSE='POWER';
      NO_LOAD_CHECK='Both';
      NO_IO_CHECK='Both';
      NO_ASSERT_CHECK='TRUE';
      NO_DIR_CHECK='TRUE';
      ALLOW_CONNECT='TRUE';
    'VSS_BR59':
      PIN_NUMBER='(0,0,0,0,0,0,0,0,0,0,0,0,0,0,0,0,0,0,0,0,0,0,0,0,0,0,0,0,0,0,0~
,0,0,BR59,0,0,0,0,0,0)';
      PINUSE='POWER';
      NO_LOAD_CHECK='Both';
      NO_IO_CHECK='Both';
      NO_ASSERT_CHECK='TRUE';
      NO_DIR_CHECK='TRUE';
      ALLOW_CONNECT='TRUE';
    'VSS_BR61':
      PIN_NUMBER='(0,0,0,0,0,0,0,0,0,0,0,0,0,0,0,0,0,0,0,0,0,0,0,0,0,0,0,0,0,0,0~
,0,0,BR61,0,0,0,0,0,0)';
      PINUSE='POWER';
      NO_LOAD_CHECK='Both';
      NO_IO_CHECK='Both';
      NO_ASSERT_CHECK='TRUE';
      NO_DIR_CHECK='TRUE';
      ALLOW_CONNECT='TRUE';
    'VSS_BR62':
      PIN_NUMBER='(0,0,0,0,0,0,0,0,0,0,0,0,0,0,0,0,0,0,0,0,0,0,0,0,0,0,0,0,0,0,0~
,0,0,BR62,0,0,0,0,0,0)';
      PINUSE='POWER';
      NO_LOAD_CHECK='Both';
      NO_IO_CHECK='Both';
      NO_ASSERT_CHECK='TRUE';
      NO_DIR_CHECK='TRUE';
      ALLOW_CONNECT='TRUE';
    'VSS_BR63':
      PIN_NUMBER='(0,0,0,0,0,0,0,0,0,0,0,0,0,0,0,0,0,0,0,0,0,0,0,0,0,0,0,0,0,0,0~
,0,0,BR63,0,0,0,0,0,0)';
      PINUSE='POWER';
      NO_LOAD_CHECK='Both';
      NO_IO_CHECK='Both';
      NO_ASSERT_CHECK='TRUE';
      NO_DIR_CHECK='TRUE';
      ALLOW_CONNECT='TRUE';
    'VSS_BR66':
      PIN_NUMBER='(0,0,0,0,0,0,0,0,0,0,0,0,0,0,0,0,0,0,0,0,0,0,0,0,0,0,0,0,0,0,0~
,0,0,BR66,0,0,0,0,0,0)';
      PINUSE='POWER';
      NO_LOAD_CHECK='Both';
      NO_IO_CHECK='Both';
      NO_ASSERT_CHECK='TRUE';
      NO_DIR_CHECK='TRUE';
      ALLOW_CONNECT='TRUE';
    'VSS_BR68':
      PIN_NUMBER='(0,0,0,0,0,0,0,0,0,0,0,0,0,0,0,0,0,0,0,0,0,0,0,0,0,0,0,0,0,0,0~
,0,0,BR68,0,0,0,0,0,0)';
      PINUSE='POWER';
      NO_LOAD_CHECK='Both';
      NO_IO_CHECK='Both';
      NO_ASSERT_CHECK='TRUE';
      NO_DIR_CHECK='TRUE';
      ALLOW_CONNECT='TRUE';
    'VSS_BR69':
      PIN_NUMBER='(0,0,0,0,0,0,0,0,0,0,0,0,0,0,0,0,0,0,0,0,0,0,0,0,0,0,0,0,0,0,0~
,0,0,BR69,0,0,0,0,0,0)';
      PINUSE='POWER';
      NO_LOAD_CHECK='Both';
      NO_IO_CHECK='Both';
      NO_ASSERT_CHECK='TRUE';
      NO_DIR_CHECK='TRUE';
      ALLOW_CONNECT='TRUE';
    'VSS_BR70':
      PIN_NUMBER='(0,0,0,0,0,0,0,0,0,0,0,0,0,0,0,0,0,0,0,0,0,0,0,0,0,0,0,0,0,0,0~
,0,0,BR70,0,0,0,0,0,0)';
      PINUSE='POWER';
      NO_LOAD_CHECK='Both';
      NO_IO_CHECK='Both';
      NO_ASSERT_CHECK='TRUE';
      NO_DIR_CHECK='TRUE';
      ALLOW_CONNECT='TRUE';
    'VSS_BR73':
      PIN_NUMBER='(0,0,0,0,0,0,0,0,0,0,0,0,0,0,0,0,0,0,0,0,0,0,0,0,0,0,0,0,0,0,0~
,0,0,BR73,0,0,0,0,0,0)';
      PINUSE='POWER';
      NO_LOAD_CHECK='Both';
      NO_IO_CHECK='Both';
      NO_ASSERT_CHECK='TRUE';
      NO_DIR_CHECK='TRUE';
      ALLOW_CONNECT='TRUE';
    'VSS_BR75':
      PIN_NUMBER='(0,0,0,0,0,0,0,0,0,0,0,0,0,0,0,0,0,0,0,0,0,0,0,0,0,0,0,0,0,0,0~
,0,0,BR75,0,0,0,0,0,0)';
      PINUSE='POWER';
      NO_LOAD_CHECK='Both';
      NO_IO_CHECK='Both';
      NO_ASSERT_CHECK='TRUE';
      NO_DIR_CHECK='TRUE';
      ALLOW_CONNECT='TRUE';
    'VSS_BT3':
      PIN_NUMBER='(0,0,0,0,0,0,0,0,0,0,0,0,0,0,0,0,0,0,0,0,0,0,0,0,0,0,0,0,0,0,0~
,0,0,BT3,0,0,0,0,0,0)';
      PINUSE='POWER';
      NO_LOAD_CHECK='Both';
      NO_IO_CHECK='Both';
      NO_ASSERT_CHECK='TRUE';
      NO_DIR_CHECK='TRUE';
      ALLOW_CONNECT='TRUE';
    'VSS_BT4':
      PIN_NUMBER='(0,0,0,0,0,0,0,0,0,0,0,0,0,0,0,0,0,0,0,0,0,0,0,0,0,0,0,0,0,0,0~
,0,0,BT4,0,0,0,0,0,0)';
      PINUSE='POWER';
      NO_LOAD_CHECK='Both';
      NO_IO_CHECK='Both';
      NO_ASSERT_CHECK='TRUE';
      NO_DIR_CHECK='TRUE';
      ALLOW_CONNECT='TRUE';
    'VSS_BT5':
      PIN_NUMBER='(0,0,0,0,0,0,0,0,0,0,0,0,0,0,0,0,0,0,0,0,0,0,0,0,0,0,0,0,0,0,0~
,0,0,BT5,0,0,0,0,0,0)';
      PINUSE='POWER';
      NO_LOAD_CHECK='Both';
      NO_IO_CHECK='Both';
      NO_ASSERT_CHECK='TRUE';
      NO_DIR_CHECK='TRUE';
      ALLOW_CONNECT='TRUE';
    'VSS_BT7':
      PIN_NUMBER='(0,0,0,0,0,0,0,0,0,0,0,0,0,0,0,0,0,0,0,0,0,0,0,0,0,0,0,0,0,0,0~
,0,0,BT7,0,0,0,0,0,0)';
      PINUSE='POWER';
      NO_LOAD_CHECK='Both';
      NO_IO_CHECK='Both';
      NO_ASSERT_CHECK='TRUE';
      NO_DIR_CHECK='TRUE';
      ALLOW_CONNECT='TRUE';
    'VSS_BT8':
      PIN_NUMBER='(0,0,0,0,0,0,0,0,0,0,0,0,0,0,0,0,0,0,0,0,0,0,0,0,0,0,0,0,0,0,0~
,0,0,BT8,0,0,0,0,0,0)';
      PINUSE='POWER';
      NO_LOAD_CHECK='Both';
      NO_IO_CHECK='Both';
      NO_ASSERT_CHECK='TRUE';
      NO_DIR_CHECK='TRUE';
      ALLOW_CONNECT='TRUE';
    'VSS_BT10':
      PIN_NUMBER='(0,0,0,0,0,0,0,0,0,0,0,0,0,0,0,0,0,0,0,0,0,0,0,0,0,0,0,0,0,0,0~
,0,0,BT10,0,0,0,0,0,0)';
      PINUSE='POWER';
      NO_LOAD_CHECK='Both';
      NO_IO_CHECK='Both';
      NO_ASSERT_CHECK='TRUE';
      NO_DIR_CHECK='TRUE';
      ALLOW_CONNECT='TRUE';
    'VSS_BT11':
      PIN_NUMBER='(0,0,0,0,0,0,0,0,0,0,0,0,0,0,0,0,0,0,0,0,0,0,0,0,0,0,0,0,0,0,0~
,0,0,BT11,0,0,0,0,0,0)';
      PINUSE='POWER';
      NO_LOAD_CHECK='Both';
      NO_IO_CHECK='Both';
      NO_ASSERT_CHECK='TRUE';
      NO_DIR_CHECK='TRUE';
      ALLOW_CONNECT='TRUE';
    'VSS_BT12':
      PIN_NUMBER='(0,0,0,0,0,0,0,0,0,0,0,0,0,0,0,0,0,0,0,0,0,0,0,0,0,0,0,0,0,0,0~
,0,0,BT12,0,0,0,0,0,0)';
      PINUSE='POWER';
      NO_LOAD_CHECK='Both';
      NO_IO_CHECK='Both';
      NO_ASSERT_CHECK='TRUE';
      NO_DIR_CHECK='TRUE';
      ALLOW_CONNECT='TRUE';
    'VSS_BT14':
      PIN_NUMBER='(0,0,0,0,0,0,0,0,0,0,0,0,0,0,0,0,0,0,0,0,0,0,0,0,0,0,0,0,0,0,0~
,0,0,BT14,0,0,0,0,0,0)';
      PINUSE='POWER';
      NO_LOAD_CHECK='Both';
      NO_IO_CHECK='Both';
      NO_ASSERT_CHECK='TRUE';
      NO_DIR_CHECK='TRUE';
      ALLOW_CONNECT='TRUE';
    'VSS_BT15':
      PIN_NUMBER='(0,0,0,0,0,0,0,0,0,0,0,0,0,0,0,0,0,0,0,0,0,0,0,0,0,0,0,0,0,0,0~
,0,0,BT15,0,0,0,0,0,0)';
      PINUSE='POWER';
      NO_LOAD_CHECK='Both';
      NO_IO_CHECK='Both';
      NO_ASSERT_CHECK='TRUE';
      NO_DIR_CHECK='TRUE';
      ALLOW_CONNECT='TRUE';
    'VSS_BT17':
      PIN_NUMBER='(0,0,0,0,0,0,0,0,0,0,0,0,0,0,0,0,0,0,0,0,0,0,0,0,0,0,0,0,0,0,0~
,0,0,BT17,0,0,0,0,0,0)';
      PINUSE='POWER';
      NO_LOAD_CHECK='Both';
      NO_IO_CHECK='Both';
      NO_ASSERT_CHECK='TRUE';
      NO_DIR_CHECK='TRUE';
      ALLOW_CONNECT='TRUE';
    'VSS_BT18':
      PIN_NUMBER='(0,0,0,0,0,0,0,0,0,0,0,0,0,0,0,0,0,0,0,0,0,0,0,0,0,0,0,0,0,0,0~
,0,0,BT18,0,0,0,0,0,0)';
      PINUSE='POWER';
      NO_LOAD_CHECK='Both';
      NO_IO_CHECK='Both';
      NO_ASSERT_CHECK='TRUE';
      NO_DIR_CHECK='TRUE';
      ALLOW_CONNECT='TRUE';
    'VSS_BT19':
      PIN_NUMBER='(0,0,0,0,0,0,0,0,0,0,0,0,0,0,0,0,0,0,0,0,0,0,0,0,0,0,0,0,0,0,0~
,0,0,BT19,0,0,0,0,0,0)';
      PINUSE='POWER';
      NO_LOAD_CHECK='Both';
      NO_IO_CHECK='Both';
      NO_ASSERT_CHECK='TRUE';
      NO_DIR_CHECK='TRUE';
      ALLOW_CONNECT='TRUE';
    'VSS_BT21':
      PIN_NUMBER='(0,0,0,0,0,0,0,0,0,0,0,0,0,0,0,0,0,0,0,0,0,0,0,0,0,0,0,0,0,0,0~
,0,0,BT21,0,0,0,0,0,0)';
      PINUSE='POWER';
      NO_LOAD_CHECK='Both';
      NO_IO_CHECK='Both';
      NO_ASSERT_CHECK='TRUE';
      NO_DIR_CHECK='TRUE';
      ALLOW_CONNECT='TRUE';
    'VSS_BT22':
      PIN_NUMBER='(0,0,0,0,0,0,0,0,0,0,0,0,0,0,0,0,0,0,0,0,0,0,0,0,0,0,0,0,0,0,0~
,0,0,BT22,0,0,0,0,0,0)';
      PINUSE='POWER';
      NO_LOAD_CHECK='Both';
      NO_IO_CHECK='Both';
      NO_ASSERT_CHECK='TRUE';
      NO_DIR_CHECK='TRUE';
      ALLOW_CONNECT='TRUE';
    'VSS_BT25':
      PIN_NUMBER='(0,0,0,0,0,0,0,0,0,0,0,0,0,0,0,0,0,0,0,0,0,0,0,0,0,0,0,0,0,0,0~
,0,0,BT25,0,0,0,0,0,0)';
      PINUSE='POWER';
      NO_LOAD_CHECK='Both';
      NO_IO_CHECK='Both';
      NO_ASSERT_CHECK='TRUE';
      NO_DIR_CHECK='TRUE';
      ALLOW_CONNECT='TRUE';
    'VSS_BT28':
      PIN_NUMBER='(0,0,0,0,0,0,0,0,0,0,0,0,0,0,0,0,0,0,0,0,0,0,0,0,0,0,0,0,0,0,0~
,0,0,BT28,0,0,0,0,0,0)';
      PINUSE='POWER';
      NO_LOAD_CHECK='Both';
      NO_IO_CHECK='Both';
      NO_ASSERT_CHECK='TRUE';
      NO_DIR_CHECK='TRUE';
      ALLOW_CONNECT='TRUE';
    'VSS_BT31':
      PIN_NUMBER='(0,0,0,0,0,0,0,0,0,0,0,0,0,0,0,0,0,0,0,0,0,0,0,0,0,0,0,0,0,0,0~
,0,0,BT31,0,0,0,0,0,0)';
      PINUSE='POWER';
      NO_LOAD_CHECK='Both';
      NO_IO_CHECK='Both';
      NO_ASSERT_CHECK='TRUE';
      NO_DIR_CHECK='TRUE';
      ALLOW_CONNECT='TRUE';
    'VSS_BT34':
      PIN_NUMBER='(0,0,0,0,0,0,0,0,0,0,0,0,0,0,0,0,0,0,0,0,0,0,0,0,0,0,0,0,0,0,0~
,0,0,BT34,0,0,0,0,0,0)';
      PINUSE='POWER';
      NO_LOAD_CHECK='Both';
      NO_IO_CHECK='Both';
      NO_ASSERT_CHECK='TRUE';
      NO_DIR_CHECK='TRUE';
      ALLOW_CONNECT='TRUE';
    'VSS_BT37':
      PIN_NUMBER='(0,0,0,0,0,0,0,0,0,0,0,0,0,0,0,0,0,0,0,0,0,0,0,0,0,0,0,0,0,0,0~
,0,0,BT37,0,0,0,0,0,0)';
      PINUSE='POWER';
      NO_LOAD_CHECK='Both';
      NO_IO_CHECK='Both';
      NO_ASSERT_CHECK='TRUE';
      NO_DIR_CHECK='TRUE';
      ALLOW_CONNECT='TRUE';
    'VSS_BT39':
      PIN_NUMBER='(0,0,0,0,0,0,0,0,0,0,0,0,0,0,0,0,0,0,0,0,0,0,0,0,0,0,0,0,0,0,0~
,0,0,BT39,0,0,0,0,0,0)';
      PINUSE='POWER';
      NO_LOAD_CHECK='Both';
      NO_IO_CHECK='Both';
      NO_ASSERT_CHECK='TRUE';
      NO_DIR_CHECK='TRUE';
      ALLOW_CONNECT='TRUE';
    'VSS_BT42':
      PIN_NUMBER='(0,0,0,0,0,0,0,0,0,0,0,0,0,0,0,0,0,0,0,0,0,0,0,0,0,0,0,0,0,0,0~
,0,0,BT42,0,0,0,0,0,0)';
      PINUSE='POWER';
      NO_LOAD_CHECK='Both';
      NO_IO_CHECK='Both';
      NO_ASSERT_CHECK='TRUE';
      NO_DIR_CHECK='TRUE';
      ALLOW_CONNECT='TRUE';
    'VSS_BT45':
      PIN_NUMBER='(0,0,0,0,0,0,0,0,0,0,0,0,0,0,0,0,0,0,0,0,0,0,0,0,0,0,0,0,0,0,0~
,0,0,BT45,0,0,0,0,0,0)';
      PINUSE='POWER';
      NO_LOAD_CHECK='Both';
      NO_IO_CHECK='Both';
      NO_ASSERT_CHECK='TRUE';
      NO_DIR_CHECK='TRUE';
      ALLOW_CONNECT='TRUE';
    'VSS_BT48':
      PIN_NUMBER='(0,0,0,0,0,0,0,0,0,0,0,0,0,0,0,0,0,0,0,0,0,0,0,0,0,0,0,0,0,0,0~
,0,0,BT48,0,0,0,0,0,0)';
      PINUSE='POWER';
      NO_LOAD_CHECK='Both';
      NO_IO_CHECK='Both';
      NO_ASSERT_CHECK='TRUE';
      NO_DIR_CHECK='TRUE';
      ALLOW_CONNECT='TRUE';
    'VSS_BT51':
      PIN_NUMBER='(0,0,0,0,0,0,0,0,0,0,0,0,0,0,0,0,0,0,0,0,0,0,0,0,0,0,0,0,0,0,0~
,0,0,BT51,0,0,0,0,0,0)';
      PINUSE='POWER';
      NO_LOAD_CHECK='Both';
      NO_IO_CHECK='Both';
      NO_ASSERT_CHECK='TRUE';
      NO_DIR_CHECK='TRUE';
      ALLOW_CONNECT='TRUE';
    'VSS_BT54':
      PIN_NUMBER='(0,0,0,0,0,0,0,0,0,0,0,0,0,0,0,0,0,0,0,0,0,0,0,0,0,0,0,0,0,0,0~
,0,0,BT54,0,0,0,0,0,0)';
      PINUSE='POWER';
      NO_LOAD_CHECK='Both';
      NO_IO_CHECK='Both';
      NO_ASSERT_CHECK='TRUE';
      NO_DIR_CHECK='TRUE';
      ALLOW_CONNECT='TRUE';
    'VSS_BT55':
      PIN_NUMBER='(0,0,0,0,0,0,0,0,0,0,0,0,0,0,0,0,0,0,0,0,0,0,0,0,0,0,0,0,0,0,0~
,0,0,BT55,0,0,0,0,0,0)';
      PINUSE='POWER';
      NO_LOAD_CHECK='Both';
      NO_IO_CHECK='Both';
      NO_ASSERT_CHECK='TRUE';
      NO_DIR_CHECK='TRUE';
      ALLOW_CONNECT='TRUE';
    'VSS_BT57':
      PIN_NUMBER='(0,0,0,0,0,0,0,0,0,0,0,0,0,0,0,0,0,0,0,0,0,0,0,0,0,0,0,0,0,0,0~
,0,0,BT57,0,0,0,0,0,0)';
      PINUSE='POWER';
      NO_LOAD_CHECK='Both';
      NO_IO_CHECK='Both';
      NO_ASSERT_CHECK='TRUE';
      NO_DIR_CHECK='TRUE';
      ALLOW_CONNECT='TRUE';
    'VSS_BT58':
      PIN_NUMBER='(0,0,0,0,0,0,0,0,0,0,0,0,0,0,0,0,0,0,0,0,0,0,0,0,0,0,0,0,0,0,0~
,0,0,BT58,0,0,0,0,0,0)';
      PINUSE='POWER';
      NO_LOAD_CHECK='Both';
      NO_IO_CHECK='Both';
      NO_ASSERT_CHECK='TRUE';
      NO_DIR_CHECK='TRUE';
      ALLOW_CONNECT='TRUE';
    'VSS_BT59':
      PIN_NUMBER='(0,0,0,0,0,0,0,0,0,0,0,0,0,0,0,0,0,0,0,0,0,0,0,0,0,0,0,0,0,0,0~
,0,0,BT59,0,0,0,0,0,0)';
      PINUSE='POWER';
      NO_LOAD_CHECK='Both';
      NO_IO_CHECK='Both';
      NO_ASSERT_CHECK='TRUE';
      NO_DIR_CHECK='TRUE';
      ALLOW_CONNECT='TRUE';
    'VSS_BT61':
      PIN_NUMBER='(0,0,0,0,0,0,0,0,0,0,0,0,0,0,0,0,0,0,0,0,0,0,0,0,0,0,0,0,0,0,0~
,0,0,BT61,0,0,0,0,0,0)';
      PINUSE='POWER';
      NO_LOAD_CHECK='Both';
      NO_IO_CHECK='Both';
      NO_ASSERT_CHECK='TRUE';
      NO_DIR_CHECK='TRUE';
      ALLOW_CONNECT='TRUE';
    'VSS_BT62':
      PIN_NUMBER='(0,0,0,0,0,0,0,0,0,0,0,0,0,0,0,0,0,0,0,0,0,0,0,0,0,0,0,0,0,0,0~
,0,0,BT62,0,0,0,0,0,0)';
      PINUSE='POWER';
      NO_LOAD_CHECK='Both';
      NO_IO_CHECK='Both';
      NO_ASSERT_CHECK='TRUE';
      NO_DIR_CHECK='TRUE';
      ALLOW_CONNECT='TRUE';
    'VSS_BT64':
      PIN_NUMBER='(0,0,0,0,0,0,0,0,0,0,0,0,0,0,0,0,0,0,0,0,0,0,0,0,0,0,0,0,0,0,0~
,0,0,BT64,0,0,0,0,0,0)';
      PINUSE='POWER';
      NO_LOAD_CHECK='Both';
      NO_IO_CHECK='Both';
      NO_ASSERT_CHECK='TRUE';
      NO_DIR_CHECK='TRUE';
      ALLOW_CONNECT='TRUE';
    'VSS_BT65':
      PIN_NUMBER='(0,0,0,0,0,0,0,0,0,0,0,0,0,0,0,0,0,0,0,0,0,0,0,0,0,0,0,0,0,0,0~
,0,0,BT65,0,0,0,0,0,0)';
      PINUSE='POWER';
      NO_LOAD_CHECK='Both';
      NO_IO_CHECK='Both';
      NO_ASSERT_CHECK='TRUE';
      NO_DIR_CHECK='TRUE';
      ALLOW_CONNECT='TRUE';
    'VSS_BT66':
      PIN_NUMBER='(0,0,0,0,0,0,0,0,0,0,0,0,0,0,0,0,0,0,0,0,0,0,0,0,0,0,0,0,0,0,0~
,0,0,BT66,0,0,0,0,0,0)';
      PINUSE='POWER';
      NO_LOAD_CHECK='Both';
      NO_IO_CHECK='Both';
      NO_ASSERT_CHECK='TRUE';
      NO_DIR_CHECK='TRUE';
      ALLOW_CONNECT='TRUE';
    'VSS_BT68':
      PIN_NUMBER='(0,0,0,0,0,0,0,0,0,0,0,0,0,0,0,0,0,0,0,0,0,0,0,0,0,0,0,0,0,0,0~
,0,0,BT68,0,0,0,0,0,0)';
      PINUSE='POWER';
      NO_LOAD_CHECK='Both';
      NO_IO_CHECK='Both';
      NO_ASSERT_CHECK='TRUE';
      NO_DIR_CHECK='TRUE';
      ALLOW_CONNECT='TRUE';
    'VSS_BT69':
      PIN_NUMBER='(0,0,0,0,0,0,0,0,0,0,0,0,0,0,0,0,0,0,0,0,0,0,0,0,0,0,0,0,0,0,0~
,0,0,BT69,0,0,0,0,0,0)';
      PINUSE='POWER';
      NO_LOAD_CHECK='Both';
      NO_IO_CHECK='Both';
      NO_ASSERT_CHECK='TRUE';
      NO_DIR_CHECK='TRUE';
      ALLOW_CONNECT='TRUE';
    'VSS_BT71':
      PIN_NUMBER='(0,0,0,0,0,0,0,0,0,0,0,0,0,0,0,0,0,0,0,0,0,0,0,0,0,0,0,0,0,0,0~
,0,0,BT71,0,0,0,0,0,0)';
      PINUSE='POWER';
      NO_LOAD_CHECK='Both';
      NO_IO_CHECK='Both';
      NO_ASSERT_CHECK='TRUE';
      NO_DIR_CHECK='TRUE';
      ALLOW_CONNECT='TRUE';
    'VSS_BT72':
      PIN_NUMBER='(0,0,0,0,0,0,0,0,0,0,0,0,0,0,0,0,0,0,0,0,0,0,0,0,0,0,0,0,0,0,0~
,0,0,BT72,0,0,0,0,0,0)';
      PINUSE='POWER';
      NO_LOAD_CHECK='Both';
      NO_IO_CHECK='Both';
      NO_ASSERT_CHECK='TRUE';
      NO_DIR_CHECK='TRUE';
      ALLOW_CONNECT='TRUE';
    'VSS_BT73':
      PIN_NUMBER='(0,0,0,0,0,0,0,0,0,0,0,0,0,0,0,0,0,0,0,0,0,0,0,0,0,0,0,0,0,0,0~
,0,0,BT73,0,0,0,0,0,0)';
      PINUSE='POWER';
      NO_LOAD_CHECK='Both';
      NO_IO_CHECK='Both';
      NO_ASSERT_CHECK='TRUE';
      NO_DIR_CHECK='TRUE';
      ALLOW_CONNECT='TRUE';
    'VSS_BU1':
      PIN_NUMBER='(0,0,0,0,0,0,0,0,0,0,0,0,0,0,0,0,0,0,0,0,0,0,0,0,0,0,0,0,0,0,0~
,0,0,BU1,0,0,0,0,0,0)';
      PINUSE='POWER';
      NO_LOAD_CHECK='Both';
      NO_IO_CHECK='Both';
      NO_ASSERT_CHECK='TRUE';
      NO_DIR_CHECK='TRUE';
      ALLOW_CONNECT='TRUE';
    'VSS_BU4':
      PIN_NUMBER='(0,0,0,0,0,0,0,0,0,0,0,0,0,0,0,0,0,0,0,0,0,0,0,0,0,0,0,0,0,0,0~
,0,0,BU4,0,0,0,0,0,0)';
      PINUSE='POWER';
      NO_LOAD_CHECK='Both';
      NO_IO_CHECK='Both';
      NO_ASSERT_CHECK='TRUE';
      NO_DIR_CHECK='TRUE';
      ALLOW_CONNECT='TRUE';
    'VSS_BU6':
      PIN_NUMBER='(0,0,0,0,0,0,0,0,0,0,0,0,0,0,0,0,0,0,0,0,0,0,0,0,0,0,0,0,0,0,0~
,0,0,BU6,0,0,0,0,0,0)';
      PINUSE='POWER';
      NO_LOAD_CHECK='Both';
      NO_IO_CHECK='Both';
      NO_ASSERT_CHECK='TRUE';
      NO_DIR_CHECK='TRUE';
      ALLOW_CONNECT='TRUE';
    'VSS_BU8':
      PIN_NUMBER='(0,0,0,0,0,0,0,0,0,0,0,0,0,0,0,0,0,0,0,0,0,0,0,0,0,0,0,0,0,0,0~
,0,0,BU8,0,0,0,0,0,0)';
      PINUSE='POWER';
      NO_LOAD_CHECK='Both';
      NO_IO_CHECK='Both';
      NO_ASSERT_CHECK='TRUE';
      NO_DIR_CHECK='TRUE';
      ALLOW_CONNECT='TRUE';
    'VSS_BU11':
      PIN_NUMBER='(0,0,0,0,0,0,0,0,0,0,0,0,0,0,0,0,0,0,0,0,0,0,0,0,0,0,0,0,0,0,0~
,0,0,BU11,0,0,0,0,0,0)';
      PINUSE='POWER';
      NO_LOAD_CHECK='Both';
      NO_IO_CHECK='Both';
      NO_ASSERT_CHECK='TRUE';
      NO_DIR_CHECK='TRUE';
      ALLOW_CONNECT='TRUE';
    'VSS_BU13':
      PIN_NUMBER='(0,0,0,0,0,0,0,0,0,0,0,0,0,0,0,0,0,0,0,0,0,0,0,0,0,0,0,0,0,0,0~
,0,0,BU13,0,0,0,0,0,0)';
      PINUSE='POWER';
      NO_LOAD_CHECK='Both';
      NO_IO_CHECK='Both';
      NO_ASSERT_CHECK='TRUE';
      NO_DIR_CHECK='TRUE';
      ALLOW_CONNECT='TRUE';
    'VSS_BU15':
      PIN_NUMBER='(0,0,0,0,0,0,0,0,0,0,0,0,0,0,0,0,0,0,0,0,0,0,0,0,0,0,0,0,0,0,0~
,0,0,BU15,0,0,0,0,0,0)';
      PINUSE='POWER';
      NO_LOAD_CHECK='Both';
      NO_IO_CHECK='Both';
      NO_ASSERT_CHECK='TRUE';
      NO_DIR_CHECK='TRUE';
      ALLOW_CONNECT='TRUE';
    'VSS_BU18':
      PIN_NUMBER='(0,0,0,0,0,0,0,0,0,0,0,0,0,0,0,0,0,0,0,0,0,0,0,0,0,0,0,0,0,0,0~
,0,0,BU18,0,0,0,0,0,0)';
      PINUSE='POWER';
      NO_LOAD_CHECK='Both';
      NO_IO_CHECK='Both';
      NO_ASSERT_CHECK='TRUE';
      NO_DIR_CHECK='TRUE';
      ALLOW_CONNECT='TRUE';
    'VSS_BU20':
      PIN_NUMBER='(0,0,0,0,0,0,0,0,0,0,0,0,0,0,0,0,0,0,0,0,0,0,0,0,0,0,0,0,0,0,0~
,0,0,BU20,0,0,0,0,0,0)';
      PINUSE='POWER';
      NO_LOAD_CHECK='Both';
      NO_IO_CHECK='Both';
      NO_ASSERT_CHECK='TRUE';
      NO_DIR_CHECK='TRUE';
      ALLOW_CONNECT='TRUE';
    'VSS_BU22':
      PIN_NUMBER='(0,0,0,0,0,0,0,0,0,0,0,0,0,0,0,0,0,0,0,0,0,0,0,0,0,0,0,0,0,0,0~
,0,0,BU22,0,0,0,0,0,0)';
      PINUSE='POWER';
      NO_LOAD_CHECK='Both';
      NO_IO_CHECK='Both';
      NO_ASSERT_CHECK='TRUE';
      NO_DIR_CHECK='TRUE';
      ALLOW_CONNECT='TRUE';
    'VSS_BU25':
      PIN_NUMBER='(0,0,0,0,0,0,0,0,0,0,0,0,0,0,0,0,0,0,0,0,0,0,0,0,0,0,0,0,0,0,0~
,0,0,BU25,0,0,0,0,0,0)';
      PINUSE='POWER';
      NO_LOAD_CHECK='Both';
      NO_IO_CHECK='Both';
      NO_ASSERT_CHECK='TRUE';
      NO_DIR_CHECK='TRUE';
      ALLOW_CONNECT='TRUE';
    'VSS_BU28':
      PIN_NUMBER='(0,0,0,0,0,0,0,0,0,0,0,0,0,0,0,0,0,0,0,0,0,0,0,0,0,0,0,0,0,0,0~
,0,0,BU28,0,0,0,0,0,0)';
      PINUSE='POWER';
      NO_LOAD_CHECK='Both';
      NO_IO_CHECK='Both';
      NO_ASSERT_CHECK='TRUE';
      NO_DIR_CHECK='TRUE';
      ALLOW_CONNECT='TRUE';
    'VSS_BU31':
      PIN_NUMBER='(0,0,0,0,0,0,0,0,0,0,0,0,0,0,0,0,0,0,0,0,0,0,0,0,0,0,0,0,0,0,0~
,0,0,BU31,0,0,0,0,0,0)';
      PINUSE='POWER';
      NO_LOAD_CHECK='Both';
      NO_IO_CHECK='Both';
      NO_ASSERT_CHECK='TRUE';
      NO_DIR_CHECK='TRUE';
      ALLOW_CONNECT='TRUE';
    'VSS_BU34':
      PIN_NUMBER='(0,0,0,0,0,0,0,0,0,0,0,0,0,0,0,0,0,0,0,0,0,0,0,0,0,0,0,0,0,0,0~
,0,0,BU34,0,0,0,0,0,0)';
      PINUSE='POWER';
      NO_LOAD_CHECK='Both';
      NO_IO_CHECK='Both';
      NO_ASSERT_CHECK='TRUE';
      NO_DIR_CHECK='TRUE';
      ALLOW_CONNECT='TRUE';
    'VSS_BU35':
      PIN_NUMBER='(0,0,0,0,0,0,0,0,0,0,0,0,0,0,0,0,0,0,0,0,0,0,0,0,0,0,0,0,0,0,0~
,0,0,BU35,0,0,0,0,0,0)';
      PINUSE='POWER';
      NO_LOAD_CHECK='Both';
      NO_IO_CHECK='Both';
      NO_ASSERT_CHECK='TRUE';
      NO_DIR_CHECK='TRUE';
      ALLOW_CONNECT='TRUE';
    'VSS_BU36':
      PIN_NUMBER='(0,0,0,0,0,0,0,0,0,0,0,0,0,0,0,0,0,0,0,0,0,0,0,0,0,0,0,0,0,0,0~
,0,0,BU36,0,0,0,0,0,0)';
      PINUSE='POWER';
      NO_LOAD_CHECK='Both';
      NO_IO_CHECK='Both';
      NO_ASSERT_CHECK='TRUE';
      NO_DIR_CHECK='TRUE';
      ALLOW_CONNECT='TRUE';
    'VSS_BU40':
      PIN_NUMBER='(0,0,0,0,0,0,0,0,0,0,0,0,0,0,0,0,0,0,0,0,0,0,0,0,0,0,0,0,0,0,0~
,0,0,BU40,0,0,0,0,0,0)';
      PINUSE='POWER';
      NO_LOAD_CHECK='Both';
      NO_IO_CHECK='Both';
      NO_ASSERT_CHECK='TRUE';
      NO_DIR_CHECK='TRUE';
      ALLOW_CONNECT='TRUE';
    'VSS_BU41':
      PIN_NUMBER='(0,0,0,0,0,0,0,0,0,0,0,0,0,0,0,0,0,0,0,0,0,0,0,0,0,0,0,0,0,0,0~
,0,0,BU41,0,0,0,0,0,0)';
      PINUSE='POWER';
      NO_LOAD_CHECK='Both';
      NO_IO_CHECK='Both';
      NO_ASSERT_CHECK='TRUE';
      NO_DIR_CHECK='TRUE';
      ALLOW_CONNECT='TRUE';
    'VSS_BU42':
      PIN_NUMBER='(0,0,0,0,0,0,0,0,0,0,0,0,0,0,0,0,0,0,0,0,0,0,0,0,0,0,0,0,0,0,0~
,0,0,BU42,0,0,0,0,0,0)';
      PINUSE='POWER';
      NO_LOAD_CHECK='Both';
      NO_IO_CHECK='Both';
      NO_ASSERT_CHECK='TRUE';
      NO_DIR_CHECK='TRUE';
      ALLOW_CONNECT='TRUE';
    'VSS_BU45':
      PIN_NUMBER='(0,0,0,0,0,0,0,0,0,0,0,0,0,0,0,0,0,0,0,0,0,0,0,0,0,0,0,0,0,0,0~
,0,0,BU45,0,0,0,0,0,0)';
      PINUSE='POWER';
      NO_LOAD_CHECK='Both';
      NO_IO_CHECK='Both';
      NO_ASSERT_CHECK='TRUE';
      NO_DIR_CHECK='TRUE';
      ALLOW_CONNECT='TRUE';
    'VSS_BU48':
      PIN_NUMBER='(0,0,0,0,0,0,0,0,0,0,0,0,0,0,0,0,0,0,0,0,0,0,0,0,0,0,0,0,0,0,0~
,0,0,BU48,0,0,0,0,0,0)';
      PINUSE='POWER';
      NO_LOAD_CHECK='Both';
      NO_IO_CHECK='Both';
      NO_ASSERT_CHECK='TRUE';
      NO_DIR_CHECK='TRUE';
      ALLOW_CONNECT='TRUE';
    'VSS_BU51':
      PIN_NUMBER='(0,0,0,0,0,0,0,0,0,0,0,0,0,0,0,0,0,0,0,0,0,0,0,0,0,0,0,0,0,0,0~
,0,0,BU51,0,0,0,0,0,0)';
      PINUSE='POWER';
      NO_LOAD_CHECK='Both';
      NO_IO_CHECK='Both';
      NO_ASSERT_CHECK='TRUE';
      NO_DIR_CHECK='TRUE';
      ALLOW_CONNECT='TRUE';
    'VSS_BU54':
      PIN_NUMBER='(0,0,0,0,0,0,0,0,0,0,0,0,0,0,0,0,0,0,0,0,0,0,0,0,0,0,0,0,0,0,0~
,0,0,BU54,0,0,0,0,0,0)';
      PINUSE='POWER';
      NO_LOAD_CHECK='Both';
      NO_IO_CHECK='Both';
      NO_ASSERT_CHECK='TRUE';
      NO_DIR_CHECK='TRUE';
      ALLOW_CONNECT='TRUE';
    'VSS_BU56':
      PIN_NUMBER='(0,0,0,0,0,0,0,0,0,0,0,0,0,0,0,0,0,0,0,0,0,0,0,0,0,0,0,0,0,0,0~
,0,0,BU56,0,0,0,0,0,0)';
      PINUSE='POWER';
      NO_LOAD_CHECK='Both';
      NO_IO_CHECK='Both';
      NO_ASSERT_CHECK='TRUE';
      NO_DIR_CHECK='TRUE';
      ALLOW_CONNECT='TRUE';
    'VSS_BU58':
      PIN_NUMBER='(0,0,0,0,0,0,0,0,0,0,0,0,0,0,0,0,0,0,0,0,0,0,0,0,0,0,0,0,0,0,0~
,0,0,BU58,0,0,0,0,0,0)';
      PINUSE='POWER';
      NO_LOAD_CHECK='Both';
      NO_IO_CHECK='Both';
      NO_ASSERT_CHECK='TRUE';
      NO_DIR_CHECK='TRUE';
      ALLOW_CONNECT='TRUE';
    'VSS_BU61':
      PIN_NUMBER='(0,0,0,0,0,0,0,0,0,0,0,0,0,0,0,0,0,0,0,0,0,0,0,0,0,0,0,0,0,0,0~
,0,0,BU61,0,0,0,0,0,0)';
      PINUSE='POWER';
      NO_LOAD_CHECK='Both';
      NO_IO_CHECK='Both';
      NO_ASSERT_CHECK='TRUE';
      NO_DIR_CHECK='TRUE';
      ALLOW_CONNECT='TRUE';
    'VSS_BU63':
      PIN_NUMBER='(0,0,0,0,0,0,0,0,0,0,0,0,0,0,0,0,0,0,0,0,0,0,0,0,0,0,0,0,0,0,0~
,0,0,BU63,0,0,0,0,0,0)';
      PINUSE='POWER';
      NO_LOAD_CHECK='Both';
      NO_IO_CHECK='Both';
      NO_ASSERT_CHECK='TRUE';
      NO_DIR_CHECK='TRUE';
      ALLOW_CONNECT='TRUE';
    'VSS_BU65':
      PIN_NUMBER='(0,0,0,0,0,0,0,0,0,0,0,0,0,0,0,0,0,0,0,0,0,0,0,0,0,0,0,0,0,0,0~
,0,0,BU65,0,0,0,0,0,0)';
      PINUSE='POWER';
      NO_LOAD_CHECK='Both';
      NO_IO_CHECK='Both';
      NO_ASSERT_CHECK='TRUE';
      NO_DIR_CHECK='TRUE';
      ALLOW_CONNECT='TRUE';
    'VSS_BU68':
      PIN_NUMBER='(0,0,0,0,0,0,0,0,0,0,0,0,0,0,0,0,0,0,0,0,0,0,0,0,0,0,0,0,0,0,0~
,0,0,BU68,0,0,0,0,0,0)';
      PINUSE='POWER';
      NO_LOAD_CHECK='Both';
      NO_IO_CHECK='Both';
      NO_ASSERT_CHECK='TRUE';
      NO_DIR_CHECK='TRUE';
      ALLOW_CONNECT='TRUE';
    'VSS_BU70':
      PIN_NUMBER='(0,0,0,0,0,0,0,0,0,0,0,0,0,0,0,0,0,0,0,0,0,0,0,0,0,0,0,0,0,0,0~
,0,0,BU70,0,0,0,0,0,0)';
      PINUSE='POWER';
      NO_LOAD_CHECK='Both';
      NO_IO_CHECK='Both';
      NO_ASSERT_CHECK='TRUE';
      NO_DIR_CHECK='TRUE';
      ALLOW_CONNECT='TRUE';
    'VSS_BU72':
      PIN_NUMBER='(0,0,0,0,0,0,0,0,0,0,0,0,0,0,0,0,0,0,0,0,0,0,0,0,0,0,0,0,0,0,0~
,0,0,BU72,0,0,0,0,0,0)';
      PINUSE='POWER';
      NO_LOAD_CHECK='Both';
      NO_IO_CHECK='Both';
      NO_ASSERT_CHECK='TRUE';
      NO_DIR_CHECK='TRUE';
      ALLOW_CONNECT='TRUE';
    'VSS_BU75':
      PIN_NUMBER='(0,0,0,0,0,0,0,0,0,0,0,0,0,0,0,0,0,0,0,0,0,0,0,0,0,0,0,0,0,0,0~
,0,0,BU75,0,0,0,0,0,0)';
      PINUSE='POWER';
      NO_LOAD_CHECK='Both';
      NO_IO_CHECK='Both';
      NO_ASSERT_CHECK='TRUE';
      NO_DIR_CHECK='TRUE';
      ALLOW_CONNECT='TRUE';
    'VSS_BV3':
      PIN_NUMBER='(0,0,0,0,0,0,0,0,0,0,0,0,0,0,0,0,0,0,0,0,0,0,0,0,0,0,0,0,0,0,0~
,0,0,BV3,0,0,0,0,0,0)';
      PINUSE='POWER';
      NO_LOAD_CHECK='Both';
      NO_IO_CHECK='Both';
      NO_ASSERT_CHECK='TRUE';
      NO_DIR_CHECK='TRUE';
      ALLOW_CONNECT='TRUE';
    'VSS_BV8':
      PIN_NUMBER='(0,0,0,0,0,0,0,0,0,0,0,0,0,0,0,0,0,0,0,0,0,0,0,0,0,0,0,0,0,0,0~
,0,0,BV8,0,0,0,0,0,0)';
      PINUSE='POWER';
      NO_LOAD_CHECK='Both';
      NO_IO_CHECK='Both';
      NO_ASSERT_CHECK='TRUE';
      NO_DIR_CHECK='TRUE';
      ALLOW_CONNECT='TRUE';
    'VSS_BV10':
      PIN_NUMBER='(0,0,0,0,0,0,0,0,0,0,0,0,0,0,0,0,0,0,0,0,0,0,0,0,0,0,0,0,0,0,0~
,0,0,BV10,0,0,0,0,0,0)';
      PINUSE='POWER';
      NO_LOAD_CHECK='Both';
      NO_IO_CHECK='Both';
      NO_ASSERT_CHECK='TRUE';
      NO_DIR_CHECK='TRUE';
      ALLOW_CONNECT='TRUE';
    'VSS_BV15':
      PIN_NUMBER='(0,0,0,0,0,0,0,0,0,0,0,0,0,0,0,0,0,0,0,0,0,0,0,0,0,0,0,0,0,0,0~
,0,0,BV15,0,0,0,0,0,0)';
      PINUSE='POWER';
      NO_LOAD_CHECK='Both';
      NO_IO_CHECK='Both';
      NO_ASSERT_CHECK='TRUE';
      NO_DIR_CHECK='TRUE';
      ALLOW_CONNECT='TRUE';
    'VSS_BV17':
      PIN_NUMBER='(0,0,0,0,0,0,0,0,0,0,0,0,0,0,0,0,0,0,0,0,0,0,0,0,0,0,0,0,0,0,0~
,0,0,BV17,0,0,0,0,0,0)';
      PINUSE='POWER';
      NO_LOAD_CHECK='Both';
      NO_IO_CHECK='Both';
      NO_ASSERT_CHECK='TRUE';
      NO_DIR_CHECK='TRUE';
      ALLOW_CONNECT='TRUE';
    'VSS_BV23':
      PIN_NUMBER='(0,0,0,0,0,0,0,0,0,0,0,0,0,0,0,0,0,0,0,0,0,0,0,0,0,0,0,0,0,0,0~
,0,0,BV23,0,0,0,0,0,0)';
      PINUSE='POWER';
      NO_LOAD_CHECK='Both';
      NO_IO_CHECK='Both';
      NO_ASSERT_CHECK='TRUE';
      NO_DIR_CHECK='TRUE';
      ALLOW_CONNECT='TRUE';
    'VSS_BV24':
      PIN_NUMBER='(0,0,0,0,0,0,0,0,0,0,0,0,0,0,0,0,0,0,0,0,0,0,0,0,0,0,0,0,0,0,0~
,0,0,BV24,0,0,0,0,0,0)';
      PINUSE='POWER';
      NO_LOAD_CHECK='Both';
      NO_IO_CHECK='Both';
      NO_ASSERT_CHECK='TRUE';
      NO_DIR_CHECK='TRUE';
      ALLOW_CONNECT='TRUE';
    'VSS_BV25':
      PIN_NUMBER='(0,0,0,0,0,0,0,0,0,0,0,0,0,0,0,0,0,0,0,0,0,0,0,0,0,0,0,0,0,0,0~
,0,0,BV25,0,0,0,0,0,0)';
      PINUSE='POWER';
      NO_LOAD_CHECK='Both';
      NO_IO_CHECK='Both';
      NO_ASSERT_CHECK='TRUE';
      NO_DIR_CHECK='TRUE';
      ALLOW_CONNECT='TRUE';
    'VSS_BV26':
      PIN_NUMBER='(0,0,0,0,0,0,0,0,0,0,0,0,0,0,0,0,0,0,0,0,0,0,0,0,0,0,0,0,0,0,0~
,0,0,BV26,0,0,0,0,0,0)';
      PINUSE='POWER';
      NO_LOAD_CHECK='Both';
      NO_IO_CHECK='Both';
      NO_ASSERT_CHECK='TRUE';
      NO_DIR_CHECK='TRUE';
      ALLOW_CONNECT='TRUE';
    'VSS_BV27':
      PIN_NUMBER='(0,0,0,0,0,0,0,0,0,0,0,0,0,0,0,0,0,0,0,0,0,0,0,0,0,0,0,0,0,0,0~
,0,0,BV27,0,0,0,0,0,0)';
      PINUSE='POWER';
      NO_LOAD_CHECK='Both';
      NO_IO_CHECK='Both';
      NO_ASSERT_CHECK='TRUE';
      NO_DIR_CHECK='TRUE';
      ALLOW_CONNECT='TRUE';
    'VSS_BV28':
      PIN_NUMBER='(0,0,0,0,0,0,0,0,0,0,0,0,0,0,0,0,0,0,0,0,0,0,0,0,0,0,0,0,0,0,0~
,0,0,BV28,0,0,0,0,0,0)';
      PINUSE='POWER';
      NO_LOAD_CHECK='Both';
      NO_IO_CHECK='Both';
      NO_ASSERT_CHECK='TRUE';
      NO_DIR_CHECK='TRUE';
      ALLOW_CONNECT='TRUE';
    'VSS_BV29':
      PIN_NUMBER='(0,0,0,0,0,0,0,0,0,0,0,0,0,0,0,0,0,0,0,0,0,0,0,0,0,0,0,0,0,0,0~
,0,0,BV29,0,0,0,0,0,0)';
      PINUSE='POWER';
      NO_LOAD_CHECK='Both';
      NO_IO_CHECK='Both';
      NO_ASSERT_CHECK='TRUE';
      NO_DIR_CHECK='TRUE';
      ALLOW_CONNECT='TRUE';
    'VSS_BV30':
      PIN_NUMBER='(0,0,0,0,0,0,0,0,0,0,0,0,0,0,0,0,0,0,0,0,0,0,0,0,0,0,0,0,0,0,0~
,0,0,BV30,0,0,0,0,0,0)';
      PINUSE='POWER';
      NO_LOAD_CHECK='Both';
      NO_IO_CHECK='Both';
      NO_ASSERT_CHECK='TRUE';
      NO_DIR_CHECK='TRUE';
      ALLOW_CONNECT='TRUE';
    'VSS_BV31':
      PIN_NUMBER='(0,0,0,0,0,0,0,0,0,0,0,0,0,0,0,0,0,0,0,0,0,0,0,0,0,0,0,0,0,0,0~
,0,0,BV31,0,0,0,0,0,0)';
      PINUSE='POWER';
      NO_LOAD_CHECK='Both';
      NO_IO_CHECK='Both';
      NO_ASSERT_CHECK='TRUE';
      NO_DIR_CHECK='TRUE';
      ALLOW_CONNECT='TRUE';
    'VSS_BV32':
      PIN_NUMBER='(0,0,0,0,0,0,0,0,0,0,0,0,0,0,0,0,0,0,0,0,0,0,0,0,0,0,0,0,0,0,0~
,0,0,BV32,0,0,0,0,0,0)';
      PINUSE='POWER';
      NO_LOAD_CHECK='Both';
      NO_IO_CHECK='Both';
      NO_ASSERT_CHECK='TRUE';
      NO_DIR_CHECK='TRUE';
      ALLOW_CONNECT='TRUE';
    'VSS_BV33':
      PIN_NUMBER='(0,0,0,0,0,0,0,0,0,0,0,0,0,0,0,0,0,0,0,0,0,0,0,0,0,0,0,0,0,0,0~
,0,0,BV33,0,0,0,0,0,0)';
      PINUSE='POWER';
      NO_LOAD_CHECK='Both';
      NO_IO_CHECK='Both';
      NO_ASSERT_CHECK='TRUE';
      NO_DIR_CHECK='TRUE';
      ALLOW_CONNECT='TRUE';
    'VSS_BV34':
      PIN_NUMBER='(0,0,0,0,0,0,0,0,0,0,0,0,0,0,0,0,0,0,0,0,0,0,0,0,0,0,0,0,0,0,0~
,0,0,BV34,0,0,0,0,0,0)';
      PINUSE='POWER';
      NO_LOAD_CHECK='Both';
      NO_IO_CHECK='Both';
      NO_ASSERT_CHECK='TRUE';
      NO_DIR_CHECK='TRUE';
      ALLOW_CONNECT='TRUE';
    'VSS_BV39':
      PIN_NUMBER='(0,0,0,0,0,0,0,0,0,0,0,0,0,0,0,0,0,0,0,0,0,0,0,0,0,0,0,0,0,0,0~
,0,0,BV39,0,0,0,0,0,0)';
      PINUSE='POWER';
      NO_LOAD_CHECK='Both';
      NO_IO_CHECK='Both';
      NO_ASSERT_CHECK='TRUE';
      NO_DIR_CHECK='TRUE';
      ALLOW_CONNECT='TRUE';
    'VSS_BV43':
      PIN_NUMBER='(0,0,0,0,0,0,0,0,0,0,0,0,0,0,0,0,0,0,0,0,0,0,0,0,0,0,0,0,0,0,0~
,0,0,BV43,0,0,0,0,0,0)';
      PINUSE='POWER';
      NO_LOAD_CHECK='Both';
      NO_IO_CHECK='Both';
      NO_ASSERT_CHECK='TRUE';
      NO_DIR_CHECK='TRUE';
      ALLOW_CONNECT='TRUE';
    'VSS_BV44':
      PIN_NUMBER='(0,0,0,0,0,0,0,0,0,0,0,0,0,0,0,0,0,0,0,0,0,0,0,0,0,0,0,0,0,0,0~
,0,0,BV44,0,0,0,0,0,0)';
      PINUSE='POWER';
      NO_LOAD_CHECK='Both';
      NO_IO_CHECK='Both';
      NO_ASSERT_CHECK='TRUE';
      NO_DIR_CHECK='TRUE';
      ALLOW_CONNECT='TRUE';
    'VSS_BV45':
      PIN_NUMBER='(0,0,0,0,0,0,0,0,0,0,0,0,0,0,0,0,0,0,0,0,0,0,0,0,0,0,0,0,0,0,0~
,0,0,BV45,0,0,0,0,0,0)';
      PINUSE='POWER';
      NO_LOAD_CHECK='Both';
      NO_IO_CHECK='Both';
      NO_ASSERT_CHECK='TRUE';
      NO_DIR_CHECK='TRUE';
      ALLOW_CONNECT='TRUE';
    'MLB_DQS_L9':
      PIN_NUMBER='(0,0,0,0,0,0,0,0,0,0,0,0,0,0,0,0,0,0,0,0,0,0,0,0,0,0,0,0,0,0,0~
,0,0,0,BW9,0,0,0,0,0)';
      BIDIRECTIONAL='TRUE';
      INPUT_LOAD='(-0.01,0.01)';
      OUTPUT_LOAD='(1.0,-1.0)';
      PINUSE='BI';
    'MLB_DQS_H5':
      PIN_NUMBER='(0,0,0,0,0,0,0,0,0,0,0,0,0,0,0,0,0,0,0,0,0,0,0,0,0,0,0,0,0,0,0~
,0,0,0,CF11,0,0,0,0,0)';
      BIDIRECTIONAL='TRUE';
      INPUT_LOAD='(-0.01,0.01)';
      OUTPUT_LOAD='(1.0,-1.0)';
      PINUSE='BI';
    'MLB_DATA4':
      PIN_NUMBER='(0,0,0,0,0,0,0,0,0,0,0,0,0,0,0,0,0,0,0,0,0,0,0,0,0,0,0,0,0,0,0~
,0,0,0,CF9,0,0,0,0,0)';
      BIDIRECTIONAL='TRUE';
      INPUT_LOAD='(-0.01,0.01)';
      OUTPUT_LOAD='(1.0,-1.0)';
      PINUSE='BI';
    'MLB_CA1':
      PIN_NUMBER='(0,0,0,0,0,0,0,0,0,0,0,0,0,0,0,0,0,0,0,0,0,0,0,0,0,0,0,0,0,0,0~
,0,0,0,BH11,0,0,0,0,0)';
      OUTPUT_LOAD='(1.0,-1.0)';
      PINUSE='OUT';
    'MLA_DATA22':
      PIN_NUMBER='(0,0,0,0,0,0,0,0,0,0,0,0,0,0,0,0,0,0,0,0,0,0,0,0,0,0,0,0,0,0,0~
,0,0,0,AB9,0,0,0,0,0)';
      BIDIRECTIONAL='TRUE';
      INPUT_LOAD='(-0.01,0.01)';
      OUTPUT_LOAD='(1.0,-1.0)';
      PINUSE='BI';
    'MLA_DATA11':
      PIN_NUMBER='(0,0,0,0,0,0,0,0,0,0,0,0,0,0,0,0,0,0,0,0,0,0,0,0,0,0,0,0,0,0,0~
,0,0,0,N10,0,0,0,0,0)';
      BIDIRECTIONAL='TRUE';
      INPUT_LOAD='(-0.01,0.01)';
      OUTPUT_LOAD='(1.0,-1.0)';
      PINUSE='BI';
    'MLA_DATA5':
      PIN_NUMBER='(0,0,0,0,0,0,0,0,0,0,0,0,0,0,0,0,0,0,0,0,0,0,0,0,0,0,0,0,0,0,0~
,0,0,0,K11,0,0,0,0,0)';
      BIDIRECTIONAL='TRUE';
      INPUT_LOAD='(-0.01,0.01)';
      OUTPUT_LOAD='(1.0,-1.0)';
      PINUSE='BI';
    'MLA_CHECK2':
      PIN_NUMBER='(0,0,0,0,0,0,0,0,0,0,0,0,0,0,0,0,0,0,0,0,0,0,0,0,0,0,0,0,0,0,0~
,0,0,0,AK9,0,0,0,0,0)';
      BIDIRECTIONAL='TRUE';
      INPUT_LOAD='(-0.01,0.01)';
      OUTPUT_LOAD='(1.0,-1.0)';
      PINUSE='BI';
    'MLA_CA2':
      PIN_NUMBER='(0,0,0,0,0,0,0,0,0,0,0,0,0,0,0,0,0,0,0,0,0,0,0,0,0,0,0,0,0,0,0~
,0,0,0,AY11,0,0,0,0,0)';
      OUTPUT_LOAD='(1.0,-1.0)';
      PINUSE='OUT';
    'ML_RESET_L':
      PIN_NUMBER='(0,0,0,0,0,0,0,0,0,0,0,0,0,0,0,0,0,0,0,0,0,0,0,0,0,0,0,0,0,0,0~
,0,0,0,AU10,0,0,0,0,0)';
      OUTPUT_LOAD='(1.0,-1.0)';
      PINUSE='OUT';
    'MLB_DQS_H6':
      PIN_NUMBER='(0,0,0,0,0,0,0,0,0,0,0,0,0,0,0,0,0,0,0,0,0,0,0,0,0,0,0,0,0,0,0~
,0,0,0,CM11,0,0,0,0,0)';
      BIDIRECTIONAL='TRUE';
      INPUT_LOAD='(-0.01,0.01)';
      OUTPUT_LOAD='(1.0,-1.0)';
      PINUSE='BI';
    'MLB_DATA5':
      PIN_NUMBER='(0,0,0,0,0,0,0,0,0,0,0,0,0,0,0,0,0,0,0,0,0,0,0,0,0,0,0,0,0,0,0~
,0,0,0,CG10,0,0,0,0,0)';
      BIDIRECTIONAL='TRUE';
      INPUT_LOAD='(-0.01,0.01)';
      OUTPUT_LOAD='(1.0,-1.0)';
      PINUSE='BI';
    'MLB_CA2':
      PIN_NUMBER='(0,0,0,0,0,0,0,0,0,0,0,0,0,0,0,0,0,0,0,0,0,0,0,0,0,0,0,0,0,0,0~
,0,0,0,BH9,0,0,0,0,0)';
      OUTPUT_LOAD='(1.0,-1.0)';
      PINUSE='OUT';
    'MLB0_CS_L0':
      PIN_NUMBER='(0,0,0,0,0,0,0,0,0,0,0,0,0,0,0,0,0,0,0,0,0,0,0,0,0,0,0,0,0,0,0~
,0,0,0,BM11,0,0,0,0,0)';
      OUTPUT_LOAD='(1.0,-1.0)';
      PINUSE='OUT';
    'MLA_DATA23':
      PIN_NUMBER='(0,0,0,0,0,0,0,0,0,0,0,0,0,0,0,0,0,0,0,0,0,0,0,0,0,0,0,0,0,0,0~
,0,0,0,AC10,0,0,0,0,0)';
      BIDIRECTIONAL='TRUE';
      INPUT_LOAD='(-0.01,0.01)';
      OUTPUT_LOAD='(1.0,-1.0)';
      PINUSE='BI';
    'MLA_DATA12':
      PIN_NUMBER='(0,0,0,0,0,0,0,0,0,0,0,0,0,0,0,0,0,0,0,0,0,0,0,0,0,0,0,0,0,0,0~
,0,0,0,R9,0,0,0,0,0)';
      BIDIRECTIONAL='TRUE';
      INPUT_LOAD='(-0.01,0.01)';
      OUTPUT_LOAD='(1.0,-1.0)';
      PINUSE='BI';
    'MLA_DATA6':
      PIN_NUMBER='(0,0,0,0,0,0,0,0,0,0,0,0,0,0,0,0,0,0,0,0,0,0,0,0,0,0,0,0,0,0,0~
,0,0,0,K9,0,0,0,0,0)';
      BIDIRECTIONAL='TRUE';
      INPUT_LOAD='(-0.01,0.01)';
      OUTPUT_LOAD='(1.0,-1.0)';
      PINUSE='BI';
    'MLA_CHECK3':
      PIN_NUMBER='(0,0,0,0,0,0,0,0,0,0,0,0,0,0,0,0,0,0,0,0,0,0,0,0,0,0,0,0,0,0,0~
,0,0,0,AL10,0,0,0,0,0)';
      BIDIRECTIONAL='TRUE';
      INPUT_LOAD='(-0.01,0.01)';
      OUTPUT_LOAD='(1.0,-1.0)';
      PINUSE='BI';
    'MLA_CA3':
      PIN_NUMBER='(0,0,0,0,0,0,0,0,0,0,0,0,0,0,0,0,0,0,0,0,0,0,0,0,0,0,0,0,0,0,0~
,0,0,0,BA10,0,0,0,0,0)';
      OUTPUT_LOAD='(1.0,-1.0)';
      PINUSE='OUT';
    'MLB_DQS_H7':
      PIN_NUMBER='(0,0,0,0,0,0,0,0,0,0,0,0,0,0,0,0,0,0,0,0,0,0,0,0,0,0,0,0,0,0,0~
,0,0,0,CV11,0,0,0,0,0)';
      BIDIRECTIONAL='TRUE';
      INPUT_LOAD='(-0.01,0.01)';
      OUTPUT_LOAD='(1.0,-1.0)';
      PINUSE='BI';
    'MLB_DATA6':
      PIN_NUMBER='(0,0,0,0,0,0,0,0,0,0,0,0,0,0,0,0,0,0,0,0,0,0,0,0,0,0,0,0,0,0,0~
,0,0,0,CG9,0,0,0,0,0)';
      BIDIRECTIONAL='TRUE';
      INPUT_LOAD='(-0.01,0.01)';
      OUTPUT_LOAD='(1.0,-1.0)';
      PINUSE='BI';
    'MLB_CA3':
      PIN_NUMBER='(0,0,0,0,0,0,0,0,0,0,0,0,0,0,0,0,0,0,0,0,0,0,0,0,0,0,0,0,0,0,0~
,0,0,0,BJ9,0,0,0,0,0)';
      OUTPUT_LOAD='(1.0,-1.0)';
      PINUSE='OUT';
    'MLB1_CS_L0':
      PIN_NUMBER='(0,0,0,0,0,0,0,0,0,0,0,0,0,0,0,0,0,0,0,0,0,0,0,0,0,0,0,0,0,0,0~
,0,0,0,BL9,0,0,0,0,0)';
      OUTPUT_LOAD='(1.0,-1.0)';
      PINUSE='OUT';
    'MLB0_CS_L1':
      PIN_NUMBER='(0,0,0,0,0,0,0,0,0,0,0,0,0,0,0,0,0,0,0,0,0,0,0,0,0,0,0,0,0,0,0~
,0,0,0,BN9,0,0,0,0,0)';
      OUTPUT_LOAD='(1.0,-1.0)';
      PINUSE='OUT';
    'MLA_DQS_L0':
      PIN_NUMBER='(0,0,0,0,0,0,0,0,0,0,0,0,0,0,0,0,0,0,0,0,0,0,0,0,0,0,0,0,0,0,0~
,0,0,0,H9,0,0,0,0,0)';
      BIDIRECTIONAL='TRUE';
      INPUT_LOAD='(-0.01,0.01)';
      OUTPUT_LOAD='(1.0,-1.0)';
      PINUSE='BI';
    'MLA_DATA24':
      PIN_NUMBER='(0,0,0,0,0,0,0,0,0,0,0,0,0,0,0,0,0,0,0,0,0,0,0,0,0,0,0,0,0,0,0~
,0,0,0,AC9,0,0,0,0,0)';
      BIDIRECTIONAL='TRUE';
      INPUT_LOAD='(-0.01,0.01)';
      OUTPUT_LOAD='(1.0,-1.0)';
      PINUSE='BI';
    'MLA_DATA13':
      PIN_NUMBER='(0,0,0,0,0,0,0,0,0,0,0,0,0,0,0,0,0,0,0,0,0,0,0,0,0,0,0,0,0,0,0~
,0,0,0,T11,0,0,0,0,0)';
      BIDIRECTIONAL='TRUE';
      INPUT_LOAD='(-0.01,0.01)';
      OUTPUT_LOAD='(1.0,-1.0)';
      PINUSE='BI';
    'MLA_DATA7':
      PIN_NUMBER='(0,0,0,0,0,0,0,0,0,0,0,0,0,0,0,0,0,0,0,0,0,0,0,0,0,0,0,0,0,0,0~
,0,0,0,L10,0,0,0,0,0)';
      BIDIRECTIONAL='TRUE';
      INPUT_LOAD='(-0.01,0.01)';
      OUTPUT_LOAD='(1.0,-1.0)';
      PINUSE='BI';
    'MLA_CHECK4':
      PIN_NUMBER='(0,0,0,0,0,0,0,0,0,0,0,0,0,0,0,0,0,0,0,0,0,0,0,0,0,0,0,0,0,0,0~
,0,0,0,AN9,0,0,0,0,0)';
      BIDIRECTIONAL='TRUE';
      INPUT_LOAD='(-0.01,0.01)';
      OUTPUT_LOAD='(1.0,-1.0)';
      PINUSE='BI';
    'MLA_CA4':
      PIN_NUMBER='(0,0,0,0,0,0,0,0,0,0,0,0,0,0,0,0,0,0,0,0,0,0,0,0,0,0,0,0,0,0,0~
,0,0,0,BA9,0,0,0,0,0)';
      OUTPUT_LOAD='(1.0,-1.0)';
      PINUSE='OUT';
    'MLB_DQS_H8':
      PIN_NUMBER='(0,0,0,0,0,0,0,0,0,0,0,0,0,0,0,0,0,0,0,0,0,0,0,0,0,0,0,0,0,0,0~
,0,0,0,DD11,0,0,0,0,0)';
      BIDIRECTIONAL='TRUE';
      INPUT_LOAD='(-0.01,0.01)';
      OUTPUT_LOAD='(1.0,-1.0)';
      PINUSE='BI';
    'MLB_DATA30':
      PIN_NUMBER='(0,0,0,0,0,0,0,0,0,0,0,0,0,0,0,0,0,0,0,0,0,0,0,0,0,0,0,0,0,0,0~
,0,0,0,DE9,0,0,0,0,0)';
      BIDIRECTIONAL='TRUE';
      INPUT_LOAD='(-0.01,0.01)';
      OUTPUT_LOAD='(1.0,-1.0)';
      PINUSE='BI';
    'MLB_DATA7':
      PIN_NUMBER='(0,0,0,0,0,0,0,0,0,0,0,0,0,0,0,0,0,0,0,0,0,0,0,0,0,0,0,0,0,0,0~
,0,0,0,CH11,0,0,0,0,0)';
      BIDIRECTIONAL='TRUE';
      INPUT_LOAD='(-0.01,0.01)';
      OUTPUT_LOAD='(1.0,-1.0)';
      PINUSE='BI';
    'MLB_CA4':
      PIN_NUMBER='(0,0,0,0,0,0,0,0,0,0,0,0,0,0,0,0,0,0,0,0,0,0,0,0,0,0,0,0,0,0,0~
,0,0,0,BJ10,0,0,0,0,0)';
      OUTPUT_LOAD='(1.0,-1.0)';
      PINUSE='OUT';
    'MLB1_CS_L1':
      PIN_NUMBER='(0,0,0,0,0,0,0,0,0,0,0,0,0,0,0,0,0,0,0,0,0,0,0,0,0,0,0,0,0,0,0~
,0,0,0,BM9,0,0,0,0,0)';
      OUTPUT_LOAD='(1.0,-1.0)';
      PINUSE='OUT';
    'MLA_DQS_L1':
      PIN_NUMBER='(0,0,0,0,0,0,0,0,0,0,0,0,0,0,0,0,0,0,0,0,0,0,0,0,0,0,0,0,0,0,0~
,0,0,0,P9,0,0,0,0,0)';
      BIDIRECTIONAL='TRUE';
      INPUT_LOAD='(-0.01,0.01)';
      OUTPUT_LOAD='(1.0,-1.0)';
      PINUSE='BI';
    'MLA_DATA25':
      PIN_NUMBER='(0,0,0,0,0,0,0,0,0,0,0,0,0,0,0,0,0,0,0,0,0,0,0,0,0,0,0,0,0,0,0~
,0,0,0,AD11,0,0,0,0,0)';
      BIDIRECTIONAL='TRUE';
      INPUT_LOAD='(-0.01,0.01)';
      OUTPUT_LOAD='(1.0,-1.0)';
      PINUSE='BI';
    'MLA_DATA14':
      PIN_NUMBER='(0,0,0,0,0,0,0,0,0,0,0,0,0,0,0,0,0,0,0,0,0,0,0,0,0,0,0,0,0,0,0~
,0,0,0,T9,0,0,0,0,0)';
      BIDIRECTIONAL='TRUE';
      INPUT_LOAD='(-0.01,0.01)';
      OUTPUT_LOAD='(1.0,-1.0)';
      PINUSE='BI';
    'MLA_DATA8':
      PIN_NUMBER='(0,0,0,0,0,0,0,0,0,0,0,0,0,0,0,0,0,0,0,0,0,0,0,0,0,0,0,0,0,0,0~
,0,0,0,L9,0,0,0,0,0)';
      BIDIRECTIONAL='TRUE';
      INPUT_LOAD='(-0.01,0.01)';
      OUTPUT_LOAD='(1.0,-1.0)';
      PINUSE='BI';
    'MLA_CHECK5':
      PIN_NUMBER='(0,0,0,0,0,0,0,0,0,0,0,0,0,0,0,0,0,0,0,0,0,0,0,0,0,0,0,0,0,0,0~
,0,0,0,AP11,0,0,0,0,0)';
      BIDIRECTIONAL='TRUE';
      INPUT_LOAD='(-0.01,0.01)';
      OUTPUT_LOAD='(1.0,-1.0)';
      PINUSE='BI';
    'MLA_CA5':
      PIN_NUMBER='(0,0,0,0,0,0,0,0,0,0,0,0,0,0,0,0,0,0,0,0,0,0,0,0,0,0,0,0,0,0,0~
,0,0,0,BB9,0,0,0,0,0)';
      OUTPUT_LOAD='(1.0,-1.0)';
      PINUSE='OUT';
    'MLB_DQS_H9':
      PIN_NUMBER='(0,0,0,0,0,0,0,0,0,0,0,0,0,0,0,0,0,0,0,0,0,0,0,0,0,0,0,0,0,0,0~
,0,0,0,BV9,0,0,0,0,0)';
      BIDIRECTIONAL='TRUE';
      INPUT_LOAD='(-0.01,0.01)';
      OUTPUT_LOAD='(1.0,-1.0)';
      PINUSE='BI';
    'MLB_DATA31':
      PIN_NUMBER='(0,0,0,0,0,0,0,0,0,0,0,0,0,0,0,0,0,0,0,0,0,0,0,0,0,0,0,0,0,0,0~
,0,0,0,DF9,0,0,0,0,0)';
      BIDIRECTIONAL='TRUE';
      INPUT_LOAD='(-0.01,0.01)';
      OUTPUT_LOAD='(1.0,-1.0)';
      PINUSE='BI';
    'MLB_DATA20':
      PIN_NUMBER='(0,0,0,0,0,0,0,0,0,0,0,0,0,0,0,0,0,0,0,0,0,0,0,0,0,0,0,0,0,0,0~
,0,0,0,CV9,0,0,0,0,0)';
      BIDIRECTIONAL='TRUE';
      INPUT_LOAD='(-0.01,0.01)';
      OUTPUT_LOAD='(1.0,-1.0)';
      PINUSE='BI';
    'MLB_DATA8':
      PIN_NUMBER='(0,0,0,0,0,0,0,0,0,0,0,0,0,0,0,0,0,0,0,0,0,0,0,0,0,0,0,0,0,0,0~
,0,0,0,CH9,0,0,0,0,0)';
      BIDIRECTIONAL='TRUE';
      INPUT_LOAD='(-0.01,0.01)';
      OUTPUT_LOAD='(1.0,-1.0)';
      PINUSE='BI';
    'MLB_CHECK0':
      PIN_NUMBER='(0,0,0,0,0,0,0,0,0,0,0,0,0,0,0,0,0,0,0,0,0,0,0,0,0,0,0,0,0,0,0~
,0,0,0,BY9,0,0,0,0,0)';
      BIDIRECTIONAL='TRUE';
      INPUT_LOAD='(-0.01,0.01)';
      OUTPUT_LOAD='(1.0,-1.0)';
      PINUSE='BI';
    'MLB_CA5':
      PIN_NUMBER='(0,0,0,0,0,0,0,0,0,0,0,0,0,0,0,0,0,0,0,0,0,0,0,0,0,0,0,0,0,0,0~
,0,0,0,BK11,0,0,0,0,0)';
      OUTPUT_LOAD='(1.0,-1.0)';
      PINUSE='OUT';
    'MLA_DQS_L2':
      PIN_NUMBER='(0,0,0,0,0,0,0,0,0,0,0,0,0,0,0,0,0,0,0,0,0,0,0,0,0,0,0,0,0,0,0~
,0,0,0,Y9,0,0,0,0,0)';
      BIDIRECTIONAL='TRUE';
      INPUT_LOAD='(-0.01,0.01)';
      OUTPUT_LOAD='(1.0,-1.0)';
      PINUSE='BI';
    'MLA_DATA26':
      PIN_NUMBER='(0,0,0,0,0,0,0,0,0,0,0,0,0,0,0,0,0,0,0,0,0,0,0,0,0,0,0,0,0,0,0~
,0,0,0,AD9,0,0,0,0,0)';
      BIDIRECTIONAL='TRUE';
      INPUT_LOAD='(-0.01,0.01)';
      OUTPUT_LOAD='(1.0,-1.0)';
      PINUSE='BI';
    'MLA_DATA15':
      PIN_NUMBER='(0,0,0,0,0,0,0,0,0,0,0,0,0,0,0,0,0,0,0,0,0,0,0,0,0,0,0,0,0,0,0~
,0,0,0,U10,0,0,0,0,0)';
      BIDIRECTIONAL='TRUE';
      INPUT_LOAD='(-0.01,0.01)';
      OUTPUT_LOAD='(1.0,-1.0)';
      PINUSE='BI';
    'MLA_DATA9':
      PIN_NUMBER='(0,0,0,0,0,0,0,0,0,0,0,0,0,0,0,0,0,0,0,0,0,0,0,0,0,0,0,0,0,0,0~
,0,0,0,M11,0,0,0,0,0)';
      BIDIRECTIONAL='TRUE';
      INPUT_LOAD='(-0.01,0.01)';
      OUTPUT_LOAD='(1.0,-1.0)';
      PINUSE='BI';
    'MLA_CHECK6':
      PIN_NUMBER='(0,0,0,0,0,0,0,0,0,0,0,0,0,0,0,0,0,0,0,0,0,0,0,0,0,0,0,0,0,0,0~
,0,0,0,AP9,0,0,0,0,0)';
      BIDIRECTIONAL='TRUE';
      INPUT_LOAD='(-0.01,0.01)';
      OUTPUT_LOAD='(1.0,-1.0)';
      PINUSE='BI';
    'MLA_CA6':
      PIN_NUMBER='(0,0,0,0,0,0,0,0,0,0,0,0,0,0,0,0,0,0,0,0,0,0,0,0,0,0,0,0,0,0,0~
,0,0,0,BB11,0,0,0,0,0)';
      OUTPUT_LOAD='(1.0,-1.0)';
      PINUSE='OUT';
    'MLA0_RSP_L':
      PIN_NUMBER='(0,0,0,0,0,0,0,0,0,0,0,0,0,0,0,0,0,0,0,0,0,0,0,0,0,0,0,0,0,0,0~
,0,0,0,BN10,0,0,0,0,0)';
      INPUT_LOAD='(-0.01,0.01)';
      PINUSE='IN';
    'MLB_DATA21':
      PIN_NUMBER='(0,0,0,0,0,0,0,0,0,0,0,0,0,0,0,0,0,0,0,0,0,0,0,0,0,0,0,0,0,0,0~
,0,0,0,CW10,0,0,0,0,0)';
      BIDIRECTIONAL='TRUE';
      INPUT_LOAD='(-0.01,0.01)';
      OUTPUT_LOAD='(1.0,-1.0)';
      PINUSE='BI';
    'MLB_DATA10':
      PIN_NUMBER='(0,0,0,0,0,0,0,0,0,0,0,0,0,0,0,0,0,0,0,0,0,0,0,0,0,0,0,0,0,0,0~
,0,0,0,CJ9,0,0,0,0,0)';
      BIDIRECTIONAL='TRUE';
      INPUT_LOAD='(-0.01,0.01)';
      OUTPUT_LOAD='(1.0,-1.0)';
      PINUSE='BI';
    'MLB_DATA9':
      PIN_NUMBER='(0,0,0,0,0,0,0,0,0,0,0,0,0,0,0,0,0,0,0,0,0,0,0,0,0,0,0,0,0,0,0~
,0,0,0,CJ10,0,0,0,0,0)';
      BIDIRECTIONAL='TRUE';
      INPUT_LOAD='(-0.01,0.01)';
      OUTPUT_LOAD='(1.0,-1.0)';
      PINUSE='BI';
    'MLB_CHECK1':
      PIN_NUMBER='(0,0,0,0,0,0,0,0,0,0,0,0,0,0,0,0,0,0,0,0,0,0,0,0,0,0,0,0,0,0,0~
,0,0,0,CA10,0,0,0,0,0)';
      BIDIRECTIONAL='TRUE';
      INPUT_LOAD='(-0.01,0.01)';
      OUTPUT_LOAD='(1.0,-1.0)';
      PINUSE='BI';
    'MLB_CA6':
      PIN_NUMBER='(0,0,0,0,0,0,0,0,0,0,0,0,0,0,0,0,0,0,0,0,0,0,0,0,0,0,0,0,0,0,0~
,0,0,0,BK9,0,0,0,0,0)';
      OUTPUT_LOAD='(1.0,-1.0)';
      PINUSE='OUT';
    'MLA_DQS_L3':
      PIN_NUMBER='(0,0,0,0,0,0,0,0,0,0,0,0,0,0,0,0,0,0,0,0,0,0,0,0,0,0,0,0,0,0,0~
,0,0,0,AF9,0,0,0,0,0)';
      BIDIRECTIONAL='TRUE';
      INPUT_LOAD='(-0.01,0.01)';
      OUTPUT_LOAD='(1.0,-1.0)';
      PINUSE='BI';
    'MLA_DATA27':
      PIN_NUMBER='(0,0,0,0,0,0,0,0,0,0,0,0,0,0,0,0,0,0,0,0,0,0,0,0,0,0,0,0,0,0,0~
,0,0,0,AE10,0,0,0,0,0)';
      BIDIRECTIONAL='TRUE';
      INPUT_LOAD='(-0.01,0.01)';
      OUTPUT_LOAD='(1.0,-1.0)';
      PINUSE='BI';
    'MLA_DATA16':
      PIN_NUMBER='(0,0,0,0,0,0,0,0,0,0,0,0,0,0,0,0,0,0,0,0,0,0,0,0,0,0,0,0,0,0,0~
,0,0,0,U9,0,0,0,0,0)';
      BIDIRECTIONAL='TRUE';
      INPUT_LOAD='(-0.01,0.01)';
      OUTPUT_LOAD='(1.0,-1.0)';
      PINUSE='BI';
    'MLA_CHECK7':
      PIN_NUMBER='(0,0,0,0,0,0,0,0,0,0,0,0,0,0,0,0,0,0,0,0,0,0,0,0,0,0,0,0,0,0,0~
,0,0,0,AR10,0,0,0,0,0)';
      BIDIRECTIONAL='TRUE';
      INPUT_LOAD='(-0.01,0.01)';
      OUTPUT_LOAD='(1.0,-1.0)';
      PINUSE='BI';
    'MLA1_RSP_L':
      PIN_NUMBER='(0,0,0,0,0,0,0,0,0,0,0,0,0,0,0,0,0,0,0,0,0,0,0,0,0,0,0,0,0,0,0~
,0,0,0,BP11,0,0,0,0,0)';
      INPUT_LOAD='(-0.01,0.01)';
      PINUSE='IN';
    'ML_ALERT_L':
      PIN_NUMBER='(0,0,0,0,0,0,0,0,0,0,0,0,0,0,0,0,0,0,0,0,0,0,0,0,0,0,0,0,0,0,0~
,0,0,0,AT11,0,0,0,0,0)';
      INPUT_LOAD='(-0.01,0.01)';
      PINUSE='IN';
    'MLB_DATA22':
      PIN_NUMBER='(0,0,0,0,0,0,0,0,0,0,0,0,0,0,0,0,0,0,0,0,0,0,0,0,0,0,0,0,0,0,0~
,0,0,0,CW9,0,0,0,0,0)';
      BIDIRECTIONAL='TRUE';
      INPUT_LOAD='(-0.01,0.01)';
      OUTPUT_LOAD='(1.0,-1.0)';
      PINUSE='BI';
    'MLB_DATA11':
      PIN_NUMBER='(0,0,0,0,0,0,0,0,0,0,0,0,0,0,0,0,0,0,0,0,0,0,0,0,0,0,0,0,0,0,0~
,0,0,0,CK11,0,0,0,0,0)';
      BIDIRECTIONAL='TRUE';
      INPUT_LOAD='(-0.01,0.01)';
      OUTPUT_LOAD='(1.0,-1.0)';
      PINUSE='BI';
    'MLB_CHECK2':
      PIN_NUMBER='(0,0,0,0,0,0,0,0,0,0,0,0,0,0,0,0,0,0,0,0,0,0,0,0,0,0,0,0,0,0,0~
,0,0,0,CA9,0,0,0,0,0)';
      BIDIRECTIONAL='TRUE';
      INPUT_LOAD='(-0.01,0.01)';
      OUTPUT_LOAD='(1.0,-1.0)';
      PINUSE='BI';
    'MLA_DQS_L4':
      PIN_NUMBER='(0,0,0,0,0,0,0,0,0,0,0,0,0,0,0,0,0,0,0,0,0,0,0,0,0,0,0,0,0,0,0~
,0,0,0,AM9,0,0,0,0,0)';
      BIDIRECTIONAL='TRUE';
      INPUT_LOAD='(-0.01,0.01)';
      OUTPUT_LOAD='(1.0,-1.0)';
      PINUSE='BI';
    'MLA_DQS_H0':
      PIN_NUMBER='(0,0,0,0,0,0,0,0,0,0,0,0,0,0,0,0,0,0,0,0,0,0,0,0,0,0,0,0,0,0,0~
,0,0,0,G9,0,0,0,0,0)';
      BIDIRECTIONAL='TRUE';
      INPUT_LOAD='(-0.01,0.01)';
      OUTPUT_LOAD='(1.0,-1.0)';
      PINUSE='BI';
    'MLA_DATA28':
      PIN_NUMBER='(0,0,0,0,0,0,0,0,0,0,0,0,0,0,0,0,0,0,0,0,0,0,0,0,0,0,0,0,0,0,0~
,0,0,0,AG9,0,0,0,0,0)';
      BIDIRECTIONAL='TRUE';
      INPUT_LOAD='(-0.01,0.01)';
      OUTPUT_LOAD='(1.0,-1.0)';
      PINUSE='BI';
    'MLA_DATA17':
      PIN_NUMBER='(0,0,0,0,0,0,0,0,0,0,0,0,0,0,0,0,0,0,0,0,0,0,0,0,0,0,0,0,0,0,0~
,0,0,0,V11,0,0,0,0,0)';
      BIDIRECTIONAL='TRUE';
      INPUT_LOAD='(-0.01,0.01)';
      OUTPUT_LOAD='(1.0,-1.0)';
      PINUSE='BI';
    'MLB_DATA23':
      PIN_NUMBER='(0,0,0,0,0,0,0,0,0,0,0,0,0,0,0,0,0,0,0,0,0,0,0,0,0,0,0,0,0,0,0~
,0,0,0,CY11,0,0,0,0,0)';
      BIDIRECTIONAL='TRUE';
      INPUT_LOAD='(-0.01,0.01)';
      OUTPUT_LOAD='(1.0,-1.0)';
      PINUSE='BI';
    'MLB_DATA12':
      PIN_NUMBER='(0,0,0,0,0,0,0,0,0,0,0,0,0,0,0,0,0,0,0,0,0,0,0,0,0,0,0,0,0,0,0~
,0,0,0,CM9,0,0,0,0,0)';
      BIDIRECTIONAL='TRUE';
      INPUT_LOAD='(-0.01,0.01)';
      OUTPUT_LOAD='(1.0,-1.0)';
      PINUSE='BI';
    'MLB_CHECK3':
      PIN_NUMBER='(0,0,0,0,0,0,0,0,0,0,0,0,0,0,0,0,0,0,0,0,0,0,0,0,0,0,0,0,0,0,0~
,0,0,0,CB11,0,0,0,0,0)';
      BIDIRECTIONAL='TRUE';
      INPUT_LOAD='(-0.01,0.01)';
      OUTPUT_LOAD='(1.0,-1.0)';
      PINUSE='BI';
    'MLA_DQS_L5':
      PIN_NUMBER='(0,0,0,0,0,0,0,0,0,0,0,0,0,0,0,0,0,0,0,0,0,0,0,0,0,0,0,0,0,0,0~
,0,0,0,H11,0,0,0,0,0)';
      BIDIRECTIONAL='TRUE';
      INPUT_LOAD='(-0.01,0.01)';
      OUTPUT_LOAD='(1.0,-1.0)';
      PINUSE='BI';
    'MLA_DQS_H1':
      PIN_NUMBER='(0,0,0,0,0,0,0,0,0,0,0,0,0,0,0,0,0,0,0,0,0,0,0,0,0,0,0,0,0,0,0~
,0,0,0,N9,0,0,0,0,0)';
      BIDIRECTIONAL='TRUE';
      INPUT_LOAD='(-0.01,0.01)';
      OUTPUT_LOAD='(1.0,-1.0)';
      PINUSE='BI';
    'MLA_DATA29':
      PIN_NUMBER='(0,0,0,0,0,0,0,0,0,0,0,0,0,0,0,0,0,0,0,0,0,0,0,0,0,0,0,0,0,0,0~
,0,0,0,AH11,0,0,0,0,0)';
      BIDIRECTIONAL='TRUE';
      INPUT_LOAD='(-0.01,0.01)';
      OUTPUT_LOAD='(1.0,-1.0)';
      PINUSE='BI';
    'MLA_DATA18':
      PIN_NUMBER='(0,0,0,0,0,0,0,0,0,0,0,0,0,0,0,0,0,0,0,0,0,0,0,0,0,0,0,0,0,0,0~
,0,0,0,V9,0,0,0,0,0)';
      BIDIRECTIONAL='TRUE';
      INPUT_LOAD='(-0.01,0.01)';
      OUTPUT_LOAD='(1.0,-1.0)';
      PINUSE='BI';
    'ML0_CLK_H':
      PIN_NUMBER='(0,0,0,0,0,0,0,0,0,0,0,0,0,0,0,0,0,0,0,0,0,0,0,0,0,0,0,0,0,0,0~
,0,0,0,BC9,0,0,0,0,0)';
      OUTPUT_LOAD='(1.0,-1.0)';
      PINUSE='OUT';
    'MLB_DQS_L0':
      PIN_NUMBER='(0,0,0,0,0,0,0,0,0,0,0,0,0,0,0,0,0,0,0,0,0,0,0,0,0,0,0,0,0,0,0~
,0,0,0,CE9,0,0,0,0,0)';
      BIDIRECTIONAL='TRUE';
      INPUT_LOAD='(-0.01,0.01)';
      OUTPUT_LOAD='(1.0,-1.0)';
      PINUSE='BI';
    'MLB_DATA24':
      PIN_NUMBER='(0,0,0,0,0,0,0,0,0,0,0,0,0,0,0,0,0,0,0,0,0,0,0,0,0,0,0,0,0,0,0~
,0,0,0,CY9,0,0,0,0,0)';
      BIDIRECTIONAL='TRUE';
      INPUT_LOAD='(-0.01,0.01)';
      OUTPUT_LOAD='(1.0,-1.0)';
      PINUSE='BI';
    'MLB_DATA13':
      PIN_NUMBER='(0,0,0,0,0,0,0,0,0,0,0,0,0,0,0,0,0,0,0,0,0,0,0,0,0,0,0,0,0,0,0~
,0,0,0,CN10,0,0,0,0,0)';
      BIDIRECTIONAL='TRUE';
      INPUT_LOAD='(-0.01,0.01)';
      OUTPUT_LOAD='(1.0,-1.0)';
      PINUSE='BI';
    'MLB_CHECK4':
      PIN_NUMBER='(0,0,0,0,0,0,0,0,0,0,0,0,0,0,0,0,0,0,0,0,0,0,0,0,0,0,0,0,0,0,0~
,0,0,0,BT9,0,0,0,0,0)';
      BIDIRECTIONAL='TRUE';
      INPUT_LOAD='(-0.01,0.01)';
      OUTPUT_LOAD='(1.0,-1.0)';
      PINUSE='BI';
    'MLA_DQS_L6':
      PIN_NUMBER='(0,0,0,0,0,0,0,0,0,0,0,0,0,0,0,0,0,0,0,0,0,0,0,0,0,0,0,0,0,0,0~
,0,0,0,P11,0,0,0,0,0)';
      BIDIRECTIONAL='TRUE';
      INPUT_LOAD='(-0.01,0.01)';
      OUTPUT_LOAD='(1.0,-1.0)';
      PINUSE='BI';
    'MLA_DQS_H2':
      PIN_NUMBER='(0,0,0,0,0,0,0,0,0,0,0,0,0,0,0,0,0,0,0,0,0,0,0,0,0,0,0,0,0,0,0~
,0,0,0,W9,0,0,0,0,0)';
      BIDIRECTIONAL='TRUE';
      INPUT_LOAD='(-0.01,0.01)';
      OUTPUT_LOAD='(1.0,-1.0)';
      PINUSE='BI';
    'MLA_DATA19':
      PIN_NUMBER='(0,0,0,0,0,0,0,0,0,0,0,0,0,0,0,0,0,0,0,0,0,0,0,0,0,0,0,0,0,0,0~
,0,0,0,W10,0,0,0,0,0)';
      BIDIRECTIONAL='TRUE';
      INPUT_LOAD='(-0.01,0.01)';
      OUTPUT_LOAD='(1.0,-1.0)';
      PINUSE='BI';
    'ML1_CLK_H':
      PIN_NUMBER='(0,0,0,0,0,0,0,0,0,0,0,0,0,0,0,0,0,0,0,0,0,0,0,0,0,0,0,0,0,0,0~
,0,0,0,BF9,0,0,0,0,0)';
      OUTPUT_LOAD='(1.0,-1.0)';
      PINUSE='OUT';
    'MLB_DQS_L1':
      PIN_NUMBER='(0,0,0,0,0,0,0,0,0,0,0,0,0,0,0,0,0,0,0,0,0,0,0,0,0,0,0,0,0,0,0~
,0,0,0,CL9,0,0,0,0,0)';
      BIDIRECTIONAL='TRUE';
      INPUT_LOAD='(-0.01,0.01)';
      OUTPUT_LOAD='(1.0,-1.0)';
      PINUSE='BI';
    'MLB_DATA25':
      PIN_NUMBER='(0,0,0,0,0,0,0,0,0,0,0,0,0,0,0,0,0,0,0,0,0,0,0,0,0,0,0,0,0,0,0~
,0,0,0,DA10,0,0,0,0,0)';
      BIDIRECTIONAL='TRUE';
      INPUT_LOAD='(-0.01,0.01)';
      OUTPUT_LOAD='(1.0,-1.0)';
      PINUSE='BI';
    'MLB_DATA14':
      PIN_NUMBER='(0,0,0,0,0,0,0,0,0,0,0,0,0,0,0,0,0,0,0,0,0,0,0,0,0,0,0,0,0,0,0~
,0,0,0,CN9,0,0,0,0,0)';
      BIDIRECTIONAL='TRUE';
      INPUT_LOAD='(-0.01,0.01)';
      OUTPUT_LOAD='(1.0,-1.0)';
      PINUSE='BI';
    'MLB_CHECK5':
      PIN_NUMBER='(0,0,0,0,0,0,0,0,0,0,0,0,0,0,0,0,0,0,0,0,0,0,0,0,0,0,0,0,0,0,0~
,0,0,0,BU10,0,0,0,0,0)';
      BIDIRECTIONAL='TRUE';
      INPUT_LOAD='(-0.01,0.01)';
      OUTPUT_LOAD='(1.0,-1.0)';
      PINUSE='BI';
    'MLA_DQS_L7':
      PIN_NUMBER='(0,0,0,0,0,0,0,0,0,0,0,0,0,0,0,0,0,0,0,0,0,0,0,0,0,0,0,0,0,0,0~
,0,0,0,Y11,0,0,0,0,0)';
      BIDIRECTIONAL='TRUE';
      INPUT_LOAD='(-0.01,0.01)';
      OUTPUT_LOAD='(1.0,-1.0)';
      PINUSE='BI';
    'MLA_DQS_H3':
      PIN_NUMBER='(0,0,0,0,0,0,0,0,0,0,0,0,0,0,0,0,0,0,0,0,0,0,0,0,0,0,0,0,0,0,0~
,0,0,0,AE9,0,0,0,0,0)';
      BIDIRECTIONAL='TRUE';
      INPUT_LOAD='(-0.01,0.01)';
      OUTPUT_LOAD='(1.0,-1.0)';
      PINUSE='BI';
    'MLB_DQS_L2':
      PIN_NUMBER='(0,0,0,0,0,0,0,0,0,0,0,0,0,0,0,0,0,0,0,0,0,0,0,0,0,0,0,0,0,0,0~
,0,0,0,CU9,0,0,0,0,0)';
      BIDIRECTIONAL='TRUE';
      INPUT_LOAD='(-0.01,0.01)';
      OUTPUT_LOAD='(1.0,-1.0)';
      PINUSE='BI';
    'MLB_DATA26':
      PIN_NUMBER='(0,0,0,0,0,0,0,0,0,0,0,0,0,0,0,0,0,0,0,0,0,0,0,0,0,0,0,0,0,0,0~
,0,0,0,DA9,0,0,0,0,0)';
      BIDIRECTIONAL='TRUE';
      INPUT_LOAD='(-0.01,0.01)';
      OUTPUT_LOAD='(1.0,-1.0)';
      PINUSE='BI';
    'MLB_DATA15':
      PIN_NUMBER='(0,0,0,0,0,0,0,0,0,0,0,0,0,0,0,0,0,0,0,0,0,0,0,0,0,0,0,0,0,0,0~
,0,0,0,CP11,0,0,0,0,0)';
      BIDIRECTIONAL='TRUE';
      INPUT_LOAD='(-0.01,0.01)';
      OUTPUT_LOAD='(1.0,-1.0)';
      PINUSE='BI';
    'MLB_CHECK6':
      PIN_NUMBER='(0,0,0,0,0,0,0,0,0,0,0,0,0,0,0,0,0,0,0,0,0,0,0,0,0,0,0,0,0,0,0~
,0,0,0,BU9,0,0,0,0,0)';
      BIDIRECTIONAL='TRUE';
      INPUT_LOAD='(-0.01,0.01)';
      OUTPUT_LOAD='(1.0,-1.0)';
      PINUSE='BI';
    'MLB0_RSP_L':
      PIN_NUMBER='(0,0,0,0,0,0,0,0,0,0,0,0,0,0,0,0,0,0,0,0,0,0,0,0,0,0,0,0,0,0,0~
,0,0,0,BP9,0,0,0,0,0)';
      INPUT_LOAD='(-0.01,0.01)';
      PINUSE='IN';
    'MLA_DQS_L8':
      PIN_NUMBER='(0,0,0,0,0,0,0,0,0,0,0,0,0,0,0,0,0,0,0,0,0,0,0,0,0,0,0,0,0,0,0~
,0,0,0,AF11,0,0,0,0,0)';
      BIDIRECTIONAL='TRUE';
      INPUT_LOAD='(-0.01,0.01)';
      OUTPUT_LOAD='(1.0,-1.0)';
      PINUSE='BI';
    'MLA_DQS_H4':
      PIN_NUMBER='(0,0,0,0,0,0,0,0,0,0,0,0,0,0,0,0,0,0,0,0,0,0,0,0,0,0,0,0,0,0,0~
,0,0,0,AL9,0,0,0,0,0)';
      BIDIRECTIONAL='TRUE';
      INPUT_LOAD='(-0.01,0.01)';
      OUTPUT_LOAD='(1.0,-1.0)';
      PINUSE='BI';
    'MLB_DQS_L3':
      PIN_NUMBER='(0,0,0,0,0,0,0,0,0,0,0,0,0,0,0,0,0,0,0,0,0,0,0,0,0,0,0,0,0,0,0~
,0,0,0,DC9,0,0,0,0,0)';
      BIDIRECTIONAL='TRUE';
      INPUT_LOAD='(-0.01,0.01)';
      OUTPUT_LOAD='(1.0,-1.0)';
      PINUSE='BI';
    'MLB_DATA27':
      PIN_NUMBER='(0,0,0,0,0,0,0,0,0,0,0,0,0,0,0,0,0,0,0,0,0,0,0,0,0,0,0,0,0,0,0~
,0,0,0,DB11,0,0,0,0,0)';
      BIDIRECTIONAL='TRUE';
      INPUT_LOAD='(-0.01,0.01)';
      OUTPUT_LOAD='(1.0,-1.0)';
      PINUSE='BI';
    'MLB_DATA16':
      PIN_NUMBER='(0,0,0,0,0,0,0,0,0,0,0,0,0,0,0,0,0,0,0,0,0,0,0,0,0,0,0,0,0,0,0~
,0,0,0,CP9,0,0,0,0,0)';
      BIDIRECTIONAL='TRUE';
      INPUT_LOAD='(-0.01,0.01)';
      OUTPUT_LOAD='(1.0,-1.0)';
      PINUSE='BI';
    'MLB_CHECK7':
      PIN_NUMBER='(0,0,0,0,0,0,0,0,0,0,0,0,0,0,0,0,0,0,0,0,0,0,0,0,0,0,0,0,0,0,0~
,0,0,0,BV11,0,0,0,0,0)';
      BIDIRECTIONAL='TRUE';
      INPUT_LOAD='(-0.01,0.01)';
      OUTPUT_LOAD='(1.0,-1.0)';
      PINUSE='BI';
    'MLB1_RSP_L':
      PIN_NUMBER='(0,0,0,0,0,0,0,0,0,0,0,0,0,0,0,0,0,0,0,0,0,0,0,0,0,0,0,0,0,0,0~
,0,0,0,BR9,0,0,0,0,0)';
      INPUT_LOAD='(-0.01,0.01)';
      PINUSE='IN';
    'MLA_PAR':
      PIN_NUMBER='(0,0,0,0,0,0,0,0,0,0,0,0,0,0,0,0,0,0,0,0,0,0,0,0,0,0,0,0,0,0,0~
,0,0,0,BC10,0,0,0,0,0)';
      OUTPUT_LOAD='(1.0,-1.0)';
      PINUSE='OUT';
    'MLA_DQS_L9':
      PIN_NUMBER='(0,0,0,0,0,0,0,0,0,0,0,0,0,0,0,0,0,0,0,0,0,0,0,0,0,0,0,0,0,0,0~
,0,0,0,AM11,0,0,0,0,0)';
      BIDIRECTIONAL='TRUE';
      INPUT_LOAD='(-0.01,0.01)';
      OUTPUT_LOAD='(1.0,-1.0)';
      PINUSE='BI';
    'MLA_DQS_H5':
      PIN_NUMBER='(0,0,0,0,0,0,0,0,0,0,0,0,0,0,0,0,0,0,0,0,0,0,0,0,0,0,0,0,0,0,0~
,0,0,0,J10,0,0,0,0,0)';
      BIDIRECTIONAL='TRUE';
      INPUT_LOAD='(-0.01,0.01)';
      OUTPUT_LOAD='(1.0,-1.0)';
      PINUSE='BI';
    'ML0_CLK_L':
      PIN_NUMBER='(0,0,0,0,0,0,0,0,0,0,0,0,0,0,0,0,0,0,0,0,0,0,0,0,0,0,0,0,0,0,0~
,0,0,0,BD9,0,0,0,0,0)';
      OUTPUT_LOAD='(1.0,-1.0)';
      PINUSE='OUT';
    'MLB_PAR':
      PIN_NUMBER='(0,0,0,0,0,0,0,0,0,0,0,0,0,0,0,0,0,0,0,0,0,0,0,0,0,0,0,0,0,0,0~
,0,0,0,BL10,0,0,0,0,0)';
      OUTPUT_LOAD='(1.0,-1.0)';
      PINUSE='OUT';
    'MLB_DQS_L4':
      PIN_NUMBER='(0,0,0,0,0,0,0,0,0,0,0,0,0,0,0,0,0,0,0,0,0,0,0,0,0,0,0,0,0,0,0~
,0,0,0,BW10,0,0,0,0,0)';
      BIDIRECTIONAL='TRUE';
      INPUT_LOAD='(-0.01,0.01)';
      OUTPUT_LOAD='(1.0,-1.0)';
      PINUSE='BI';
    'MLB_DQS_H0':
      PIN_NUMBER='(0,0,0,0,0,0,0,0,0,0,0,0,0,0,0,0,0,0,0,0,0,0,0,0,0,0,0,0,0,0,0~
,0,0,0,CD9,0,0,0,0,0)';
      BIDIRECTIONAL='TRUE';
      INPUT_LOAD='(-0.01,0.01)';
      OUTPUT_LOAD='(1.0,-1.0)';
      PINUSE='BI';
    'MLB_DATA28':
      PIN_NUMBER='(0,0,0,0,0,0,0,0,0,0,0,0,0,0,0,0,0,0,0,0,0,0,0,0,0,0,0,0,0,0,0~
,0,0,0,DD9,0,0,0,0,0)';
      BIDIRECTIONAL='TRUE';
      INPUT_LOAD='(-0.01,0.01)';
      OUTPUT_LOAD='(1.0,-1.0)';
      PINUSE='BI';
    'MLB_DATA17':
      PIN_NUMBER='(0,0,0,0,0,0,0,0,0,0,0,0,0,0,0,0,0,0,0,0,0,0,0,0,0,0,0,0,0,0,0~
,0,0,0,CR10,0,0,0,0,0)';
      BIDIRECTIONAL='TRUE';
      INPUT_LOAD='(-0.01,0.01)';
      OUTPUT_LOAD='(1.0,-1.0)';
      PINUSE='BI';
    'MLA_DQS_H6':
      PIN_NUMBER='(0,0,0,0,0,0,0,0,0,0,0,0,0,0,0,0,0,0,0,0,0,0,0,0,0,0,0,0,0,0,0~
,0,0,0,R10,0,0,0,0,0)';
      BIDIRECTIONAL='TRUE';
      INPUT_LOAD='(-0.01,0.01)';
      OUTPUT_LOAD='(1.0,-1.0)';
      PINUSE='BI';
    'MLA_DATA0':
      PIN_NUMBER='(0,0,0,0,0,0,0,0,0,0,0,0,0,0,0,0,0,0,0,0,0,0,0,0,0,0,0,0,0,0,0~
,0,0,0,E9,0,0,0,0,0)';
      BIDIRECTIONAL='TRUE';
      INPUT_LOAD='(-0.01,0.01)';
      OUTPUT_LOAD='(1.0,-1.0)';
      PINUSE='BI';
    'MLA0_CS_L0':
      PIN_NUMBER='(0,0,0,0,0,0,0,0,0,0,0,0,0,0,0,0,0,0,0,0,0,0,0,0,0,0,0,0,0,0,0~
,0,0,0,AU9,0,0,0,0,0)';
      OUTPUT_LOAD='(1.0,-1.0)';
      PINUSE='OUT';
    'ML1_CLK_L':
      PIN_NUMBER='(0,0,0,0,0,0,0,0,0,0,0,0,0,0,0,0,0,0,0,0,0,0,0,0,0,0,0,0,0,0,0~
,0,0,0,BG9,0,0,0,0,0)';
      OUTPUT_LOAD='(1.0,-1.0)';
      PINUSE='OUT';
    'MLB_DQS_L5':
      PIN_NUMBER='(0,0,0,0,0,0,0,0,0,0,0,0,0,0,0,0,0,0,0,0,0,0,0,0,0,0,0,0,0,0,0~
,0,0,0,CE10,0,0,0,0,0)';
      BIDIRECTIONAL='TRUE';
      INPUT_LOAD='(-0.01,0.01)';
      OUTPUT_LOAD='(1.0,-1.0)';
      PINUSE='BI';
    'MLB_DQS_H1':
      PIN_NUMBER='(0,0,0,0,0,0,0,0,0,0,0,0,0,0,0,0,0,0,0,0,0,0,0,0,0,0,0,0,0,0,0~
,0,0,0,CK9,0,0,0,0,0)';
      BIDIRECTIONAL='TRUE';
      INPUT_LOAD='(-0.01,0.01)';
      OUTPUT_LOAD='(1.0,-1.0)';
      PINUSE='BI';
    'MLB_DATA29':
      PIN_NUMBER='(0,0,0,0,0,0,0,0,0,0,0,0,0,0,0,0,0,0,0,0,0,0,0,0,0,0,0,0,0,0,0~
,0,0,0,DE10,0,0,0,0,0)';
      BIDIRECTIONAL='TRUE';
      INPUT_LOAD='(-0.01,0.01)';
      OUTPUT_LOAD='(1.0,-1.0)';
      PINUSE='BI';
    'MLB_DATA18':
      PIN_NUMBER='(0,0,0,0,0,0,0,0,0,0,0,0,0,0,0,0,0,0,0,0,0,0,0,0,0,0,0,0,0,0,0~
,0,0,0,CR9,0,0,0,0,0)';
      BIDIRECTIONAL='TRUE';
      INPUT_LOAD='(-0.01,0.01)';
      OUTPUT_LOAD='(1.0,-1.0)';
      PINUSE='BI';
    'MLB_DATA0':
      PIN_NUMBER='(0,0,0,0,0,0,0,0,0,0,0,0,0,0,0,0,0,0,0,0,0,0,0,0,0,0,0,0,0,0,0~
,0,0,0,CB9,0,0,0,0,0)';
      BIDIRECTIONAL='TRUE';
      INPUT_LOAD='(-0.01,0.01)';
      OUTPUT_LOAD='(1.0,-1.0)';
      PINUSE='BI';
    'MLA_DQS_H7':
      PIN_NUMBER='(0,0,0,0,0,0,0,0,0,0,0,0,0,0,0,0,0,0,0,0,0,0,0,0,0,0,0,0,0,0,0~
,0,0,0,AA10,0,0,0,0,0)';
      BIDIRECTIONAL='TRUE';
      INPUT_LOAD='(-0.01,0.01)';
      OUTPUT_LOAD='(1.0,-1.0)';
      PINUSE='BI';
    'MLA_DATA1':
      PIN_NUMBER='(0,0,0,0,0,0,0,0,0,0,0,0,0,0,0,0,0,0,0,0,0,0,0,0,0,0,0,0,0,0,0~
,0,0,0,F11,0,0,0,0,0)';
      BIDIRECTIONAL='TRUE';
      INPUT_LOAD='(-0.01,0.01)';
      OUTPUT_LOAD='(1.0,-1.0)';
      PINUSE='BI';
    'MLA1_CS_L0':
      PIN_NUMBER='(0,0,0,0,0,0,0,0,0,0,0,0,0,0,0,0,0,0,0,0,0,0,0,0,0,0,0,0,0,0,0~
,0,0,0,AV9,0,0,0,0,0)';
      OUTPUT_LOAD='(1.0,-1.0)';
      PINUSE='OUT';
    'MLA0_CS_L1':
      PIN_NUMBER='(0,0,0,0,0,0,0,0,0,0,0,0,0,0,0,0,0,0,0,0,0,0,0,0,0,0,0,0,0,0,0~
,0,0,0,AV11,0,0,0,0,0)';
      OUTPUT_LOAD='(1.0,-1.0)';
      PINUSE='OUT';
    'MLB_DQS_L6':
      PIN_NUMBER='(0,0,0,0,0,0,0,0,0,0,0,0,0,0,0,0,0,0,0,0,0,0,0,0,0,0,0,0,0,0,0~
,0,0,0,CL10,0,0,0,0,0)';
      BIDIRECTIONAL='TRUE';
      INPUT_LOAD='(-0.01,0.01)';
      OUTPUT_LOAD='(1.0,-1.0)';
      PINUSE='BI';
    'MLB_DQS_H2':
      PIN_NUMBER='(0,0,0,0,0,0,0,0,0,0,0,0,0,0,0,0,0,0,0,0,0,0,0,0,0,0,0,0,0,0,0~
,0,0,0,CT9,0,0,0,0,0)';
      BIDIRECTIONAL='TRUE';
      INPUT_LOAD='(-0.01,0.01)';
      OUTPUT_LOAD='(1.0,-1.0)';
      PINUSE='BI';
    'MLB_DATA19':
      PIN_NUMBER='(0,0,0,0,0,0,0,0,0,0,0,0,0,0,0,0,0,0,0,0,0,0,0,0,0,0,0,0,0,0,0~
,0,0,0,CT11,0,0,0,0,0)';
      BIDIRECTIONAL='TRUE';
      INPUT_LOAD='(-0.01,0.01)';
      OUTPUT_LOAD='(1.0,-1.0)';
      PINUSE='BI';
    'MLB_DATA1':
      PIN_NUMBER='(0,0,0,0,0,0,0,0,0,0,0,0,0,0,0,0,0,0,0,0,0,0,0,0,0,0,0,0,0,0,0~
,0,0,0,CC10,0,0,0,0,0)';
      BIDIRECTIONAL='TRUE';
      INPUT_LOAD='(-0.01,0.01)';
      OUTPUT_LOAD='(1.0,-1.0)';
      PINUSE='BI';
    'MLA_DQS_H8':
      PIN_NUMBER='(0,0,0,0,0,0,0,0,0,0,0,0,0,0,0,0,0,0,0,0,0,0,0,0,0,0,0,0,0,0,0~
,0,0,0,AG10,0,0,0,0,0)';
      BIDIRECTIONAL='TRUE';
      INPUT_LOAD='(-0.01,0.01)';
      OUTPUT_LOAD='(1.0,-1.0)';
      PINUSE='BI';
    'MLA_DATA30':
      PIN_NUMBER='(0,0,0,0,0,0,0,0,0,0,0,0,0,0,0,0,0,0,0,0,0,0,0,0,0,0,0,0,0,0,0~
,0,0,0,AH9,0,0,0,0,0)';
      BIDIRECTIONAL='TRUE';
      INPUT_LOAD='(-0.01,0.01)';
      OUTPUT_LOAD='(1.0,-1.0)';
      PINUSE='BI';
    'MLA_DATA2':
      PIN_NUMBER='(0,0,0,0,0,0,0,0,0,0,0,0,0,0,0,0,0,0,0,0,0,0,0,0,0,0,0,0,0,0,0~
,0,0,0,F9,0,0,0,0,0)';
      BIDIRECTIONAL='TRUE';
      INPUT_LOAD='(-0.01,0.01)';
      OUTPUT_LOAD='(1.0,-1.0)';
      PINUSE='BI';
    'MLA1_CS_L1':
      PIN_NUMBER='(0,0,0,0,0,0,0,0,0,0,0,0,0,0,0,0,0,0,0,0,0,0,0,0,0,0,0,0,0,0,0~
,0,0,0,AW10,0,0,0,0,0)';
      OUTPUT_LOAD='(1.0,-1.0)';
      PINUSE='OUT';
    'MLB_DQS_L7':
      PIN_NUMBER='(0,0,0,0,0,0,0,0,0,0,0,0,0,0,0,0,0,0,0,0,0,0,0,0,0,0,0,0,0,0,0~
,0,0,0,CU10,0,0,0,0,0)';
      BIDIRECTIONAL='TRUE';
      INPUT_LOAD='(-0.01,0.01)';
      OUTPUT_LOAD='(1.0,-1.0)';
      PINUSE='BI';
    'MLB_DQS_H3':
      PIN_NUMBER='(0,0,0,0,0,0,0,0,0,0,0,0,0,0,0,0,0,0,0,0,0,0,0,0,0,0,0,0,0,0,0~
,0,0,0,DB9,0,0,0,0,0)';
      BIDIRECTIONAL='TRUE';
      INPUT_LOAD='(-0.01,0.01)';
      OUTPUT_LOAD='(1.0,-1.0)';
      PINUSE='BI';
    'MLB_DATA2':
      PIN_NUMBER='(0,0,0,0,0,0,0,0,0,0,0,0,0,0,0,0,0,0,0,0,0,0,0,0,0,0,0,0,0,0,0~
,0,0,0,CC9,0,0,0,0,0)';
      BIDIRECTIONAL='TRUE';
      INPUT_LOAD='(-0.01,0.01)';
      OUTPUT_LOAD='(1.0,-1.0)';
      PINUSE='BI';
    'MLA_DQS_H9':
      PIN_NUMBER='(0,0,0,0,0,0,0,0,0,0,0,0,0,0,0,0,0,0,0,0,0,0,0,0,0,0,0,0,0,0,0~
,0,0,0,AN10,0,0,0,0,0)';
      BIDIRECTIONAL='TRUE';
      INPUT_LOAD='(-0.01,0.01)';
      OUTPUT_LOAD='(1.0,-1.0)';
      PINUSE='BI';
    'MLA_DATA31':
      PIN_NUMBER='(0,0,0,0,0,0,0,0,0,0,0,0,0,0,0,0,0,0,0,0,0,0,0,0,0,0,0,0,0,0,0~
,0,0,0,AJ10,0,0,0,0,0)';
      BIDIRECTIONAL='TRUE';
      INPUT_LOAD='(-0.01,0.01)';
      OUTPUT_LOAD='(1.0,-1.0)';
      PINUSE='BI';
    'MLA_DATA20':
      PIN_NUMBER='(0,0,0,0,0,0,0,0,0,0,0,0,0,0,0,0,0,0,0,0,0,0,0,0,0,0,0,0,0,0,0~
,0,0,0,AA9,0,0,0,0,0)';
      BIDIRECTIONAL='TRUE';
      INPUT_LOAD='(-0.01,0.01)';
      OUTPUT_LOAD='(1.0,-1.0)';
      PINUSE='BI';
    'MLA_DATA3':
      PIN_NUMBER='(0,0,0,0,0,0,0,0,0,0,0,0,0,0,0,0,0,0,0,0,0,0,0,0,0,0,0,0,0,0,0~
,0,0,0,G10,0,0,0,0,0)';
      BIDIRECTIONAL='TRUE';
      INPUT_LOAD='(-0.01,0.01)';
      OUTPUT_LOAD='(1.0,-1.0)';
      PINUSE='BI';
    'MLA_CHECK0':
      PIN_NUMBER='(0,0,0,0,0,0,0,0,0,0,0,0,0,0,0,0,0,0,0,0,0,0,0,0,0,0,0,0,0,0,0~
,0,0,0,AJ9,0,0,0,0,0)';
      BIDIRECTIONAL='TRUE';
      INPUT_LOAD='(-0.01,0.01)';
      OUTPUT_LOAD='(1.0,-1.0)';
      PINUSE='BI';
    'MLA_CA0':
      PIN_NUMBER='(0,0,0,0,0,0,0,0,0,0,0,0,0,0,0,0,0,0,0,0,0,0,0,0,0,0,0,0,0,0,0~
,0,0,0,AW9,0,0,0,0,0)';
      OUTPUT_LOAD='(1.0,-1.0)';
      PINUSE='OUT';
    'MLB_DQS_L8':
      PIN_NUMBER='(0,0,0,0,0,0,0,0,0,0,0,0,0,0,0,0,0,0,0,0,0,0,0,0,0,0,0,0,0,0,0~
,0,0,0,DC10,0,0,0,0,0)';
      BIDIRECTIONAL='TRUE';
      INPUT_LOAD='(-0.01,0.01)';
      OUTPUT_LOAD='(1.0,-1.0)';
      PINUSE='BI';
    'MLB_DQS_H4':
      PIN_NUMBER='(0,0,0,0,0,0,0,0,0,0,0,0,0,0,0,0,0,0,0,0,0,0,0,0,0,0,0,0,0,0,0~
,0,0,0,BY11,0,0,0,0,0)';
      BIDIRECTIONAL='TRUE';
      INPUT_LOAD='(-0.01,0.01)';
      OUTPUT_LOAD='(1.0,-1.0)';
      PINUSE='BI';
    'MLB_DATA3':
      PIN_NUMBER='(0,0,0,0,0,0,0,0,0,0,0,0,0,0,0,0,0,0,0,0,0,0,0,0,0,0,0,0,0,0,0~
,0,0,0,CD11,0,0,0,0,0)';
      BIDIRECTIONAL='TRUE';
      INPUT_LOAD='(-0.01,0.01)';
      OUTPUT_LOAD='(1.0,-1.0)';
      PINUSE='BI';
    'MLB_CA0':
      PIN_NUMBER='(0,0,0,0,0,0,0,0,0,0,0,0,0,0,0,0,0,0,0,0,0,0,0,0,0,0,0,0,0,0,0~
,0,0,0,BG10,0,0,0,0,0)';
      OUTPUT_LOAD='(1.0,-1.0)';
      PINUSE='OUT';
    'MLA_DATA21':
      PIN_NUMBER='(0,0,0,0,0,0,0,0,0,0,0,0,0,0,0,0,0,0,0,0,0,0,0,0,0,0,0,0,0,0,0~
,0,0,0,AB11,0,0,0,0,0)';
      BIDIRECTIONAL='TRUE';
      INPUT_LOAD='(-0.01,0.01)';
      OUTPUT_LOAD='(1.0,-1.0)';
      PINUSE='BI';
    'MLA_DATA10':
      PIN_NUMBER='(0,0,0,0,0,0,0,0,0,0,0,0,0,0,0,0,0,0,0,0,0,0,0,0,0,0,0,0,0,0,0~
,0,0,0,M9,0,0,0,0,0)';
      BIDIRECTIONAL='TRUE';
      INPUT_LOAD='(-0.01,0.01)';
      OUTPUT_LOAD='(1.0,-1.0)';
      PINUSE='BI';
    'MLA_DATA4':
      PIN_NUMBER='(0,0,0,0,0,0,0,0,0,0,0,0,0,0,0,0,0,0,0,0,0,0,0,0,0,0,0,0,0,0,0~
,0,0,0,J9,0,0,0,0,0)';
      BIDIRECTIONAL='TRUE';
      INPUT_LOAD='(-0.01,0.01)';
      OUTPUT_LOAD='(1.0,-1.0)';
      PINUSE='BI';
    'MLA_CHECK1':
      PIN_NUMBER='(0,0,0,0,0,0,0,0,0,0,0,0,0,0,0,0,0,0,0,0,0,0,0,0,0,0,0,0,0,0,0~
,0,0,0,AK11,0,0,0,0,0)';
      BIDIRECTIONAL='TRUE';
      INPUT_LOAD='(-0.01,0.01)';
      OUTPUT_LOAD='(1.0,-1.0)';
      PINUSE='BI';
    'MLA_CA1':
      PIN_NUMBER='(0,0,0,0,0,0,0,0,0,0,0,0,0,0,0,0,0,0,0,0,0,0,0,0,0,0,0,0,0,0,0~
,0,0,0,AY9,0,0,0,0,0)';
      OUTPUT_LOAD='(1.0,-1.0)';
      PINUSE='OUT';
    'TEST39L':
      PIN_NUMBER='(0,0,0,0,0,0,0,0,0,0,0,0,0,0,0,0,0,0,0,0,0,0,0,0,0,0,0,0,0,0,0~
,0,0,0,BF11,0,0,0,0,0)';
      OUTPUT_LOAD='(1.0,-1.0)';
      PINUSE='OUT';
    'MKB_DQS_L6':
      PIN_NUMBER='(0,0,0,0,0,0,0,0,0,0,0,0,0,0,0,0,0,0,0,0,0,0,0,0,0,0,0,0,0,0,0~
,0,0,0,0,CL7,0,0,0,0)';
      BIDIRECTIONAL='TRUE';
      INPUT_LOAD='(-0.01,0.01)';
      OUTPUT_LOAD='(1.0,-1.0)';
      PINUSE='BI';
    'MKB_DQS_H2':
      PIN_NUMBER='(0,0,0,0,0,0,0,0,0,0,0,0,0,0,0,0,0,0,0,0,0,0,0,0,0,0,0,0,0,0,0~
,0,0,0,0,CT6,0,0,0,0)';
      BIDIRECTIONAL='TRUE';
      INPUT_LOAD='(-0.01,0.01)';
      OUTPUT_LOAD='(1.0,-1.0)';
      PINUSE='BI';
    'MKB_DATA19':
      PIN_NUMBER='(0,0,0,0,0,0,0,0,0,0,0,0,0,0,0,0,0,0,0,0,0,0,0,0,0,0,0,0,0,0,0~
,0,0,0,0,CT7,0,0,0,0)';
      BIDIRECTIONAL='TRUE';
      INPUT_LOAD='(-0.01,0.01)';
      OUTPUT_LOAD='(1.0,-1.0)';
      PINUSE='BI';
    'MKB_CA0':
      PIN_NUMBER='(0,0,0,0,0,0,0,0,0,0,0,0,0,0,0,0,0,0,0,0,0,0,0,0,0,0,0,0,0,0,0~
,0,0,0,0,BG7,0,0,0,0)';
      OUTPUT_LOAD='(1.0,-1.0)';
      PINUSE='OUT';
    'MKA_DQS_H8':
      PIN_NUMBER='(0,0,0,0,0,0,0,0,0,0,0,0,0,0,0,0,0,0,0,0,0,0,0,0,0,0,0,0,0,0,0~
,0,0,0,0,AG7,0,0,0,0)';
      BIDIRECTIONAL='TRUE';
      INPUT_LOAD='(-0.01,0.01)';
      OUTPUT_LOAD='(1.0,-1.0)';
      PINUSE='BI';
    'MKA_DATA30':
      PIN_NUMBER='(0,0,0,0,0,0,0,0,0,0,0,0,0,0,0,0,0,0,0,0,0,0,0,0,0,0,0,0,0,0,0~
,0,0,0,0,AH6,0,0,0,0)';
      BIDIRECTIONAL='TRUE';
      INPUT_LOAD='(-0.01,0.01)';
      OUTPUT_LOAD='(1.0,-1.0)';
      PINUSE='BI';
    'MKA_CA1':
      PIN_NUMBER='(0,0,0,0,0,0,0,0,0,0,0,0,0,0,0,0,0,0,0,0,0,0,0,0,0,0,0,0,0,0,0~
,0,0,0,0,AY6,0,0,0,0)';
      OUTPUT_LOAD='(1.0,-1.0)';
      PINUSE='OUT';
    'MKA1_CS_L0':
      PIN_NUMBER='(0,0,0,0,0,0,0,0,0,0,0,0,0,0,0,0,0,0,0,0,0,0,0,0,0,0,0,0,0,0,0~
,0,0,0,0,AV6,0,0,0,0)';
      OUTPUT_LOAD='(1.0,-1.0)';
      PINUSE='OUT';
    'MKA0_CS_L1':
      PIN_NUMBER='(0,0,0,0,0,0,0,0,0,0,0,0,0,0,0,0,0,0,0,0,0,0,0,0,0,0,0,0,0,0,0~
,0,0,0,0,AV7,0,0,0,0)';
      OUTPUT_LOAD='(1.0,-1.0)';
      PINUSE='OUT';
    'MKB_DQS_L7':
      PIN_NUMBER='(0,0,0,0,0,0,0,0,0,0,0,0,0,0,0,0,0,0,0,0,0,0,0,0,0,0,0,0,0,0,0~
,0,0,0,0,CU7,0,0,0,0)';
      BIDIRECTIONAL='TRUE';
      INPUT_LOAD='(-0.01,0.01)';
      OUTPUT_LOAD='(1.0,-1.0)';
      PINUSE='BI';
    'MKB_DQS_H3':
      PIN_NUMBER='(0,0,0,0,0,0,0,0,0,0,0,0,0,0,0,0,0,0,0,0,0,0,0,0,0,0,0,0,0,0,0~
,0,0,0,0,DB6,0,0,0,0)';
      BIDIRECTIONAL='TRUE';
      INPUT_LOAD='(-0.01,0.01)';
      OUTPUT_LOAD='(1.0,-1.0)';
      PINUSE='BI';
    'MKB_CA1':
      PIN_NUMBER='(0,0,0,0,0,0,0,0,0,0,0,0,0,0,0,0,0,0,0,0,0,0,0,0,0,0,0,0,0,0,0~
,0,0,0,0,BH7,0,0,0,0)';
      OUTPUT_LOAD='(1.0,-1.0)';
      PINUSE='OUT';
    'MKA_DQS_H9':
      PIN_NUMBER='(0,0,0,0,0,0,0,0,0,0,0,0,0,0,0,0,0,0,0,0,0,0,0,0,0,0,0,0,0,0,0~
,0,0,0,0,AN7,0,0,0,0)';
      BIDIRECTIONAL='TRUE';
      INPUT_LOAD='(-0.01,0.01)';
      OUTPUT_LOAD='(1.0,-1.0)';
      PINUSE='BI';
    'MKA_DATA31':
      PIN_NUMBER='(0,0,0,0,0,0,0,0,0,0,0,0,0,0,0,0,0,0,0,0,0,0,0,0,0,0,0,0,0,0,0~
,0,0,0,0,AJ7,0,0,0,0)';
      BIDIRECTIONAL='TRUE';
      INPUT_LOAD='(-0.01,0.01)';
      OUTPUT_LOAD='(1.0,-1.0)';
      PINUSE='BI';
    'MKA_DATA20':
      PIN_NUMBER='(0,0,0,0,0,0,0,0,0,0,0,0,0,0,0,0,0,0,0,0,0,0,0,0,0,0,0,0,0,0,0~
,0,0,0,0,AA5,0,0,0,0)';
      BIDIRECTIONAL='TRUE';
      INPUT_LOAD='(-0.01,0.01)';
      OUTPUT_LOAD='(1.0,-1.0)';
      PINUSE='BI';
    'MKA_CHECK0':
      PIN_NUMBER='(0,0,0,0,0,0,0,0,0,0,0,0,0,0,0,0,0,0,0,0,0,0,0,0,0,0,0,0,0,0,0~
,0,0,0,0,AJ5,0,0,0,0)';
      BIDIRECTIONAL='TRUE';
      INPUT_LOAD='(-0.01,0.01)';
      OUTPUT_LOAD='(1.0,-1.0)';
      PINUSE='BI';
    'MKA_CA2':
      PIN_NUMBER='(0,0,0,0,0,0,0,0,0,0,0,0,0,0,0,0,0,0,0,0,0,0,0,0,0,0,0,0,0,0,0~
,0,0,0,0,AY7,0,0,0,0)';
      OUTPUT_LOAD='(1.0,-1.0)';
      PINUSE='OUT';
    'MKA1_CS_L1':
      PIN_NUMBER='(0,0,0,0,0,0,0,0,0,0,0,0,0,0,0,0,0,0,0,0,0,0,0,0,0,0,0,0,0,0,0~
,0,0,0,0,AW7,0,0,0,0)';
      OUTPUT_LOAD='(1.0,-1.0)';
      PINUSE='OUT';
    'MK0_CLK_H':
      PIN_NUMBER='(0,0,0,0,0,0,0,0,0,0,0,0,0,0,0,0,0,0,0,0,0,0,0,0,0,0,0,0,0,0,0~
,0,0,0,0,BC5,0,0,0,0)';
      OUTPUT_LOAD='(1.0,-1.0)';
      PINUSE='OUT';
    'MKB_DQS_L8':
      PIN_NUMBER='(0,0,0,0,0,0,0,0,0,0,0,0,0,0,0,0,0,0,0,0,0,0,0,0,0,0,0,0,0,0,0~
,0,0,0,0,DC7,0,0,0,0)';
      BIDIRECTIONAL='TRUE';
      INPUT_LOAD='(-0.01,0.01)';
      OUTPUT_LOAD='(1.0,-1.0)';
      PINUSE='BI';
    'MKB_DQS_H4':
      PIN_NUMBER='(0,0,0,0,0,0,0,0,0,0,0,0,0,0,0,0,0,0,0,0,0,0,0,0,0,0,0,0,0,0,0~
,0,0,0,0,BY7,0,0,0,0)';
      BIDIRECTIONAL='TRUE';
      INPUT_LOAD='(-0.01,0.01)';
      OUTPUT_LOAD='(1.0,-1.0)';
      PINUSE='BI';
    'MKB_CA2':
      PIN_NUMBER='(0,0,0,0,0,0,0,0,0,0,0,0,0,0,0,0,0,0,0,0,0,0,0,0,0,0,0,0,0,0,0~
,0,0,0,0,BH6,0,0,0,0)';
      OUTPUT_LOAD='(1.0,-1.0)';
      PINUSE='OUT';
    'MKA_DATA21':
      PIN_NUMBER='(0,0,0,0,0,0,0,0,0,0,0,0,0,0,0,0,0,0,0,0,0,0,0,0,0,0,0,0,0,0,0~
,0,0,0,0,AB7,0,0,0,0)';
      BIDIRECTIONAL='TRUE';
      INPUT_LOAD='(-0.01,0.01)';
      OUTPUT_LOAD='(1.0,-1.0)';
      PINUSE='BI';
    'MKA_DATA10':
      PIN_NUMBER='(0,0,0,0,0,0,0,0,0,0,0,0,0,0,0,0,0,0,0,0,0,0,0,0,0,0,0,0,0,0,0~
,0,0,0,0,M6,0,0,0,0)';
      BIDIRECTIONAL='TRUE';
      INPUT_LOAD='(-0.01,0.01)';
      OUTPUT_LOAD='(1.0,-1.0)';
      PINUSE='BI';
    'MKA_CHECK1':
      PIN_NUMBER='(0,0,0,0,0,0,0,0,0,0,0,0,0,0,0,0,0,0,0,0,0,0,0,0,0,0,0,0,0,0,0~
,0,0,0,0,AK7,0,0,0,0)';
      BIDIRECTIONAL='TRUE';
      INPUT_LOAD='(-0.01,0.01)';
      OUTPUT_LOAD='(1.0,-1.0)';
      PINUSE='BI';
    'MKA_CA3':
      PIN_NUMBER='(0,0,0,0,0,0,0,0,0,0,0,0,0,0,0,0,0,0,0,0,0,0,0,0,0,0,0,0,0,0,0~
,0,0,0,0,BA7,0,0,0,0)';
      OUTPUT_LOAD='(1.0,-1.0)';
      PINUSE='OUT';
    'MK1_CLK_H':
      PIN_NUMBER='(0,0,0,0,0,0,0,0,0,0,0,0,0,0,0,0,0,0,0,0,0,0,0,0,0,0,0,0,0,0,0~
,0,0,0,0,BF6,0,0,0,0)';
      OUTPUT_LOAD='(1.0,-1.0)';
      PINUSE='OUT';
    'MKB_DQS_L9':
      PIN_NUMBER='(0,0,0,0,0,0,0,0,0,0,0,0,0,0,0,0,0,0,0,0,0,0,0,0,0,0,0,0,0,0,0~
,0,0,0,0,BW5,0,0,0,0)';
      BIDIRECTIONAL='TRUE';
      INPUT_LOAD='(-0.01,0.01)';
      OUTPUT_LOAD='(1.0,-1.0)';
      PINUSE='BI';
    'MKB_DQS_H5':
      PIN_NUMBER='(0,0,0,0,0,0,0,0,0,0,0,0,0,0,0,0,0,0,0,0,0,0,0,0,0,0,0,0,0,0,0~
,0,0,0,0,CF7,0,0,0,0)';
      BIDIRECTIONAL='TRUE';
      INPUT_LOAD='(-0.01,0.01)';
      OUTPUT_LOAD='(1.0,-1.0)';
      PINUSE='BI';
    'MKB_CA3':
      PIN_NUMBER='(0,0,0,0,0,0,0,0,0,0,0,0,0,0,0,0,0,0,0,0,0,0,0,0,0,0,0,0,0,0,0~
,0,0,0,0,BJ5,0,0,0,0)';
      OUTPUT_LOAD='(1.0,-1.0)';
      PINUSE='OUT';
    'MKA_DATA22':
      PIN_NUMBER='(0,0,0,0,0,0,0,0,0,0,0,0,0,0,0,0,0,0,0,0,0,0,0,0,0,0,0,0,0,0,0~
,0,0,0,0,AB6,0,0,0,0)';
      BIDIRECTIONAL='TRUE';
      INPUT_LOAD='(-0.01,0.01)';
      OUTPUT_LOAD='(1.0,-1.0)';
      PINUSE='BI';
    'MKA_DATA11':
      PIN_NUMBER='(0,0,0,0,0,0,0,0,0,0,0,0,0,0,0,0,0,0,0,0,0,0,0,0,0,0,0,0,0,0,0~
,0,0,0,0,N7,0,0,0,0)';
      BIDIRECTIONAL='TRUE';
      INPUT_LOAD='(-0.01,0.01)';
      OUTPUT_LOAD='(1.0,-1.0)';
      PINUSE='BI';
    'MKA_CHECK2':
      PIN_NUMBER='(0,0,0,0,0,0,0,0,0,0,0,0,0,0,0,0,0,0,0,0,0,0,0,0,0,0,0,0,0,0,0~
,0,0,0,0,AK6,0,0,0,0)';
      BIDIRECTIONAL='TRUE';
      INPUT_LOAD='(-0.01,0.01)';
      OUTPUT_LOAD='(1.0,-1.0)';
      PINUSE='BI';
    'MKA_CA4':
      PIN_NUMBER='(0,0,0,0,0,0,0,0,0,0,0,0,0,0,0,0,0,0,0,0,0,0,0,0,0,0,0,0,0,0,0~
,0,0,0,0,BA5,0,0,0,0)';
      OUTPUT_LOAD='(1.0,-1.0)';
      PINUSE='OUT';
    'MK_RESET_L':
      PIN_NUMBER='(0,0,0,0,0,0,0,0,0,0,0,0,0,0,0,0,0,0,0,0,0,0,0,0,0,0,0,0,0,0,0~
,0,0,0,0,AU7,0,0,0,0)';
      OUTPUT_LOAD='(1.0,-1.0)';
      PINUSE='OUT';
    'MKB_DQS_H6':
      PIN_NUMBER='(0,0,0,0,0,0,0,0,0,0,0,0,0,0,0,0,0,0,0,0,0,0,0,0,0,0,0,0,0,0,0~
,0,0,0,0,CM7,0,0,0,0)';
      BIDIRECTIONAL='TRUE';
      INPUT_LOAD='(-0.01,0.01)';
      OUTPUT_LOAD='(1.0,-1.0)';
      PINUSE='BI';
    'MKB_CA4':
      PIN_NUMBER='(0,0,0,0,0,0,0,0,0,0,0,0,0,0,0,0,0,0,0,0,0,0,0,0,0,0,0,0,0,0,0~
,0,0,0,0,BJ7,0,0,0,0)';
      OUTPUT_LOAD='(1.0,-1.0)';
      PINUSE='OUT';
    'MKA_DATA23':
      PIN_NUMBER='(0,0,0,0,0,0,0,0,0,0,0,0,0,0,0,0,0,0,0,0,0,0,0,0,0,0,0,0,0,0,0~
,0,0,0,0,AC7,0,0,0,0)';
      BIDIRECTIONAL='TRUE';
      INPUT_LOAD='(-0.01,0.01)';
      OUTPUT_LOAD='(1.0,-1.0)';
      PINUSE='BI';
    'MKA_DATA12':
      PIN_NUMBER='(0,0,0,0,0,0,0,0,0,0,0,0,0,0,0,0,0,0,0,0,0,0,0,0,0,0,0,0,0,0,0~
,0,0,0,0,R5,0,0,0,0)';
      BIDIRECTIONAL='TRUE';
      INPUT_LOAD='(-0.01,0.01)';
      OUTPUT_LOAD='(1.0,-1.0)';
      PINUSE='BI';
    'MKA_CHECK3':
      PIN_NUMBER='(0,0,0,0,0,0,0,0,0,0,0,0,0,0,0,0,0,0,0,0,0,0,0,0,0,0,0,0,0,0,0~
,0,0,0,0,AL7,0,0,0,0)';
      BIDIRECTIONAL='TRUE';
      INPUT_LOAD='(-0.01,0.01)';
      OUTPUT_LOAD='(1.0,-1.0)';
      PINUSE='BI';
    'MKA_CA5':
      PIN_NUMBER='(0,0,0,0,0,0,0,0,0,0,0,0,0,0,0,0,0,0,0,0,0,0,0,0,0,0,0,0,0,0,0~
,0,0,0,0,BB6,0,0,0,0)';
      OUTPUT_LOAD='(1.0,-1.0)';
      PINUSE='OUT';
    'MKB_DQS_H7':
      PIN_NUMBER='(0,0,0,0,0,0,0,0,0,0,0,0,0,0,0,0,0,0,0,0,0,0,0,0,0,0,0,0,0,0,0~
,0,0,0,0,CV7,0,0,0,0)';
      BIDIRECTIONAL='TRUE';
      INPUT_LOAD='(-0.01,0.01)';
      OUTPUT_LOAD='(1.0,-1.0)';
      PINUSE='BI';
    'MKB_CA5':
      PIN_NUMBER='(0,0,0,0,0,0,0,0,0,0,0,0,0,0,0,0,0,0,0,0,0,0,0,0,0,0,0,0,0,0,0~
,0,0,0,0,BK7,0,0,0,0)';
      OUTPUT_LOAD='(1.0,-1.0)';
      PINUSE='OUT';
    'MKB0_CS_L0':
      PIN_NUMBER='(0,0,0,0,0,0,0,0,0,0,0,0,0,0,0,0,0,0,0,0,0,0,0,0,0,0,0,0,0,0,0~
,0,0,0,0,BM7,0,0,0,0)';
      OUTPUT_LOAD='(1.0,-1.0)';
      PINUSE='OUT';
    'MKA_DQS_L0':
      PIN_NUMBER='(0,0,0,0,0,0,0,0,0,0,0,0,0,0,0,0,0,0,0,0,0,0,0,0,0,0,0,0,0,0,0~
,0,0,0,0,H6,0,0,0,0)';
      BIDIRECTIONAL='TRUE';
      INPUT_LOAD='(-0.01,0.01)';
      OUTPUT_LOAD='(1.0,-1.0)';
      PINUSE='BI';
    'MKA_DATA24':
      PIN_NUMBER='(0,0,0,0,0,0,0,0,0,0,0,0,0,0,0,0,0,0,0,0,0,0,0,0,0,0,0,0,0,0,0~
,0,0,0,0,AC5,0,0,0,0)';
      BIDIRECTIONAL='TRUE';
      INPUT_LOAD='(-0.01,0.01)';
      OUTPUT_LOAD='(1.0,-1.0)';
      PINUSE='BI';
    'MKA_DATA13':
      PIN_NUMBER='(0,0,0,0,0,0,0,0,0,0,0,0,0,0,0,0,0,0,0,0,0,0,0,0,0,0,0,0,0,0,0~
,0,0,0,0,T7,0,0,0,0)';
      BIDIRECTIONAL='TRUE';
      INPUT_LOAD='(-0.01,0.01)';
      OUTPUT_LOAD='(1.0,-1.0)';
      PINUSE='BI';
    'MKA_CHECK4':
      PIN_NUMBER='(0,0,0,0,0,0,0,0,0,0,0,0,0,0,0,0,0,0,0,0,0,0,0,0,0,0,0,0,0,0,0~
,0,0,0,0,AN5,0,0,0,0)';
      BIDIRECTIONAL='TRUE';
      INPUT_LOAD='(-0.01,0.01)';
      OUTPUT_LOAD='(1.0,-1.0)';
      PINUSE='BI';
    'MKA_CA6':
      PIN_NUMBER='(0,0,0,0,0,0,0,0,0,0,0,0,0,0,0,0,0,0,0,0,0,0,0,0,0,0,0,0,0,0,0~
,0,0,0,0,BB7,0,0,0,0)';
      OUTPUT_LOAD='(1.0,-1.0)';
      PINUSE='OUT';
    'MK0_CLK_L':
      PIN_NUMBER='(0,0,0,0,0,0,0,0,0,0,0,0,0,0,0,0,0,0,0,0,0,0,0,0,0,0,0,0,0,0,0~
,0,0,0,0,BD6,0,0,0,0)';
      OUTPUT_LOAD='(1.0,-1.0)';
      PINUSE='OUT';
    'MKB_DQS_H8':
      PIN_NUMBER='(0,0,0,0,0,0,0,0,0,0,0,0,0,0,0,0,0,0,0,0,0,0,0,0,0,0,0,0,0,0,0~
,0,0,0,0,DD7,0,0,0,0)';
      BIDIRECTIONAL='TRUE';
      INPUT_LOAD='(-0.01,0.01)';
      OUTPUT_LOAD='(1.0,-1.0)';
      PINUSE='BI';
    'MKB_DATA30':
      PIN_NUMBER='(0,0,0,0,0,0,0,0,0,0,0,0,0,0,0,0,0,0,0,0,0,0,0,0,0,0,0,0,0,0,0~
,0,0,0,0,DE5,0,0,0,0)';
      BIDIRECTIONAL='TRUE';
      INPUT_LOAD='(-0.01,0.01)';
      OUTPUT_LOAD='(1.0,-1.0)';
      PINUSE='BI';
    'MKB_CA6':
      PIN_NUMBER='(0,0,0,0,0,0,0,0,0,0,0,0,0,0,0,0,0,0,0,0,0,0,0,0,0,0,0,0,0,0,0~
,0,0,0,0,BK6,0,0,0,0)';
      OUTPUT_LOAD='(1.0,-1.0)';
      PINUSE='OUT';
    'MKB1_CS_L0':
      PIN_NUMBER='(0,0,0,0,0,0,0,0,0,0,0,0,0,0,0,0,0,0,0,0,0,0,0,0,0,0,0,0,0,0,0~
,0,0,0,0,BL5,0,0,0,0)';
      OUTPUT_LOAD='(1.0,-1.0)';
      PINUSE='OUT';
    'MKB0_CS_L1':
      PIN_NUMBER='(0,0,0,0,0,0,0,0,0,0,0,0,0,0,0,0,0,0,0,0,0,0,0,0,0,0,0,0,0,0,0~
,0,0,0,0,BN5,0,0,0,0)';
      OUTPUT_LOAD='(1.0,-1.0)';
      PINUSE='OUT';
    'MKA_DQS_L1':
      PIN_NUMBER='(0,0,0,0,0,0,0,0,0,0,0,0,0,0,0,0,0,0,0,0,0,0,0,0,0,0,0,0,0,0,0~
,0,0,0,0,P6,0,0,0,0)';
      BIDIRECTIONAL='TRUE';
      INPUT_LOAD='(-0.01,0.01)';
      OUTPUT_LOAD='(1.0,-1.0)';
      PINUSE='BI';
    'MKA_DATA25':
      PIN_NUMBER='(0,0,0,0,0,0,0,0,0,0,0,0,0,0,0,0,0,0,0,0,0,0,0,0,0,0,0,0,0,0,0~
,0,0,0,0,AD7,0,0,0,0)';
      BIDIRECTIONAL='TRUE';
      INPUT_LOAD='(-0.01,0.01)';
      OUTPUT_LOAD='(1.0,-1.0)';
      PINUSE='BI';
    'MKA_DATA14':
      PIN_NUMBER='(0,0,0,0,0,0,0,0,0,0,0,0,0,0,0,0,0,0,0,0,0,0,0,0,0,0,0,0,0,0,0~
,0,0,0,0,T6,0,0,0,0)';
      BIDIRECTIONAL='TRUE';
      INPUT_LOAD='(-0.01,0.01)';
      OUTPUT_LOAD='(1.0,-1.0)';
      PINUSE='BI';
    'MKA_DATA0':
      PIN_NUMBER='(0,0,0,0,0,0,0,0,0,0,0,0,0,0,0,0,0,0,0,0,0,0,0,0,0,0,0,0,0,0,0~
,0,0,0,0,E5,0,0,0,0)';
      BIDIRECTIONAL='TRUE';
      INPUT_LOAD='(-0.01,0.01)';
      OUTPUT_LOAD='(1.0,-1.0)';
      PINUSE='BI';
    'MKA_CHECK5':
      PIN_NUMBER='(0,0,0,0,0,0,0,0,0,0,0,0,0,0,0,0,0,0,0,0,0,0,0,0,0,0,0,0,0,0,0~
,0,0,0,0,AP7,0,0,0,0)';
      BIDIRECTIONAL='TRUE';
      INPUT_LOAD='(-0.01,0.01)';
      OUTPUT_LOAD='(1.0,-1.0)';
      PINUSE='BI';
    'MK1_CLK_L':
      PIN_NUMBER='(0,0,0,0,0,0,0,0,0,0,0,0,0,0,0,0,0,0,0,0,0,0,0,0,0,0,0,0,0,0,0~
,0,0,0,0,BG5,0,0,0,0)';
      OUTPUT_LOAD='(1.0,-1.0)';
      PINUSE='OUT';
    'MKB_DQS_H9':
      PIN_NUMBER='(0,0,0,0,0,0,0,0,0,0,0,0,0,0,0,0,0,0,0,0,0,0,0,0,0,0,0,0,0,0,0~
,0,0,0,0,BV6,0,0,0,0)';
      BIDIRECTIONAL='TRUE';
      INPUT_LOAD='(-0.01,0.01)';
      OUTPUT_LOAD='(1.0,-1.0)';
      PINUSE='BI';
    'MKB_DATA31':
      PIN_NUMBER='(0,0,0,0,0,0,0,0,0,0,0,0,0,0,0,0,0,0,0,0,0,0,0,0,0,0,0,0,0,0,0~
,0,0,0,0,DF7,0,0,0,0)';
      BIDIRECTIONAL='TRUE';
      INPUT_LOAD='(-0.01,0.01)';
      OUTPUT_LOAD='(1.0,-1.0)';
      PINUSE='BI';
    'MKB_DATA20':
      PIN_NUMBER='(0,0,0,0,0,0,0,0,0,0,0,0,0,0,0,0,0,0,0,0,0,0,0,0,0,0,0,0,0,0,0~
,0,0,0,0,CV6,0,0,0,0)';
      BIDIRECTIONAL='TRUE';
      INPUT_LOAD='(-0.01,0.01)';
      OUTPUT_LOAD='(1.0,-1.0)';
      PINUSE='BI';
    'MKB_DATA0':
      PIN_NUMBER='(0,0,0,0,0,0,0,0,0,0,0,0,0,0,0,0,0,0,0,0,0,0,0,0,0,0,0,0,0,0,0~
,0,0,0,0,CB6,0,0,0,0)';
      BIDIRECTIONAL='TRUE';
      INPUT_LOAD='(-0.01,0.01)';
      OUTPUT_LOAD='(1.0,-1.0)';
      PINUSE='BI';
    'MKB_CHECK0':
      PIN_NUMBER='(0,0,0,0,0,0,0,0,0,0,0,0,0,0,0,0,0,0,0,0,0,0,0,0,0,0,0,0,0,0,0~
,0,0,0,0,BY6,0,0,0,0)';
      BIDIRECTIONAL='TRUE';
      INPUT_LOAD='(-0.01,0.01)';
      OUTPUT_LOAD='(1.0,-1.0)';
      PINUSE='BI';
    'MKB1_CS_L1':
      PIN_NUMBER='(0,0,0,0,0,0,0,0,0,0,0,0,0,0,0,0,0,0,0,0,0,0,0,0,0,0,0,0,0,0,0~
,0,0,0,0,BM6,0,0,0,0)';
      OUTPUT_LOAD='(1.0,-1.0)';
      PINUSE='OUT';
    'MKA_DQS_L2':
      PIN_NUMBER='(0,0,0,0,0,0,0,0,0,0,0,0,0,0,0,0,0,0,0,0,0,0,0,0,0,0,0,0,0,0,0~
,0,0,0,0,Y6,0,0,0,0)';
      BIDIRECTIONAL='TRUE';
      INPUT_LOAD='(-0.01,0.01)';
      OUTPUT_LOAD='(1.0,-1.0)';
      PINUSE='BI';
    'MKA_DATA26':
      PIN_NUMBER='(0,0,0,0,0,0,0,0,0,0,0,0,0,0,0,0,0,0,0,0,0,0,0,0,0,0,0,0,0,0,0~
,0,0,0,0,AD6,0,0,0,0)';
      BIDIRECTIONAL='TRUE';
      INPUT_LOAD='(-0.01,0.01)';
      OUTPUT_LOAD='(1.0,-1.0)';
      PINUSE='BI';
    'MKA_DATA15':
      PIN_NUMBER='(0,0,0,0,0,0,0,0,0,0,0,0,0,0,0,0,0,0,0,0,0,0,0,0,0,0,0,0,0,0,0~
,0,0,0,0,U7,0,0,0,0)';
      BIDIRECTIONAL='TRUE';
      INPUT_LOAD='(-0.01,0.01)';
      OUTPUT_LOAD='(1.0,-1.0)';
      PINUSE='BI';
    'MKA_DATA1':
      PIN_NUMBER='(0,0,0,0,0,0,0,0,0,0,0,0,0,0,0,0,0,0,0,0,0,0,0,0,0,0,0,0,0,0,0~
,0,0,0,0,F7,0,0,0,0)';
      BIDIRECTIONAL='TRUE';
      INPUT_LOAD='(-0.01,0.01)';
      OUTPUT_LOAD='(1.0,-1.0)';
      PINUSE='BI';
    'MKA_CHECK6':
      PIN_NUMBER='(0,0,0,0,0,0,0,0,0,0,0,0,0,0,0,0,0,0,0,0,0,0,0,0,0,0,0,0,0,0,0~
,0,0,0,0,AP6,0,0,0,0)';
      BIDIRECTIONAL='TRUE';
      INPUT_LOAD='(-0.01,0.01)';
      OUTPUT_LOAD='(1.0,-1.0)';
      PINUSE='BI';
    'MKB_DATA21':
      PIN_NUMBER='(0,0,0,0,0,0,0,0,0,0,0,0,0,0,0,0,0,0,0,0,0,0,0,0,0,0,0,0,0,0,0~
,0,0,0,0,CW7,0,0,0,0)';
      BIDIRECTIONAL='TRUE';
      INPUT_LOAD='(-0.01,0.01)';
      OUTPUT_LOAD='(1.0,-1.0)';
      PINUSE='BI';
    'MKB_DATA10':
      PIN_NUMBER='(0,0,0,0,0,0,0,0,0,0,0,0,0,0,0,0,0,0,0,0,0,0,0,0,0,0,0,0,0,0,0~
,0,0,0,0,CJ5,0,0,0,0)';
      BIDIRECTIONAL='TRUE';
      INPUT_LOAD='(-0.01,0.01)';
      OUTPUT_LOAD='(1.0,-1.0)';
      PINUSE='BI';
    'MKB_DATA1':
      PIN_NUMBER='(0,0,0,0,0,0,0,0,0,0,0,0,0,0,0,0,0,0,0,0,0,0,0,0,0,0,0,0,0,0,0~
,0,0,0,0,CC7,0,0,0,0)';
      BIDIRECTIONAL='TRUE';
      INPUT_LOAD='(-0.01,0.01)';
      OUTPUT_LOAD='(1.0,-1.0)';
      PINUSE='BI';
    'MKB_CHECK1':
      PIN_NUMBER='(0,0,0,0,0,0,0,0,0,0,0,0,0,0,0,0,0,0,0,0,0,0,0,0,0,0,0,0,0,0,0~
,0,0,0,0,CA7,0,0,0,0)';
      BIDIRECTIONAL='TRUE';
      INPUT_LOAD='(-0.01,0.01)';
      OUTPUT_LOAD='(1.0,-1.0)';
      PINUSE='BI';
    'MKA_DQS_L3':
      PIN_NUMBER='(0,0,0,0,0,0,0,0,0,0,0,0,0,0,0,0,0,0,0,0,0,0,0,0,0,0,0,0,0,0,0~
,0,0,0,0,AF6,0,0,0,0)';
      BIDIRECTIONAL='TRUE';
      INPUT_LOAD='(-0.01,0.01)';
      OUTPUT_LOAD='(1.0,-1.0)';
      PINUSE='BI';
    'MKA_DATA27':
      PIN_NUMBER='(0,0,0,0,0,0,0,0,0,0,0,0,0,0,0,0,0,0,0,0,0,0,0,0,0,0,0,0,0,0,0~
,0,0,0,0,AE7,0,0,0,0)';
      BIDIRECTIONAL='TRUE';
      INPUT_LOAD='(-0.01,0.01)';
      OUTPUT_LOAD='(1.0,-1.0)';
      PINUSE='BI';
    'MKA_DATA16':
      PIN_NUMBER='(0,0,0,0,0,0,0,0,0,0,0,0,0,0,0,0,0,0,0,0,0,0,0,0,0,0,0,0,0,0,0~
,0,0,0,0,U5,0,0,0,0)';
      BIDIRECTIONAL='TRUE';
      INPUT_LOAD='(-0.01,0.01)';
      OUTPUT_LOAD='(1.0,-1.0)';
      PINUSE='BI';
    'MKA_DATA2':
      PIN_NUMBER='(0,0,0,0,0,0,0,0,0,0,0,0,0,0,0,0,0,0,0,0,0,0,0,0,0,0,0,0,0,0,0~
,0,0,0,0,F6,0,0,0,0)';
      BIDIRECTIONAL='TRUE';
      INPUT_LOAD='(-0.01,0.01)';
      OUTPUT_LOAD='(1.0,-1.0)';
      PINUSE='BI';
    'MKA_CHECK7':
      PIN_NUMBER='(0,0,0,0,0,0,0,0,0,0,0,0,0,0,0,0,0,0,0,0,0,0,0,0,0,0,0,0,0,0,0~
,0,0,0,0,AR7,0,0,0,0)';
      BIDIRECTIONAL='TRUE';
      INPUT_LOAD='(-0.01,0.01)';
      OUTPUT_LOAD='(1.0,-1.0)';
      PINUSE='BI';
    'MKA0_RSP_L':
      PIN_NUMBER='(0,0,0,0,0,0,0,0,0,0,0,0,0,0,0,0,0,0,0,0,0,0,0,0,0,0,0,0,0,0,0~
,0,0,0,0,BN7,0,0,0,0)';
      INPUT_LOAD='(-0.01,0.01)';
      PINUSE='IN';
    'MK_ALERT_L':
      PIN_NUMBER='(0,0,0,0,0,0,0,0,0,0,0,0,0,0,0,0,0,0,0,0,0,0,0,0,0,0,0,0,0,0,0~
,0,0,0,0,AT7,0,0,0,0)';
      INPUT_LOAD='(-0.01,0.01)';
      PINUSE='IN';
    'MKB_DATA22':
      PIN_NUMBER='(0,0,0,0,0,0,0,0,0,0,0,0,0,0,0,0,0,0,0,0,0,0,0,0,0,0,0,0,0,0,0~
,0,0,0,0,CW5,0,0,0,0)';
      BIDIRECTIONAL='TRUE';
      INPUT_LOAD='(-0.01,0.01)';
      OUTPUT_LOAD='(1.0,-1.0)';
      PINUSE='BI';
    'MKB_DATA11':
      PIN_NUMBER='(0,0,0,0,0,0,0,0,0,0,0,0,0,0,0,0,0,0,0,0,0,0,0,0,0,0,0,0,0,0,0~
,0,0,0,0,CK7,0,0,0,0)';
      BIDIRECTIONAL='TRUE';
      INPUT_LOAD='(-0.01,0.01)';
      OUTPUT_LOAD='(1.0,-1.0)';
      PINUSE='BI';
    'MKB_DATA2':
      PIN_NUMBER='(0,0,0,0,0,0,0,0,0,0,0,0,0,0,0,0,0,0,0,0,0,0,0,0,0,0,0,0,0,0,0~
,0,0,0,0,CC5,0,0,0,0)';
      BIDIRECTIONAL='TRUE';
      INPUT_LOAD='(-0.01,0.01)';
      OUTPUT_LOAD='(1.0,-1.0)';
      PINUSE='BI';
    'MKB_CHECK2':
      PIN_NUMBER='(0,0,0,0,0,0,0,0,0,0,0,0,0,0,0,0,0,0,0,0,0,0,0,0,0,0,0,0,0,0,0~
,0,0,0,0,CA5,0,0,0,0)';
      BIDIRECTIONAL='TRUE';
      INPUT_LOAD='(-0.01,0.01)';
      OUTPUT_LOAD='(1.0,-1.0)';
      PINUSE='BI';
    'MKA_DQS_L4':
      PIN_NUMBER='(0,0,0,0,0,0,0,0,0,0,0,0,0,0,0,0,0,0,0,0,0,0,0,0,0,0,0,0,0,0,0~
,0,0,0,0,AM6,0,0,0,0)';
      BIDIRECTIONAL='TRUE';
      INPUT_LOAD='(-0.01,0.01)';
      OUTPUT_LOAD='(1.0,-1.0)';
      PINUSE='BI';
    'MKA_DQS_H0':
      PIN_NUMBER='(0,0,0,0,0,0,0,0,0,0,0,0,0,0,0,0,0,0,0,0,0,0,0,0,0,0,0,0,0,0,0~
,0,0,0,0,G5,0,0,0,0)';
      BIDIRECTIONAL='TRUE';
      INPUT_LOAD='(-0.01,0.01)';
      OUTPUT_LOAD='(1.0,-1.0)';
      PINUSE='BI';
    'MKA_DATA28':
      PIN_NUMBER='(0,0,0,0,0,0,0,0,0,0,0,0,0,0,0,0,0,0,0,0,0,0,0,0,0,0,0,0,0,0,0~
,0,0,0,0,AG5,0,0,0,0)';
      BIDIRECTIONAL='TRUE';
      INPUT_LOAD='(-0.01,0.01)';
      OUTPUT_LOAD='(1.0,-1.0)';
      PINUSE='BI';
    'MKA_DATA17':
      PIN_NUMBER='(0,0,0,0,0,0,0,0,0,0,0,0,0,0,0,0,0,0,0,0,0,0,0,0,0,0,0,0,0,0,0~
,0,0,0,0,V7,0,0,0,0)';
      BIDIRECTIONAL='TRUE';
      INPUT_LOAD='(-0.01,0.01)';
      OUTPUT_LOAD='(1.0,-1.0)';
      PINUSE='BI';
    'MKA_DATA3':
      PIN_NUMBER='(0,0,0,0,0,0,0,0,0,0,0,0,0,0,0,0,0,0,0,0,0,0,0,0,0,0,0,0,0,0,0~
,0,0,0,0,G7,0,0,0,0)';
      BIDIRECTIONAL='TRUE';
      INPUT_LOAD='(-0.01,0.01)';
      OUTPUT_LOAD='(1.0,-1.0)';
      PINUSE='BI';
    'MKA1_RSP_L':
      PIN_NUMBER='(0,0,0,0,0,0,0,0,0,0,0,0,0,0,0,0,0,0,0,0,0,0,0,0,0,0,0,0,0,0,0~
,0,0,0,0,BP7,0,0,0,0)';
      INPUT_LOAD='(-0.01,0.01)';
      PINUSE='IN';
    'MKB_DATA23':
      PIN_NUMBER='(0,0,0,0,0,0,0,0,0,0,0,0,0,0,0,0,0,0,0,0,0,0,0,0,0,0,0,0,0,0,0~
,0,0,0,0,CY7,0,0,0,0)';
      BIDIRECTIONAL='TRUE';
      INPUT_LOAD='(-0.01,0.01)';
      OUTPUT_LOAD='(1.0,-1.0)';
      PINUSE='BI';
    'MKB_DATA12':
      PIN_NUMBER='(0,0,0,0,0,0,0,0,0,0,0,0,0,0,0,0,0,0,0,0,0,0,0,0,0,0,0,0,0,0,0~
,0,0,0,0,CM6,0,0,0,0)';
      BIDIRECTIONAL='TRUE';
      INPUT_LOAD='(-0.01,0.01)';
      OUTPUT_LOAD='(1.0,-1.0)';
      PINUSE='BI';
    'MKB_DATA3':
      PIN_NUMBER='(0,0,0,0,0,0,0,0,0,0,0,0,0,0,0,0,0,0,0,0,0,0,0,0,0,0,0,0,0,0,0~
,0,0,0,0,CD7,0,0,0,0)';
      BIDIRECTIONAL='TRUE';
      INPUT_LOAD='(-0.01,0.01)';
      OUTPUT_LOAD='(1.0,-1.0)';
      PINUSE='BI';
    'MKB_CHECK3':
      PIN_NUMBER='(0,0,0,0,0,0,0,0,0,0,0,0,0,0,0,0,0,0,0,0,0,0,0,0,0,0,0,0,0,0,0~
,0,0,0,0,CB7,0,0,0,0)';
      BIDIRECTIONAL='TRUE';
      INPUT_LOAD='(-0.01,0.01)';
      OUTPUT_LOAD='(1.0,-1.0)';
      PINUSE='BI';
    'MKA_DQS_L5':
      PIN_NUMBER='(0,0,0,0,0,0,0,0,0,0,0,0,0,0,0,0,0,0,0,0,0,0,0,0,0,0,0,0,0,0,0~
,0,0,0,0,H7,0,0,0,0)';
      BIDIRECTIONAL='TRUE';
      INPUT_LOAD='(-0.01,0.01)';
      OUTPUT_LOAD='(1.0,-1.0)';
      PINUSE='BI';
    'MKA_DQS_H1':
      PIN_NUMBER='(0,0,0,0,0,0,0,0,0,0,0,0,0,0,0,0,0,0,0,0,0,0,0,0,0,0,0,0,0,0,0~
,0,0,0,0,N5,0,0,0,0)';
      BIDIRECTIONAL='TRUE';
      INPUT_LOAD='(-0.01,0.01)';
      OUTPUT_LOAD='(1.0,-1.0)';
      PINUSE='BI';
    'MKA_DATA29':
      PIN_NUMBER='(0,0,0,0,0,0,0,0,0,0,0,0,0,0,0,0,0,0,0,0,0,0,0,0,0,0,0,0,0,0,0~
,0,0,0,0,AH7,0,0,0,0)';
      BIDIRECTIONAL='TRUE';
      INPUT_LOAD='(-0.01,0.01)';
      OUTPUT_LOAD='(1.0,-1.0)';
      PINUSE='BI';
    'MKA_DATA18':
      PIN_NUMBER='(0,0,0,0,0,0,0,0,0,0,0,0,0,0,0,0,0,0,0,0,0,0,0,0,0,0,0,0,0,0,0~
,0,0,0,0,V6,0,0,0,0)';
      BIDIRECTIONAL='TRUE';
      INPUT_LOAD='(-0.01,0.01)';
      OUTPUT_LOAD='(1.0,-1.0)';
      PINUSE='BI';
    'MKA_DATA4':
      PIN_NUMBER='(0,0,0,0,0,0,0,0,0,0,0,0,0,0,0,0,0,0,0,0,0,0,0,0,0,0,0,0,0,0,0~
,0,0,0,0,J5,0,0,0,0)';
      BIDIRECTIONAL='TRUE';
      INPUT_LOAD='(-0.01,0.01)';
      OUTPUT_LOAD='(1.0,-1.0)';
      PINUSE='BI';
    'MKB_DQS_L0':
      PIN_NUMBER='(0,0,0,0,0,0,0,0,0,0,0,0,0,0,0,0,0,0,0,0,0,0,0,0,0,0,0,0,0,0,0~
,0,0,0,0,CE5,0,0,0,0)';
      BIDIRECTIONAL='TRUE';
      INPUT_LOAD='(-0.01,0.01)';
      OUTPUT_LOAD='(1.0,-1.0)';
      PINUSE='BI';
    'MKB_DATA24':
      PIN_NUMBER='(0,0,0,0,0,0,0,0,0,0,0,0,0,0,0,0,0,0,0,0,0,0,0,0,0,0,0,0,0,0,0~
,0,0,0,0,CY6,0,0,0,0)';
      BIDIRECTIONAL='TRUE';
      INPUT_LOAD='(-0.01,0.01)';
      OUTPUT_LOAD='(1.0,-1.0)';
      PINUSE='BI';
    'MKB_DATA13':
      PIN_NUMBER='(0,0,0,0,0,0,0,0,0,0,0,0,0,0,0,0,0,0,0,0,0,0,0,0,0,0,0,0,0,0,0~
,0,0,0,0,CN7,0,0,0,0)';
      BIDIRECTIONAL='TRUE';
      INPUT_LOAD='(-0.01,0.01)';
      OUTPUT_LOAD='(1.0,-1.0)';
      PINUSE='BI';
    'MKB_DATA4':
      PIN_NUMBER='(0,0,0,0,0,0,0,0,0,0,0,0,0,0,0,0,0,0,0,0,0,0,0,0,0,0,0,0,0,0,0~
,0,0,0,0,CF6,0,0,0,0)';
      BIDIRECTIONAL='TRUE';
      INPUT_LOAD='(-0.01,0.01)';
      OUTPUT_LOAD='(1.0,-1.0)';
      PINUSE='BI';
    'MKB_CHECK4':
      PIN_NUMBER='(0,0,0,0,0,0,0,0,0,0,0,0,0,0,0,0,0,0,0,0,0,0,0,0,0,0,0,0,0,0,0~
,0,0,0,0,BT6,0,0,0,0)';
      BIDIRECTIONAL='TRUE';
      INPUT_LOAD='(-0.01,0.01)';
      OUTPUT_LOAD='(1.0,-1.0)';
      PINUSE='BI';
    'MKA_DQS_L6':
      PIN_NUMBER='(0,0,0,0,0,0,0,0,0,0,0,0,0,0,0,0,0,0,0,0,0,0,0,0,0,0,0,0,0,0,0~
,0,0,0,0,P7,0,0,0,0)';
      BIDIRECTIONAL='TRUE';
      INPUT_LOAD='(-0.01,0.01)';
      OUTPUT_LOAD='(1.0,-1.0)';
      PINUSE='BI';
    'MKA_DQS_H2':
      PIN_NUMBER='(0,0,0,0,0,0,0,0,0,0,0,0,0,0,0,0,0,0,0,0,0,0,0,0,0,0,0,0,0,0,0~
,0,0,0,0,W5,0,0,0,0)';
      BIDIRECTIONAL='TRUE';
      INPUT_LOAD='(-0.01,0.01)';
      OUTPUT_LOAD='(1.0,-1.0)';
      PINUSE='BI';
    'MKA_DATA19':
      PIN_NUMBER='(0,0,0,0,0,0,0,0,0,0,0,0,0,0,0,0,0,0,0,0,0,0,0,0,0,0,0,0,0,0,0~
,0,0,0,0,W7,0,0,0,0)';
      BIDIRECTIONAL='TRUE';
      INPUT_LOAD='(-0.01,0.01)';
      OUTPUT_LOAD='(1.0,-1.0)';
      PINUSE='BI';
    'MKA_DATA5':
      PIN_NUMBER='(0,0,0,0,0,0,0,0,0,0,0,0,0,0,0,0,0,0,0,0,0,0,0,0,0,0,0,0,0,0,0~
,0,0,0,0,K7,0,0,0,0)';
      BIDIRECTIONAL='TRUE';
      INPUT_LOAD='(-0.01,0.01)';
      OUTPUT_LOAD='(1.0,-1.0)';
      PINUSE='BI';
    'MKB_DQS_L1':
      PIN_NUMBER='(0,0,0,0,0,0,0,0,0,0,0,0,0,0,0,0,0,0,0,0,0,0,0,0,0,0,0,0,0,0,0~
,0,0,0,0,CL5,0,0,0,0)';
      BIDIRECTIONAL='TRUE';
      INPUT_LOAD='(-0.01,0.01)';
      OUTPUT_LOAD='(1.0,-1.0)';
      PINUSE='BI';
    'MKB_DATA25':
      PIN_NUMBER='(0,0,0,0,0,0,0,0,0,0,0,0,0,0,0,0,0,0,0,0,0,0,0,0,0,0,0,0,0,0,0~
,0,0,0,0,DA7,0,0,0,0)';
      BIDIRECTIONAL='TRUE';
      INPUT_LOAD='(-0.01,0.01)';
      OUTPUT_LOAD='(1.0,-1.0)';
      PINUSE='BI';
    'MKB_DATA14':
      PIN_NUMBER='(0,0,0,0,0,0,0,0,0,0,0,0,0,0,0,0,0,0,0,0,0,0,0,0,0,0,0,0,0,0,0~
,0,0,0,0,CN5,0,0,0,0)';
      BIDIRECTIONAL='TRUE';
      INPUT_LOAD='(-0.01,0.01)';
      OUTPUT_LOAD='(1.0,-1.0)';
      PINUSE='BI';
    'MKB_DATA5':
      PIN_NUMBER='(0,0,0,0,0,0,0,0,0,0,0,0,0,0,0,0,0,0,0,0,0,0,0,0,0,0,0,0,0,0,0~
,0,0,0,0,CG7,0,0,0,0)';
      BIDIRECTIONAL='TRUE';
      INPUT_LOAD='(-0.01,0.01)';
      OUTPUT_LOAD='(1.0,-1.0)';
      PINUSE='BI';
    'MKB_CHECK5':
      PIN_NUMBER='(0,0,0,0,0,0,0,0,0,0,0,0,0,0,0,0,0,0,0,0,0,0,0,0,0,0,0,0,0,0,0~
,0,0,0,0,BU7,0,0,0,0)';
      BIDIRECTIONAL='TRUE';
      INPUT_LOAD='(-0.01,0.01)';
      OUTPUT_LOAD='(1.0,-1.0)';
      PINUSE='BI';
    'MKA_PAR':
      PIN_NUMBER='(0,0,0,0,0,0,0,0,0,0,0,0,0,0,0,0,0,0,0,0,0,0,0,0,0,0,0,0,0,0,0~
,0,0,0,0,BC7,0,0,0,0)';
      OUTPUT_LOAD='(1.0,-1.0)';
      PINUSE='OUT';
    'MKA_DQS_L7':
      PIN_NUMBER='(0,0,0,0,0,0,0,0,0,0,0,0,0,0,0,0,0,0,0,0,0,0,0,0,0,0,0,0,0,0,0~
,0,0,0,0,Y7,0,0,0,0)';
      BIDIRECTIONAL='TRUE';
      INPUT_LOAD='(-0.01,0.01)';
      OUTPUT_LOAD='(1.0,-1.0)';
      PINUSE='BI';
    'MKA_DQS_H3':
      PIN_NUMBER='(0,0,0,0,0,0,0,0,0,0,0,0,0,0,0,0,0,0,0,0,0,0,0,0,0,0,0,0,0,0,0~
,0,0,0,0,AE5,0,0,0,0)';
      BIDIRECTIONAL='TRUE';
      INPUT_LOAD='(-0.01,0.01)';
      OUTPUT_LOAD='(1.0,-1.0)';
      PINUSE='BI';
    'MKA_DATA6':
      PIN_NUMBER='(0,0,0,0,0,0,0,0,0,0,0,0,0,0,0,0,0,0,0,0,0,0,0,0,0,0,0,0,0,0,0~
,0,0,0,0,K6,0,0,0,0)';
      BIDIRECTIONAL='TRUE';
      INPUT_LOAD='(-0.01,0.01)';
      OUTPUT_LOAD='(1.0,-1.0)';
      PINUSE='BI';
    'MKB_PAR':
      PIN_NUMBER='(0,0,0,0,0,0,0,0,0,0,0,0,0,0,0,0,0,0,0,0,0,0,0,0,0,0,0,0,0,0,0~
,0,0,0,0,BL7,0,0,0,0)';
      OUTPUT_LOAD='(1.0,-1.0)';
      PINUSE='OUT';
    'MKB_DQS_L2':
      PIN_NUMBER='(0,0,0,0,0,0,0,0,0,0,0,0,0,0,0,0,0,0,0,0,0,0,0,0,0,0,0,0,0,0,0~
,0,0,0,0,CU5,0,0,0,0)';
      BIDIRECTIONAL='TRUE';
      INPUT_LOAD='(-0.01,0.01)';
      OUTPUT_LOAD='(1.0,-1.0)';
      PINUSE='BI';
    'MKB_DATA26':
      PIN_NUMBER='(0,0,0,0,0,0,0,0,0,0,0,0,0,0,0,0,0,0,0,0,0,0,0,0,0,0,0,0,0,0,0~
,0,0,0,0,DA5,0,0,0,0)';
      BIDIRECTIONAL='TRUE';
      INPUT_LOAD='(-0.01,0.01)';
      OUTPUT_LOAD='(1.0,-1.0)';
      PINUSE='BI';
    'MKB_DATA15':
      PIN_NUMBER='(0,0,0,0,0,0,0,0,0,0,0,0,0,0,0,0,0,0,0,0,0,0,0,0,0,0,0,0,0,0,0~
,0,0,0,0,CP7,0,0,0,0)';
      BIDIRECTIONAL='TRUE';
      INPUT_LOAD='(-0.01,0.01)';
      OUTPUT_LOAD='(1.0,-1.0)';
      PINUSE='BI';
    'MKB_DATA6':
      PIN_NUMBER='(0,0,0,0,0,0,0,0,0,0,0,0,0,0,0,0,0,0,0,0,0,0,0,0,0,0,0,0,0,0,0~
,0,0,0,0,CG5,0,0,0,0)';
      BIDIRECTIONAL='TRUE';
      INPUT_LOAD='(-0.01,0.01)';
      OUTPUT_LOAD='(1.0,-1.0)';
      PINUSE='BI';
    'MKB_CHECK6':
      PIN_NUMBER='(0,0,0,0,0,0,0,0,0,0,0,0,0,0,0,0,0,0,0,0,0,0,0,0,0,0,0,0,0,0,0~
,0,0,0,0,BU5,0,0,0,0)';
      BIDIRECTIONAL='TRUE';
      INPUT_LOAD='(-0.01,0.01)';
      OUTPUT_LOAD='(1.0,-1.0)';
      PINUSE='BI';
    'MKA_DQS_L8':
      PIN_NUMBER='(0,0,0,0,0,0,0,0,0,0,0,0,0,0,0,0,0,0,0,0,0,0,0,0,0,0,0,0,0,0,0~
,0,0,0,0,AF7,0,0,0,0)';
      BIDIRECTIONAL='TRUE';
      INPUT_LOAD='(-0.01,0.01)';
      OUTPUT_LOAD='(1.0,-1.0)';
      PINUSE='BI';
    'MKA_DQS_H4':
      PIN_NUMBER='(0,0,0,0,0,0,0,0,0,0,0,0,0,0,0,0,0,0,0,0,0,0,0,0,0,0,0,0,0,0,0~
,0,0,0,0,AL5,0,0,0,0)';
      BIDIRECTIONAL='TRUE';
      INPUT_LOAD='(-0.01,0.01)';
      OUTPUT_LOAD='(1.0,-1.0)';
      PINUSE='BI';
    'MKA_DATA7':
      PIN_NUMBER='(0,0,0,0,0,0,0,0,0,0,0,0,0,0,0,0,0,0,0,0,0,0,0,0,0,0,0,0,0,0,0~
,0,0,0,0,L7,0,0,0,0)';
      BIDIRECTIONAL='TRUE';
      INPUT_LOAD='(-0.01,0.01)';
      OUTPUT_LOAD='(1.0,-1.0)';
      PINUSE='BI';
    'MKB_DQS_L3':
      PIN_NUMBER='(0,0,0,0,0,0,0,0,0,0,0,0,0,0,0,0,0,0,0,0,0,0,0,0,0,0,0,0,0,0,0~
,0,0,0,0,DC5,0,0,0,0)';
      BIDIRECTIONAL='TRUE';
      INPUT_LOAD='(-0.01,0.01)';
      OUTPUT_LOAD='(1.0,-1.0)';
      PINUSE='BI';
    'MKB_DATA27':
      PIN_NUMBER='(0,0,0,0,0,0,0,0,0,0,0,0,0,0,0,0,0,0,0,0,0,0,0,0,0,0,0,0,0,0,0~
,0,0,0,0,DB7,0,0,0,0)';
      BIDIRECTIONAL='TRUE';
      INPUT_LOAD='(-0.01,0.01)';
      OUTPUT_LOAD='(1.0,-1.0)';
      PINUSE='BI';
    'MKB_DATA16':
      PIN_NUMBER='(0,0,0,0,0,0,0,0,0,0,0,0,0,0,0,0,0,0,0,0,0,0,0,0,0,0,0,0,0,0,0~
,0,0,0,0,CP6,0,0,0,0)';
      BIDIRECTIONAL='TRUE';
      INPUT_LOAD='(-0.01,0.01)';
      OUTPUT_LOAD='(1.0,-1.0)';
      PINUSE='BI';
    'MKB_DATA7':
      PIN_NUMBER='(0,0,0,0,0,0,0,0,0,0,0,0,0,0,0,0,0,0,0,0,0,0,0,0,0,0,0,0,0,0,0~
,0,0,0,0,CH7,0,0,0,0)';
      BIDIRECTIONAL='TRUE';
      INPUT_LOAD='(-0.01,0.01)';
      OUTPUT_LOAD='(1.0,-1.0)';
      PINUSE='BI';
    'MKB_CHECK7':
      PIN_NUMBER='(0,0,0,0,0,0,0,0,0,0,0,0,0,0,0,0,0,0,0,0,0,0,0,0,0,0,0,0,0,0,0~
,0,0,0,0,BV7,0,0,0,0)';
      BIDIRECTIONAL='TRUE';
      INPUT_LOAD='(-0.01,0.01)';
      OUTPUT_LOAD='(1.0,-1.0)';
      PINUSE='BI';
    'MKB0_RSP_L':
      PIN_NUMBER='(0,0,0,0,0,0,0,0,0,0,0,0,0,0,0,0,0,0,0,0,0,0,0,0,0,0,0,0,0,0,0~
,0,0,0,0,BP6,0,0,0,0)';
      INPUT_LOAD='(-0.01,0.01)';
      PINUSE='IN';
    'MKA_DQS_L9':
      PIN_NUMBER='(0,0,0,0,0,0,0,0,0,0,0,0,0,0,0,0,0,0,0,0,0,0,0,0,0,0,0,0,0,0,0~
,0,0,0,0,AM7,0,0,0,0)';
      BIDIRECTIONAL='TRUE';
      INPUT_LOAD='(-0.01,0.01)';
      OUTPUT_LOAD='(1.0,-1.0)';
      PINUSE='BI';
    'MKA_DQS_H5':
      PIN_NUMBER='(0,0,0,0,0,0,0,0,0,0,0,0,0,0,0,0,0,0,0,0,0,0,0,0,0,0,0,0,0,0,0~
,0,0,0,0,J7,0,0,0,0)';
      BIDIRECTIONAL='TRUE';
      INPUT_LOAD='(-0.01,0.01)';
      OUTPUT_LOAD='(1.0,-1.0)';
      PINUSE='BI';
    'MKA_DATA8':
      PIN_NUMBER='(0,0,0,0,0,0,0,0,0,0,0,0,0,0,0,0,0,0,0,0,0,0,0,0,0,0,0,0,0,0,0~
,0,0,0,0,L5,0,0,0,0)';
      BIDIRECTIONAL='TRUE';
      INPUT_LOAD='(-0.01,0.01)';
      OUTPUT_LOAD='(1.0,-1.0)';
      PINUSE='BI';
    'MKB_DQS_L4':
      PIN_NUMBER='(0,0,0,0,0,0,0,0,0,0,0,0,0,0,0,0,0,0,0,0,0,0,0,0,0,0,0,0,0,0,0~
,0,0,0,0,BW7,0,0,0,0)';
      BIDIRECTIONAL='TRUE';
      INPUT_LOAD='(-0.01,0.01)';
      OUTPUT_LOAD='(1.0,-1.0)';
      PINUSE='BI';
    'MKB_DQS_H0':
      PIN_NUMBER='(0,0,0,0,0,0,0,0,0,0,0,0,0,0,0,0,0,0,0,0,0,0,0,0,0,0,0,0,0,0,0~
,0,0,0,0,CD6,0,0,0,0)';
      BIDIRECTIONAL='TRUE';
      INPUT_LOAD='(-0.01,0.01)';
      OUTPUT_LOAD='(1.0,-1.0)';
      PINUSE='BI';
    'MKB_DATA28':
      PIN_NUMBER='(0,0,0,0,0,0,0,0,0,0,0,0,0,0,0,0,0,0,0,0,0,0,0,0,0,0,0,0,0,0,0~
,0,0,0,0,DD6,0,0,0,0)';
      BIDIRECTIONAL='TRUE';
      INPUT_LOAD='(-0.01,0.01)';
      OUTPUT_LOAD='(1.0,-1.0)';
      PINUSE='BI';
    'MKB_DATA17':
      PIN_NUMBER='(0,0,0,0,0,0,0,0,0,0,0,0,0,0,0,0,0,0,0,0,0,0,0,0,0,0,0,0,0,0,0~
,0,0,0,0,CR7,0,0,0,0)';
      BIDIRECTIONAL='TRUE';
      INPUT_LOAD='(-0.01,0.01)';
      OUTPUT_LOAD='(1.0,-1.0)';
      PINUSE='BI';
    'MKB_DATA8':
      PIN_NUMBER='(0,0,0,0,0,0,0,0,0,0,0,0,0,0,0,0,0,0,0,0,0,0,0,0,0,0,0,0,0,0,0~
,0,0,0,0,CH6,0,0,0,0)';
      BIDIRECTIONAL='TRUE';
      INPUT_LOAD='(-0.01,0.01)';
      OUTPUT_LOAD='(1.0,-1.0)';
      PINUSE='BI';
    'MKB1_RSP_L':
      PIN_NUMBER='(0,0,0,0,0,0,0,0,0,0,0,0,0,0,0,0,0,0,0,0,0,0,0,0,0,0,0,0,0,0,0~
,0,0,0,0,BR5,0,0,0,0)';
      INPUT_LOAD='(-0.01,0.01)';
      PINUSE='IN';
    'MKA_DQS_H6':
      PIN_NUMBER='(0,0,0,0,0,0,0,0,0,0,0,0,0,0,0,0,0,0,0,0,0,0,0,0,0,0,0,0,0,0,0~
,0,0,0,0,R7,0,0,0,0)';
      BIDIRECTIONAL='TRUE';
      INPUT_LOAD='(-0.01,0.01)';
      OUTPUT_LOAD='(1.0,-1.0)';
      PINUSE='BI';
    'MKA_DATA9':
      PIN_NUMBER='(0,0,0,0,0,0,0,0,0,0,0,0,0,0,0,0,0,0,0,0,0,0,0,0,0,0,0,0,0,0,0~
,0,0,0,0,M7,0,0,0,0)';
      BIDIRECTIONAL='TRUE';
      INPUT_LOAD='(-0.01,0.01)';
      OUTPUT_LOAD='(1.0,-1.0)';
      PINUSE='BI';
    'MKB_DQS_L5':
      PIN_NUMBER='(0,0,0,0,0,0,0,0,0,0,0,0,0,0,0,0,0,0,0,0,0,0,0,0,0,0,0,0,0,0,0~
,0,0,0,0,CE7,0,0,0,0)';
      BIDIRECTIONAL='TRUE';
      INPUT_LOAD='(-0.01,0.01)';
      OUTPUT_LOAD='(1.0,-1.0)';
      PINUSE='BI';
    'MKB_DQS_H1':
      PIN_NUMBER='(0,0,0,0,0,0,0,0,0,0,0,0,0,0,0,0,0,0,0,0,0,0,0,0,0,0,0,0,0,0,0~
,0,0,0,0,CK6,0,0,0,0)';
      BIDIRECTIONAL='TRUE';
      INPUT_LOAD='(-0.01,0.01)';
      OUTPUT_LOAD='(1.0,-1.0)';
      PINUSE='BI';
    'MKB_DATA29':
      PIN_NUMBER='(0,0,0,0,0,0,0,0,0,0,0,0,0,0,0,0,0,0,0,0,0,0,0,0,0,0,0,0,0,0,0~
,0,0,0,0,DE7,0,0,0,0)';
      BIDIRECTIONAL='TRUE';
      INPUT_LOAD='(-0.01,0.01)';
      OUTPUT_LOAD='(1.0,-1.0)';
      PINUSE='BI';
    'MKB_DATA18':
      PIN_NUMBER='(0,0,0,0,0,0,0,0,0,0,0,0,0,0,0,0,0,0,0,0,0,0,0,0,0,0,0,0,0,0,0~
,0,0,0,0,CR5,0,0,0,0)';
      BIDIRECTIONAL='TRUE';
      INPUT_LOAD='(-0.01,0.01)';
      OUTPUT_LOAD='(1.0,-1.0)';
      PINUSE='BI';
    'MKB_DATA9':
      PIN_NUMBER='(0,0,0,0,0,0,0,0,0,0,0,0,0,0,0,0,0,0,0,0,0,0,0,0,0,0,0,0,0,0,0~
,0,0,0,0,CJ7,0,0,0,0)';
      BIDIRECTIONAL='TRUE';
      INPUT_LOAD='(-0.01,0.01)';
      OUTPUT_LOAD='(1.0,-1.0)';
      PINUSE='BI';
    'MKA_DQS_H7':
      PIN_NUMBER='(0,0,0,0,0,0,0,0,0,0,0,0,0,0,0,0,0,0,0,0,0,0,0,0,0,0,0,0,0,0,0~
,0,0,0,0,AA7,0,0,0,0)';
      BIDIRECTIONAL='TRUE';
      INPUT_LOAD='(-0.01,0.01)';
      OUTPUT_LOAD='(1.0,-1.0)';
      PINUSE='BI';
    'MKA_CA0':
      PIN_NUMBER='(0,0,0,0,0,0,0,0,0,0,0,0,0,0,0,0,0,0,0,0,0,0,0,0,0,0,0,0,0,0,0~
,0,0,0,0,AW5,0,0,0,0)';
      OUTPUT_LOAD='(1.0,-1.0)';
      PINUSE='OUT';
    'MKA0_CS_L0':
      PIN_NUMBER='(0,0,0,0,0,0,0,0,0,0,0,0,0,0,0,0,0,0,0,0,0,0,0,0,0,0,0,0,0,0,0~
,0,0,0,0,AU5,0,0,0,0)';
      OUTPUT_LOAD='(1.0,-1.0)';
      PINUSE='OUT';
    'TEST39K':
      PIN_NUMBER='(0,0,0,0,0,0,0,0,0,0,0,0,0,0,0,0,0,0,0,0,0,0,0,0,0,0,0,0,0,0,0~
,0,0,0,0,BF7,0,0,0,0)';
      OUTPUT_LOAD='(1.0,-1.0)';
      PINUSE='OUT';
    'VSS_BV46':
      PIN_NUMBER='(0,0,0,0,0,0,0,0,0,0,0,0,0,0,0,0,0,0,0,0,0,0,0,0,0,0,0,0,0,0,0~
,0,0,0,0,0,BV46,0,0,0)';
      PINUSE='POWER';
      NO_LOAD_CHECK='Both';
      NO_IO_CHECK='Both';
      NO_ASSERT_CHECK='TRUE';
      NO_DIR_CHECK='TRUE';
      ALLOW_CONNECT='TRUE';
    'VSS_BV47':
      PIN_NUMBER='(0,0,0,0,0,0,0,0,0,0,0,0,0,0,0,0,0,0,0,0,0,0,0,0,0,0,0,0,0,0,0~
,0,0,0,0,0,BV47,0,0,0)';
      PINUSE='POWER';
      NO_LOAD_CHECK='Both';
      NO_IO_CHECK='Both';
      NO_ASSERT_CHECK='TRUE';
      NO_DIR_CHECK='TRUE';
      ALLOW_CONNECT='TRUE';
    'VSS_BV48':
      PIN_NUMBER='(0,0,0,0,0,0,0,0,0,0,0,0,0,0,0,0,0,0,0,0,0,0,0,0,0,0,0,0,0,0,0~
,0,0,0,0,0,BV48,0,0,0)';
      PINUSE='POWER';
      NO_LOAD_CHECK='Both';
      NO_IO_CHECK='Both';
      NO_ASSERT_CHECK='TRUE';
      NO_DIR_CHECK='TRUE';
      ALLOW_CONNECT='TRUE';
    'VSS_BV49':
      PIN_NUMBER='(0,0,0,0,0,0,0,0,0,0,0,0,0,0,0,0,0,0,0,0,0,0,0,0,0,0,0,0,0,0,0~
,0,0,0,0,0,BV49,0,0,0)';
      PINUSE='POWER';
      NO_LOAD_CHECK='Both';
      NO_IO_CHECK='Both';
      NO_ASSERT_CHECK='TRUE';
      NO_DIR_CHECK='TRUE';
      ALLOW_CONNECT='TRUE';
    'VSS_BV50':
      PIN_NUMBER='(0,0,0,0,0,0,0,0,0,0,0,0,0,0,0,0,0,0,0,0,0,0,0,0,0,0,0,0,0,0,0~
,0,0,0,0,0,BV50,0,0,0)';
      PINUSE='POWER';
      NO_LOAD_CHECK='Both';
      NO_IO_CHECK='Both';
      NO_ASSERT_CHECK='TRUE';
      NO_DIR_CHECK='TRUE';
      ALLOW_CONNECT='TRUE';
    'VSS_BV51':
      PIN_NUMBER='(0,0,0,0,0,0,0,0,0,0,0,0,0,0,0,0,0,0,0,0,0,0,0,0,0,0,0,0,0,0,0~
,0,0,0,0,0,BV51,0,0,0)';
      PINUSE='POWER';
      NO_LOAD_CHECK='Both';
      NO_IO_CHECK='Both';
      NO_ASSERT_CHECK='TRUE';
      NO_DIR_CHECK='TRUE';
      ALLOW_CONNECT='TRUE';
    'VSS_BV52':
      PIN_NUMBER='(0,0,0,0,0,0,0,0,0,0,0,0,0,0,0,0,0,0,0,0,0,0,0,0,0,0,0,0,0,0,0~
,0,0,0,0,0,BV52,0,0,0)';
      PINUSE='POWER';
      NO_LOAD_CHECK='Both';
      NO_IO_CHECK='Both';
      NO_ASSERT_CHECK='TRUE';
      NO_DIR_CHECK='TRUE';
      ALLOW_CONNECT='TRUE';
    'VSS_BV53':
      PIN_NUMBER='(0,0,0,0,0,0,0,0,0,0,0,0,0,0,0,0,0,0,0,0,0,0,0,0,0,0,0,0,0,0,0~
,0,0,0,0,0,BV53,0,0,0)';
      PINUSE='POWER';
      NO_LOAD_CHECK='Both';
      NO_IO_CHECK='Both';
      NO_ASSERT_CHECK='TRUE';
      NO_DIR_CHECK='TRUE';
      ALLOW_CONNECT='TRUE';
    'VSS_BV59':
      PIN_NUMBER='(0,0,0,0,0,0,0,0,0,0,0,0,0,0,0,0,0,0,0,0,0,0,0,0,0,0,0,0,0,0,0~
,0,0,0,0,0,BV59,0,0,0)';
      PINUSE='POWER';
      NO_LOAD_CHECK='Both';
      NO_IO_CHECK='Both';
      NO_ASSERT_CHECK='TRUE';
      NO_DIR_CHECK='TRUE';
      ALLOW_CONNECT='TRUE';
    'VSS_BV61':
      PIN_NUMBER='(0,0,0,0,0,0,0,0,0,0,0,0,0,0,0,0,0,0,0,0,0,0,0,0,0,0,0,0,0,0,0~
,0,0,0,0,0,BV61,0,0,0)';
      PINUSE='POWER';
      NO_LOAD_CHECK='Both';
      NO_IO_CHECK='Both';
      NO_ASSERT_CHECK='TRUE';
      NO_DIR_CHECK='TRUE';
      ALLOW_CONNECT='TRUE';
    'VSS_BV66':
      PIN_NUMBER='(0,0,0,0,0,0,0,0,0,0,0,0,0,0,0,0,0,0,0,0,0,0,0,0,0,0,0,0,0,0,0~
,0,0,0,0,0,BV66,0,0,0)';
      PINUSE='POWER';
      NO_LOAD_CHECK='Both';
      NO_IO_CHECK='Both';
      NO_ASSERT_CHECK='TRUE';
      NO_DIR_CHECK='TRUE';
      ALLOW_CONNECT='TRUE';
    'VSS_BV68':
      PIN_NUMBER='(0,0,0,0,0,0,0,0,0,0,0,0,0,0,0,0,0,0,0,0,0,0,0,0,0,0,0,0,0,0,0~
,0,0,0,0,0,BV68,0,0,0)';
      PINUSE='POWER';
      NO_LOAD_CHECK='Both';
      NO_IO_CHECK='Both';
      NO_ASSERT_CHECK='TRUE';
      NO_DIR_CHECK='TRUE';
      ALLOW_CONNECT='TRUE';
    'VSS_BV73':
      PIN_NUMBER='(0,0,0,0,0,0,0,0,0,0,0,0,0,0,0,0,0,0,0,0,0,0,0,0,0,0,0,0,0,0,0~
,0,0,0,0,0,BV73,0,0,0)';
      PINUSE='POWER';
      NO_LOAD_CHECK='Both';
      NO_IO_CHECK='Both';
      NO_ASSERT_CHECK='TRUE';
      NO_DIR_CHECK='TRUE';
      ALLOW_CONNECT='TRUE';
    'VSS_BW1':
      PIN_NUMBER='(0,0,0,0,0,0,0,0,0,0,0,0,0,0,0,0,0,0,0,0,0,0,0,0,0,0,0,0,0,0,0~
,0,0,0,0,0,BW1,0,0,0)';
      PINUSE='POWER';
      NO_LOAD_CHECK='Both';
      NO_IO_CHECK='Both';
      NO_ASSERT_CHECK='TRUE';
      NO_DIR_CHECK='TRUE';
      ALLOW_CONNECT='TRUE';
    'VSS_BW4':
      PIN_NUMBER='(0,0,0,0,0,0,0,0,0,0,0,0,0,0,0,0,0,0,0,0,0,0,0,0,0,0,0,0,0,0,0~
,0,0,0,0,0,BW4,0,0,0)';
      PINUSE='POWER';
      NO_LOAD_CHECK='Both';
      NO_IO_CHECK='Both';
      NO_ASSERT_CHECK='TRUE';
      NO_DIR_CHECK='TRUE';
      ALLOW_CONNECT='TRUE';
    'VSS_BW6':
      PIN_NUMBER='(0,0,0,0,0,0,0,0,0,0,0,0,0,0,0,0,0,0,0,0,0,0,0,0,0,0,0,0,0,0,0~
,0,0,0,0,0,BW6,0,0,0)';
      PINUSE='POWER';
      NO_LOAD_CHECK='Both';
      NO_IO_CHECK='Both';
      NO_ASSERT_CHECK='TRUE';
      NO_DIR_CHECK='TRUE';
      ALLOW_CONNECT='TRUE';
    'VSS_BW8':
      PIN_NUMBER='(0,0,0,0,0,0,0,0,0,0,0,0,0,0,0,0,0,0,0,0,0,0,0,0,0,0,0,0,0,0,0~
,0,0,0,0,0,BW8,0,0,0)';
      PINUSE='POWER';
      NO_LOAD_CHECK='Both';
      NO_IO_CHECK='Both';
      NO_ASSERT_CHECK='TRUE';
      NO_DIR_CHECK='TRUE';
      ALLOW_CONNECT='TRUE';
    'VSS_BW11':
      PIN_NUMBER='(0,0,0,0,0,0,0,0,0,0,0,0,0,0,0,0,0,0,0,0,0,0,0,0,0,0,0,0,0,0,0~
,0,0,0,0,0,BW11,0,0,0)';
      PINUSE='POWER';
      NO_LOAD_CHECK='Both';
      NO_IO_CHECK='Both';
      NO_ASSERT_CHECK='TRUE';
      NO_DIR_CHECK='TRUE';
      ALLOW_CONNECT='TRUE';
    'VSS_BW13':
      PIN_NUMBER='(0,0,0,0,0,0,0,0,0,0,0,0,0,0,0,0,0,0,0,0,0,0,0,0,0,0,0,0,0,0,0~
,0,0,0,0,0,BW13,0,0,0)';
      PINUSE='POWER';
      NO_LOAD_CHECK='Both';
      NO_IO_CHECK='Both';
      NO_ASSERT_CHECK='TRUE';
      NO_DIR_CHECK='TRUE';
      ALLOW_CONNECT='TRUE';
    'VSS_BW15':
      PIN_NUMBER='(0,0,0,0,0,0,0,0,0,0,0,0,0,0,0,0,0,0,0,0,0,0,0,0,0,0,0,0,0,0,0~
,0,0,0,0,0,BW15,0,0,0)';
      PINUSE='POWER';
      NO_LOAD_CHECK='Both';
      NO_IO_CHECK='Both';
      NO_ASSERT_CHECK='TRUE';
      NO_DIR_CHECK='TRUE';
      ALLOW_CONNECT='TRUE';
    'VSS_BW18':
      PIN_NUMBER='(0,0,0,0,0,0,0,0,0,0,0,0,0,0,0,0,0,0,0,0,0,0,0,0,0,0,0,0,0,0,0~
,0,0,0,0,0,BW18,0,0,0)';
      PINUSE='POWER';
      NO_LOAD_CHECK='Both';
      NO_IO_CHECK='Both';
      NO_ASSERT_CHECK='TRUE';
      NO_DIR_CHECK='TRUE';
      ALLOW_CONNECT='TRUE';
    'VSS_BW20':
      PIN_NUMBER='(0,0,0,0,0,0,0,0,0,0,0,0,0,0,0,0,0,0,0,0,0,0,0,0,0,0,0,0,0,0,0~
,0,0,0,0,0,BW20,0,0,0)';
      PINUSE='POWER';
      NO_LOAD_CHECK='Both';
      NO_IO_CHECK='Both';
      NO_ASSERT_CHECK='TRUE';
      NO_DIR_CHECK='TRUE';
      ALLOW_CONNECT='TRUE';
    'VSS_BW22':
      PIN_NUMBER='(0,0,0,0,0,0,0,0,0,0,0,0,0,0,0,0,0,0,0,0,0,0,0,0,0,0,0,0,0,0,0~
,0,0,0,0,0,BW22,0,0,0)';
      PINUSE='POWER';
      NO_LOAD_CHECK='Both';
      NO_IO_CHECK='Both';
      NO_ASSERT_CHECK='TRUE';
      NO_DIR_CHECK='TRUE';
      ALLOW_CONNECT='TRUE';
    'VSS_BW28':
      PIN_NUMBER='(0,0,0,0,0,0,0,0,0,0,0,0,0,0,0,0,0,0,0,0,0,0,0,0,0,0,0,0,0,0,0~
,0,0,0,0,0,BW28,0,0,0)';
      PINUSE='POWER';
      NO_LOAD_CHECK='Both';
      NO_IO_CHECK='Both';
      NO_ASSERT_CHECK='TRUE';
      NO_DIR_CHECK='TRUE';
      ALLOW_CONNECT='TRUE';
    'VSS_BW31':
      PIN_NUMBER='(0,0,0,0,0,0,0,0,0,0,0,0,0,0,0,0,0,0,0,0,0,0,0,0,0,0,0,0,0,0,0~
,0,0,0,0,0,BW31,0,0,0)';
      PINUSE='POWER';
      NO_LOAD_CHECK='Both';
      NO_IO_CHECK='Both';
      NO_ASSERT_CHECK='TRUE';
      NO_DIR_CHECK='TRUE';
      ALLOW_CONNECT='TRUE';
    'VSS_BW34':
      PIN_NUMBER='(0,0,0,0,0,0,0,0,0,0,0,0,0,0,0,0,0,0,0,0,0,0,0,0,0,0,0,0,0,0,0~
,0,0,0,0,0,BW34,0,0,0)';
      PINUSE='POWER';
      NO_LOAD_CHECK='Both';
      NO_IO_CHECK='Both';
      NO_ASSERT_CHECK='TRUE';
      NO_DIR_CHECK='TRUE';
      ALLOW_CONNECT='TRUE';
    'VSS_BW42':
      PIN_NUMBER='(0,0,0,0,0,0,0,0,0,0,0,0,0,0,0,0,0,0,0,0,0,0,0,0,0,0,0,0,0,0,0~
,0,0,0,0,0,BW42,0,0,0)';
      PINUSE='POWER';
      NO_LOAD_CHECK='Both';
      NO_IO_CHECK='Both';
      NO_ASSERT_CHECK='TRUE';
      NO_DIR_CHECK='TRUE';
      ALLOW_CONNECT='TRUE';
    'VSS_BW45':
      PIN_NUMBER='(0,0,0,0,0,0,0,0,0,0,0,0,0,0,0,0,0,0,0,0,0,0,0,0,0,0,0,0,0,0,0~
,0,0,0,0,0,BW45,0,0,0)';
      PINUSE='POWER';
      NO_LOAD_CHECK='Both';
      NO_IO_CHECK='Both';
      NO_ASSERT_CHECK='TRUE';
      NO_DIR_CHECK='TRUE';
      ALLOW_CONNECT='TRUE';
    'VSS_BW48':
      PIN_NUMBER='(0,0,0,0,0,0,0,0,0,0,0,0,0,0,0,0,0,0,0,0,0,0,0,0,0,0,0,0,0,0,0~
,0,0,0,0,0,BW48,0,0,0)';
      PINUSE='POWER';
      NO_LOAD_CHECK='Both';
      NO_IO_CHECK='Both';
      NO_ASSERT_CHECK='TRUE';
      NO_DIR_CHECK='TRUE';
      ALLOW_CONNECT='TRUE';
    'VSS_BW51':
      PIN_NUMBER='(0,0,0,0,0,0,0,0,0,0,0,0,0,0,0,0,0,0,0,0,0,0,0,0,0,0,0,0,0,0,0~
,0,0,0,0,0,BW51,0,0,0)';
      PINUSE='POWER';
      NO_LOAD_CHECK='Both';
      NO_IO_CHECK='Both';
      NO_ASSERT_CHECK='TRUE';
      NO_DIR_CHECK='TRUE';
      ALLOW_CONNECT='TRUE';
    'VSS_BW54':
      PIN_NUMBER='(0,0,0,0,0,0,0,0,0,0,0,0,0,0,0,0,0,0,0,0,0,0,0,0,0,0,0,0,0,0,0~
,0,0,0,0,0,BW54,0,0,0)';
      PINUSE='POWER';
      NO_LOAD_CHECK='Both';
      NO_IO_CHECK='Both';
      NO_ASSERT_CHECK='TRUE';
      NO_DIR_CHECK='TRUE';
      ALLOW_CONNECT='TRUE';
    'VSS_BW56':
      PIN_NUMBER='(0,0,0,0,0,0,0,0,0,0,0,0,0,0,0,0,0,0,0,0,0,0,0,0,0,0,0,0,0,0,0~
,0,0,0,0,0,BW56,0,0,0)';
      PINUSE='POWER';
      NO_LOAD_CHECK='Both';
      NO_IO_CHECK='Both';
      NO_ASSERT_CHECK='TRUE';
      NO_DIR_CHECK='TRUE';
      ALLOW_CONNECT='TRUE';
    'VSS_BW58':
      PIN_NUMBER='(0,0,0,0,0,0,0,0,0,0,0,0,0,0,0,0,0,0,0,0,0,0,0,0,0,0,0,0,0,0,0~
,0,0,0,0,0,BW58,0,0,0)';
      PINUSE='POWER';
      NO_LOAD_CHECK='Both';
      NO_IO_CHECK='Both';
      NO_ASSERT_CHECK='TRUE';
      NO_DIR_CHECK='TRUE';
      ALLOW_CONNECT='TRUE';
    'VSS_BW61':
      PIN_NUMBER='(0,0,0,0,0,0,0,0,0,0,0,0,0,0,0,0,0,0,0,0,0,0,0,0,0,0,0,0,0,0,0~
,0,0,0,0,0,BW61,0,0,0)';
      PINUSE='POWER';
      NO_LOAD_CHECK='Both';
      NO_IO_CHECK='Both';
      NO_ASSERT_CHECK='TRUE';
      NO_DIR_CHECK='TRUE';
      ALLOW_CONNECT='TRUE';
    'VSS_BW63':
      PIN_NUMBER='(0,0,0,0,0,0,0,0,0,0,0,0,0,0,0,0,0,0,0,0,0,0,0,0,0,0,0,0,0,0,0~
,0,0,0,0,0,BW63,0,0,0)';
      PINUSE='POWER';
      NO_LOAD_CHECK='Both';
      NO_IO_CHECK='Both';
      NO_ASSERT_CHECK='TRUE';
      NO_DIR_CHECK='TRUE';
      ALLOW_CONNECT='TRUE';
    'VSS_BW65':
      PIN_NUMBER='(0,0,0,0,0,0,0,0,0,0,0,0,0,0,0,0,0,0,0,0,0,0,0,0,0,0,0,0,0,0,0~
,0,0,0,0,0,BW65,0,0,0)';
      PINUSE='POWER';
      NO_LOAD_CHECK='Both';
      NO_IO_CHECK='Both';
      NO_ASSERT_CHECK='TRUE';
      NO_DIR_CHECK='TRUE';
      ALLOW_CONNECT='TRUE';
    'VSS_BW68':
      PIN_NUMBER='(0,0,0,0,0,0,0,0,0,0,0,0,0,0,0,0,0,0,0,0,0,0,0,0,0,0,0,0,0,0,0~
,0,0,0,0,0,BW68,0,0,0)';
      PINUSE='POWER';
      NO_LOAD_CHECK='Both';
      NO_IO_CHECK='Both';
      NO_ASSERT_CHECK='TRUE';
      NO_DIR_CHECK='TRUE';
      ALLOW_CONNECT='TRUE';
    'VSS_BW70':
      PIN_NUMBER='(0,0,0,0,0,0,0,0,0,0,0,0,0,0,0,0,0,0,0,0,0,0,0,0,0,0,0,0,0,0,0~
,0,0,0,0,0,BW70,0,0,0)';
      PINUSE='POWER';
      NO_LOAD_CHECK='Both';
      NO_IO_CHECK='Both';
      NO_ASSERT_CHECK='TRUE';
      NO_DIR_CHECK='TRUE';
      ALLOW_CONNECT='TRUE';
    'VSS_BW72':
      PIN_NUMBER='(0,0,0,0,0,0,0,0,0,0,0,0,0,0,0,0,0,0,0,0,0,0,0,0,0,0,0,0,0,0,0~
,0,0,0,0,0,BW72,0,0,0)';
      PINUSE='POWER';
      NO_LOAD_CHECK='Both';
      NO_IO_CHECK='Both';
      NO_ASSERT_CHECK='TRUE';
      NO_DIR_CHECK='TRUE';
      ALLOW_CONNECT='TRUE';
    'VSS_BW75':
      PIN_NUMBER='(0,0,0,0,0,0,0,0,0,0,0,0,0,0,0,0,0,0,0,0,0,0,0,0,0,0,0,0,0,0,0~
,0,0,0,0,0,BW75,0,0,0)';
      PINUSE='POWER';
      NO_LOAD_CHECK='Both';
      NO_IO_CHECK='Both';
      NO_ASSERT_CHECK='TRUE';
      NO_DIR_CHECK='TRUE';
      ALLOW_CONNECT='TRUE';
    'VSS_BY3':
      PIN_NUMBER='(0,0,0,0,0,0,0,0,0,0,0,0,0,0,0,0,0,0,0,0,0,0,0,0,0,0,0,0,0,0,0~
,0,0,0,0,0,BY3,0,0,0)';
      PINUSE='POWER';
      NO_LOAD_CHECK='Both';
      NO_IO_CHECK='Both';
      NO_ASSERT_CHECK='TRUE';
      NO_DIR_CHECK='TRUE';
      ALLOW_CONNECT='TRUE';
    'VSS_BY5':
      PIN_NUMBER='(0,0,0,0,0,0,0,0,0,0,0,0,0,0,0,0,0,0,0,0,0,0,0,0,0,0,0,0,0,0,0~
,0,0,0,0,0,BY5,0,0,0)';
      PINUSE='POWER';
      NO_LOAD_CHECK='Both';
      NO_IO_CHECK='Both';
      NO_ASSERT_CHECK='TRUE';
      NO_DIR_CHECK='TRUE';
      ALLOW_CONNECT='TRUE';
    'VSS_BY8':
      PIN_NUMBER='(0,0,0,0,0,0,0,0,0,0,0,0,0,0,0,0,0,0,0,0,0,0,0,0,0,0,0,0,0,0,0~
,0,0,0,0,0,BY8,0,0,0)';
      PINUSE='POWER';
      NO_LOAD_CHECK='Both';
      NO_IO_CHECK='Both';
      NO_ASSERT_CHECK='TRUE';
      NO_DIR_CHECK='TRUE';
      ALLOW_CONNECT='TRUE';
    'VSS_BY10':
      PIN_NUMBER='(0,0,0,0,0,0,0,0,0,0,0,0,0,0,0,0,0,0,0,0,0,0,0,0,0,0,0,0,0,0,0~
,0,0,0,0,0,BY10,0,0,0)';
      PINUSE='POWER';
      NO_LOAD_CHECK='Both';
      NO_IO_CHECK='Both';
      NO_ASSERT_CHECK='TRUE';
      NO_DIR_CHECK='TRUE';
      ALLOW_CONNECT='TRUE';
    'VSS_BY12':
      PIN_NUMBER='(0,0,0,0,0,0,0,0,0,0,0,0,0,0,0,0,0,0,0,0,0,0,0,0,0,0,0,0,0,0,0~
,0,0,0,0,0,BY12,0,0,0)';
      PINUSE='POWER';
      NO_LOAD_CHECK='Both';
      NO_IO_CHECK='Both';
      NO_ASSERT_CHECK='TRUE';
      NO_DIR_CHECK='TRUE';
      ALLOW_CONNECT='TRUE';
    'VSS_BY15':
      PIN_NUMBER='(0,0,0,0,0,0,0,0,0,0,0,0,0,0,0,0,0,0,0,0,0,0,0,0,0,0,0,0,0,0,0~
,0,0,0,0,0,BY15,0,0,0)';
      PINUSE='POWER';
      NO_LOAD_CHECK='Both';
      NO_IO_CHECK='Both';
      NO_ASSERT_CHECK='TRUE';
      NO_DIR_CHECK='TRUE';
      ALLOW_CONNECT='TRUE';
    'VSS_BY17':
      PIN_NUMBER='(0,0,0,0,0,0,0,0,0,0,0,0,0,0,0,0,0,0,0,0,0,0,0,0,0,0,0,0,0,0,0~
,0,0,0,0,0,BY17,0,0,0)';
      PINUSE='POWER';
      NO_LOAD_CHECK='Both';
      NO_IO_CHECK='Both';
      NO_ASSERT_CHECK='TRUE';
      NO_DIR_CHECK='TRUE';
      ALLOW_CONNECT='TRUE';
    'VSS_BY19':
      PIN_NUMBER='(0,0,0,0,0,0,0,0,0,0,0,0,0,0,0,0,0,0,0,0,0,0,0,0,0,0,0,0,0,0,0~
,0,0,0,0,0,BY19,0,0,0)';
      PINUSE='POWER';
      NO_LOAD_CHECK='Both';
      NO_IO_CHECK='Both';
      NO_ASSERT_CHECK='TRUE';
      NO_DIR_CHECK='TRUE';
      ALLOW_CONNECT='TRUE';
    'VSS_BY22':
      PIN_NUMBER='(0,0,0,0,0,0,0,0,0,0,0,0,0,0,0,0,0,0,0,0,0,0,0,0,0,0,0,0,0,0,0~
,0,0,0,0,0,BY22,0,0,0)';
      PINUSE='POWER';
      NO_LOAD_CHECK='Both';
      NO_IO_CHECK='Both';
      NO_ASSERT_CHECK='TRUE';
      NO_DIR_CHECK='TRUE';
      ALLOW_CONNECT='TRUE';
    'VSS_BY25':
      PIN_NUMBER='(0,0,0,0,0,0,0,0,0,0,0,0,0,0,0,0,0,0,0,0,0,0,0,0,0,0,0,0,0,0,0~
,0,0,0,0,0,BY25,0,0,0)';
      PINUSE='POWER';
      NO_LOAD_CHECK='Both';
      NO_IO_CHECK='Both';
      NO_ASSERT_CHECK='TRUE';
      NO_DIR_CHECK='TRUE';
      ALLOW_CONNECT='TRUE';
    'VSS_BY28':
      PIN_NUMBER='(0,0,0,0,0,0,0,0,0,0,0,0,0,0,0,0,0,0,0,0,0,0,0,0,0,0,0,0,0,0,0~
,0,0,0,0,0,BY28,0,0,0)';
      PINUSE='POWER';
      NO_LOAD_CHECK='Both';
      NO_IO_CHECK='Both';
      NO_ASSERT_CHECK='TRUE';
      NO_DIR_CHECK='TRUE';
      ALLOW_CONNECT='TRUE';
    'VSS_BY31':
      PIN_NUMBER='(0,0,0,0,0,0,0,0,0,0,0,0,0,0,0,0,0,0,0,0,0,0,0,0,0,0,0,0,0,0,0~
,0,0,0,0,0,BY31,0,0,0)';
      PINUSE='POWER';
      NO_LOAD_CHECK='Both';
      NO_IO_CHECK='Both';
      NO_ASSERT_CHECK='TRUE';
      NO_DIR_CHECK='TRUE';
      ALLOW_CONNECT='TRUE';
    'VSS_BY34':
      PIN_NUMBER='(0,0,0,0,0,0,0,0,0,0,0,0,0,0,0,0,0,0,0,0,0,0,0,0,0,0,0,0,0,0,0~
,0,0,0,0,0,BY34,0,0,0)';
      PINUSE='POWER';
      NO_LOAD_CHECK='Both';
      NO_IO_CHECK='Both';
      NO_ASSERT_CHECK='TRUE';
      NO_DIR_CHECK='TRUE';
      ALLOW_CONNECT='TRUE';
    'VSS_BY37':
      PIN_NUMBER='(0,0,0,0,0,0,0,0,0,0,0,0,0,0,0,0,0,0,0,0,0,0,0,0,0,0,0,0,0,0,0~
,0,0,0,0,0,BY37,0,0,0)';
      PINUSE='POWER';
      NO_LOAD_CHECK='Both';
      NO_IO_CHECK='Both';
      NO_ASSERT_CHECK='TRUE';
      NO_DIR_CHECK='TRUE';
      ALLOW_CONNECT='TRUE';
    'VSS_BY39':
      PIN_NUMBER='(0,0,0,0,0,0,0,0,0,0,0,0,0,0,0,0,0,0,0,0,0,0,0,0,0,0,0,0,0,0,0~
,0,0,0,0,0,BY39,0,0,0)';
      PINUSE='POWER';
      NO_LOAD_CHECK='Both';
      NO_IO_CHECK='Both';
      NO_ASSERT_CHECK='TRUE';
      NO_DIR_CHECK='TRUE';
      ALLOW_CONNECT='TRUE';
    'VSS_BY42':
      PIN_NUMBER='(0,0,0,0,0,0,0,0,0,0,0,0,0,0,0,0,0,0,0,0,0,0,0,0,0,0,0,0,0,0,0~
,0,0,0,0,0,BY42,0,0,0)';
      PINUSE='POWER';
      NO_LOAD_CHECK='Both';
      NO_IO_CHECK='Both';
      NO_ASSERT_CHECK='TRUE';
      NO_DIR_CHECK='TRUE';
      ALLOW_CONNECT='TRUE';
    'VSS_BY45':
      PIN_NUMBER='(0,0,0,0,0,0,0,0,0,0,0,0,0,0,0,0,0,0,0,0,0,0,0,0,0,0,0,0,0,0,0~
,0,0,0,0,0,BY45,0,0,0)';
      PINUSE='POWER';
      NO_LOAD_CHECK='Both';
      NO_IO_CHECK='Both';
      NO_ASSERT_CHECK='TRUE';
      NO_DIR_CHECK='TRUE';
      ALLOW_CONNECT='TRUE';
    'VSS_BY48':
      PIN_NUMBER='(0,0,0,0,0,0,0,0,0,0,0,0,0,0,0,0,0,0,0,0,0,0,0,0,0,0,0,0,0,0,0~
,0,0,0,0,0,BY48,0,0,0)';
      PINUSE='POWER';
      NO_LOAD_CHECK='Both';
      NO_IO_CHECK='Both';
      NO_ASSERT_CHECK='TRUE';
      NO_DIR_CHECK='TRUE';
      ALLOW_CONNECT='TRUE';
    'VSS_BY51':
      PIN_NUMBER='(0,0,0,0,0,0,0,0,0,0,0,0,0,0,0,0,0,0,0,0,0,0,0,0,0,0,0,0,0,0,0~
,0,0,0,0,0,BY51,0,0,0)';
      PINUSE='POWER';
      NO_LOAD_CHECK='Both';
      NO_IO_CHECK='Both';
      NO_ASSERT_CHECK='TRUE';
      NO_DIR_CHECK='TRUE';
      ALLOW_CONNECT='TRUE';
    'VSS_BY54':
      PIN_NUMBER='(0,0,0,0,0,0,0,0,0,0,0,0,0,0,0,0,0,0,0,0,0,0,0,0,0,0,0,0,0,0,0~
,0,0,0,0,0,BY54,0,0,0)';
      PINUSE='POWER';
      NO_LOAD_CHECK='Both';
      NO_IO_CHECK='Both';
      NO_ASSERT_CHECK='TRUE';
      NO_DIR_CHECK='TRUE';
      ALLOW_CONNECT='TRUE';
    'VSS_BY57':
      PIN_NUMBER='(0,0,0,0,0,0,0,0,0,0,0,0,0,0,0,0,0,0,0,0,0,0,0,0,0,0,0,0,0,0,0~
,0,0,0,0,0,BY57,0,0,0)';
      PINUSE='POWER';
      NO_LOAD_CHECK='Both';
      NO_IO_CHECK='Both';
      NO_ASSERT_CHECK='TRUE';
      NO_DIR_CHECK='TRUE';
      ALLOW_CONNECT='TRUE';
    'VSS_BY59':
      PIN_NUMBER='(0,0,0,0,0,0,0,0,0,0,0,0,0,0,0,0,0,0,0,0,0,0,0,0,0,0,0,0,0,0,0~
,0,0,0,0,0,BY59,0,0,0)';
      PINUSE='POWER';
      NO_LOAD_CHECK='Both';
      NO_IO_CHECK='Both';
      NO_ASSERT_CHECK='TRUE';
      NO_DIR_CHECK='TRUE';
      ALLOW_CONNECT='TRUE';
    'VSS_BY61':
      PIN_NUMBER='(0,0,0,0,0,0,0,0,0,0,0,0,0,0,0,0,0,0,0,0,0,0,0,0,0,0,0,0,0,0,0~
,0,0,0,0,0,BY61,0,0,0)';
      PINUSE='POWER';
      NO_LOAD_CHECK='Both';
      NO_IO_CHECK='Both';
      NO_ASSERT_CHECK='TRUE';
      NO_DIR_CHECK='TRUE';
      ALLOW_CONNECT='TRUE';
    'VSS_BY64':
      PIN_NUMBER='(0,0,0,0,0,0,0,0,0,0,0,0,0,0,0,0,0,0,0,0,0,0,0,0,0,0,0,0,0,0,0~
,0,0,0,0,0,BY64,0,0,0)';
      PINUSE='POWER';
      NO_LOAD_CHECK='Both';
      NO_IO_CHECK='Both';
      NO_ASSERT_CHECK='TRUE';
      NO_DIR_CHECK='TRUE';
      ALLOW_CONNECT='TRUE';
    'VSS_BY66':
      PIN_NUMBER='(0,0,0,0,0,0,0,0,0,0,0,0,0,0,0,0,0,0,0,0,0,0,0,0,0,0,0,0,0,0,0~
,0,0,0,0,0,BY66,0,0,0)';
      PINUSE='POWER';
      NO_LOAD_CHECK='Both';
      NO_IO_CHECK='Both';
      NO_ASSERT_CHECK='TRUE';
      NO_DIR_CHECK='TRUE';
      ALLOW_CONNECT='TRUE';
    'VSS_BY68':
      PIN_NUMBER='(0,0,0,0,0,0,0,0,0,0,0,0,0,0,0,0,0,0,0,0,0,0,0,0,0,0,0,0,0,0,0~
,0,0,0,0,0,BY68,0,0,0)';
      PINUSE='POWER';
      NO_LOAD_CHECK='Both';
      NO_IO_CHECK='Both';
      NO_ASSERT_CHECK='TRUE';
      NO_DIR_CHECK='TRUE';
      ALLOW_CONNECT='TRUE';
    'VSS_BY71':
      PIN_NUMBER='(0,0,0,0,0,0,0,0,0,0,0,0,0,0,0,0,0,0,0,0,0,0,0,0,0,0,0,0,0,0,0~
,0,0,0,0,0,BY71,0,0,0)';
      PINUSE='POWER';
      NO_LOAD_CHECK='Both';
      NO_IO_CHECK='Both';
      NO_ASSERT_CHECK='TRUE';
      NO_DIR_CHECK='TRUE';
      ALLOW_CONNECT='TRUE';
    'VSS_BY73':
      PIN_NUMBER='(0,0,0,0,0,0,0,0,0,0,0,0,0,0,0,0,0,0,0,0,0,0,0,0,0,0,0,0,0,0,0~
,0,0,0,0,0,BY73,0,0,0)';
      PINUSE='POWER';
      NO_LOAD_CHECK='Both';
      NO_IO_CHECK='Both';
      NO_ASSERT_CHECK='TRUE';
      NO_DIR_CHECK='TRUE';
      ALLOW_CONNECT='TRUE';
    'VSS_CA1':
      PIN_NUMBER='(0,0,0,0,0,0,0,0,0,0,0,0,0,0,0,0,0,0,0,0,0,0,0,0,0,0,0,0,0,0,0~
,0,0,0,0,0,CA1,0,0,0)';
      PINUSE='POWER';
      NO_LOAD_CHECK='Both';
      NO_IO_CHECK='Both';
      NO_ASSERT_CHECK='TRUE';
      NO_DIR_CHECK='TRUE';
      ALLOW_CONNECT='TRUE';
    'VSS_CA6':
      PIN_NUMBER='(0,0,0,0,0,0,0,0,0,0,0,0,0,0,0,0,0,0,0,0,0,0,0,0,0,0,0,0,0,0,0~
,0,0,0,0,0,CA6,0,0,0)';
      PINUSE='POWER';
      NO_LOAD_CHECK='Both';
      NO_IO_CHECK='Both';
      NO_ASSERT_CHECK='TRUE';
      NO_DIR_CHECK='TRUE';
      ALLOW_CONNECT='TRUE';
    'VSS_CA8':
      PIN_NUMBER='(0,0,0,0,0,0,0,0,0,0,0,0,0,0,0,0,0,0,0,0,0,0,0,0,0,0,0,0,0,0,0~
,0,0,0,0,0,CA8,0,0,0)';
      PINUSE='POWER';
      NO_LOAD_CHECK='Both';
      NO_IO_CHECK='Both';
      NO_ASSERT_CHECK='TRUE';
      NO_DIR_CHECK='TRUE';
      ALLOW_CONNECT='TRUE';
    'VSS_CA13':
      PIN_NUMBER='(0,0,0,0,0,0,0,0,0,0,0,0,0,0,0,0,0,0,0,0,0,0,0,0,0,0,0,0,0,0,0~
,0,0,0,0,0,CA13,0,0,0)';
      PINUSE='POWER';
      NO_LOAD_CHECK='Both';
      NO_IO_CHECK='Both';
      NO_ASSERT_CHECK='TRUE';
      NO_DIR_CHECK='TRUE';
      ALLOW_CONNECT='TRUE';
    'VSS_CA15':
      PIN_NUMBER='(0,0,0,0,0,0,0,0,0,0,0,0,0,0,0,0,0,0,0,0,0,0,0,0,0,0,0,0,0,0,0~
,0,0,0,0,0,CA15,0,0,0)';
      PINUSE='POWER';
      NO_LOAD_CHECK='Both';
      NO_IO_CHECK='Both';
      NO_ASSERT_CHECK='TRUE';
      NO_DIR_CHECK='TRUE';
      ALLOW_CONNECT='TRUE';
    'VSS_CA20':
      PIN_NUMBER='(0,0,0,0,0,0,0,0,0,0,0,0,0,0,0,0,0,0,0,0,0,0,0,0,0,0,0,0,0,0,0~
,0,0,0,0,0,CA20,0,0,0)';
      PINUSE='POWER';
      NO_LOAD_CHECK='Both';
      NO_IO_CHECK='Both';
      NO_ASSERT_CHECK='TRUE';
      NO_DIR_CHECK='TRUE';
      ALLOW_CONNECT='TRUE';
    'VSS_CA22':
      PIN_NUMBER='(0,0,0,0,0,0,0,0,0,0,0,0,0,0,0,0,0,0,0,0,0,0,0,0,0,0,0,0,0,0,0~
,0,0,0,0,0,CA22,0,0,0)';
      PINUSE='POWER';
      NO_LOAD_CHECK='Both';
      NO_IO_CHECK='Both';
      NO_ASSERT_CHECK='TRUE';
      NO_DIR_CHECK='TRUE';
      ALLOW_CONNECT='TRUE';
    'VSS_CA25':
      PIN_NUMBER='(0,0,0,0,0,0,0,0,0,0,0,0,0,0,0,0,0,0,0,0,0,0,0,0,0,0,0,0,0,0,0~
,0,0,0,0,0,CA25,0,0,0)';
      PINUSE='POWER';
      NO_LOAD_CHECK='Both';
      NO_IO_CHECK='Both';
      NO_ASSERT_CHECK='TRUE';
      NO_DIR_CHECK='TRUE';
      ALLOW_CONNECT='TRUE';
    'VSS_CA28':
      PIN_NUMBER='(0,0,0,0,0,0,0,0,0,0,0,0,0,0,0,0,0,0,0,0,0,0,0,0,0,0,0,0,0,0,0~
,0,0,0,0,0,CA28,0,0,0)';
      PINUSE='POWER';
      NO_LOAD_CHECK='Both';
      NO_IO_CHECK='Both';
      NO_ASSERT_CHECK='TRUE';
      NO_DIR_CHECK='TRUE';
      ALLOW_CONNECT='TRUE';
    'VSS_CA31':
      PIN_NUMBER='(0,0,0,0,0,0,0,0,0,0,0,0,0,0,0,0,0,0,0,0,0,0,0,0,0,0,0,0,0,0,0~
,0,0,0,0,0,CA31,0,0,0)';
      PINUSE='POWER';
      NO_LOAD_CHECK='Both';
      NO_IO_CHECK='Both';
      NO_ASSERT_CHECK='TRUE';
      NO_DIR_CHECK='TRUE';
      ALLOW_CONNECT='TRUE';
    'VSS_CA34':
      PIN_NUMBER='(0,0,0,0,0,0,0,0,0,0,0,0,0,0,0,0,0,0,0,0,0,0,0,0,0,0,0,0,0,0,0~
,0,0,0,0,0,CA34,0,0,0)';
      PINUSE='POWER';
      NO_LOAD_CHECK='Both';
      NO_IO_CHECK='Both';
      NO_ASSERT_CHECK='TRUE';
      NO_DIR_CHECK='TRUE';
      ALLOW_CONNECT='TRUE';
    'VSS_CA35':
      PIN_NUMBER='(0,0,0,0,0,0,0,0,0,0,0,0,0,0,0,0,0,0,0,0,0,0,0,0,0,0,0,0,0,0,0~
,0,0,0,0,0,CA35,0,0,0)';
      PINUSE='POWER';
      NO_LOAD_CHECK='Both';
      NO_IO_CHECK='Both';
      NO_ASSERT_CHECK='TRUE';
      NO_DIR_CHECK='TRUE';
      ALLOW_CONNECT='TRUE';
    'VSS_CA36':
      PIN_NUMBER='(0,0,0,0,0,0,0,0,0,0,0,0,0,0,0,0,0,0,0,0,0,0,0,0,0,0,0,0,0,0,0~
,0,0,0,0,0,CA36,0,0,0)';
      PINUSE='POWER';
      NO_LOAD_CHECK='Both';
      NO_IO_CHECK='Both';
      NO_ASSERT_CHECK='TRUE';
      NO_DIR_CHECK='TRUE';
      ALLOW_CONNECT='TRUE';
    'VSS_CA40':
      PIN_NUMBER='(0,0,0,0,0,0,0,0,0,0,0,0,0,0,0,0,0,0,0,0,0,0,0,0,0,0,0,0,0,0,0~
,0,0,0,0,0,CA40,0,0,0)';
      PINUSE='POWER';
      NO_LOAD_CHECK='Both';
      NO_IO_CHECK='Both';
      NO_ASSERT_CHECK='TRUE';
      NO_DIR_CHECK='TRUE';
      ALLOW_CONNECT='TRUE';
    'VSS_CA41':
      PIN_NUMBER='(0,0,0,0,0,0,0,0,0,0,0,0,0,0,0,0,0,0,0,0,0,0,0,0,0,0,0,0,0,0,0~
,0,0,0,0,0,CA41,0,0,0)';
      PINUSE='POWER';
      NO_LOAD_CHECK='Both';
      NO_IO_CHECK='Both';
      NO_ASSERT_CHECK='TRUE';
      NO_DIR_CHECK='TRUE';
      ALLOW_CONNECT='TRUE';
    'VSS_CA42':
      PIN_NUMBER='(0,0,0,0,0,0,0,0,0,0,0,0,0,0,0,0,0,0,0,0,0,0,0,0,0,0,0,0,0,0,0~
,0,0,0,0,0,CA42,0,0,0)';
      PINUSE='POWER';
      NO_LOAD_CHECK='Both';
      NO_IO_CHECK='Both';
      NO_ASSERT_CHECK='TRUE';
      NO_DIR_CHECK='TRUE';
      ALLOW_CONNECT='TRUE';
    'VSS_CA45':
      PIN_NUMBER='(0,0,0,0,0,0,0,0,0,0,0,0,0,0,0,0,0,0,0,0,0,0,0,0,0,0,0,0,0,0,0~
,0,0,0,0,0,CA45,0,0,0)';
      PINUSE='POWER';
      NO_LOAD_CHECK='Both';
      NO_IO_CHECK='Both';
      NO_ASSERT_CHECK='TRUE';
      NO_DIR_CHECK='TRUE';
      ALLOW_CONNECT='TRUE';
    'VSS_CA48':
      PIN_NUMBER='(0,0,0,0,0,0,0,0,0,0,0,0,0,0,0,0,0,0,0,0,0,0,0,0,0,0,0,0,0,0,0~
,0,0,0,0,0,CA48,0,0,0)';
      PINUSE='POWER';
      NO_LOAD_CHECK='Both';
      NO_IO_CHECK='Both';
      NO_ASSERT_CHECK='TRUE';
      NO_DIR_CHECK='TRUE';
      ALLOW_CONNECT='TRUE';
    'VSS_CA51':
      PIN_NUMBER='(0,0,0,0,0,0,0,0,0,0,0,0,0,0,0,0,0,0,0,0,0,0,0,0,0,0,0,0,0,0,0~
,0,0,0,0,0,CA51,0,0,0)';
      PINUSE='POWER';
      NO_LOAD_CHECK='Both';
      NO_IO_CHECK='Both';
      NO_ASSERT_CHECK='TRUE';
      NO_DIR_CHECK='TRUE';
      ALLOW_CONNECT='TRUE';
    'VSS_CA54':
      PIN_NUMBER='(0,0,0,0,0,0,0,0,0,0,0,0,0,0,0,0,0,0,0,0,0,0,0,0,0,0,0,0,0,0,0~
,0,0,0,0,0,CA54,0,0,0)';
      PINUSE='POWER';
      NO_LOAD_CHECK='Both';
      NO_IO_CHECK='Both';
      NO_ASSERT_CHECK='TRUE';
      NO_DIR_CHECK='TRUE';
      ALLOW_CONNECT='TRUE';
    'VSS_CA56':
      PIN_NUMBER='(0,0,0,0,0,0,0,0,0,0,0,0,0,0,0,0,0,0,0,0,0,0,0,0,0,0,0,0,0,0,0~
,0,0,0,0,0,CA56,0,0,0)';
      PINUSE='POWER';
      NO_LOAD_CHECK='Both';
      NO_IO_CHECK='Both';
      NO_ASSERT_CHECK='TRUE';
      NO_DIR_CHECK='TRUE';
      ALLOW_CONNECT='TRUE';
    'VSS_CA61':
      PIN_NUMBER='(0,0,0,0,0,0,0,0,0,0,0,0,0,0,0,0,0,0,0,0,0,0,0,0,0,0,0,0,0,0,0~
,0,0,0,0,0,CA61,0,0,0)';
      PINUSE='POWER';
      NO_LOAD_CHECK='Both';
      NO_IO_CHECK='Both';
      NO_ASSERT_CHECK='TRUE';
      NO_DIR_CHECK='TRUE';
      ALLOW_CONNECT='TRUE';
    'VSS_CA63':
      PIN_NUMBER='(0,0,0,0,0,0,0,0,0,0,0,0,0,0,0,0,0,0,0,0,0,0,0,0,0,0,0,0,0,0,0~
,0,0,0,0,0,CA63,0,0,0)';
      PINUSE='POWER';
      NO_LOAD_CHECK='Both';
      NO_IO_CHECK='Both';
      NO_ASSERT_CHECK='TRUE';
      NO_DIR_CHECK='TRUE';
      ALLOW_CONNECT='TRUE';
    'VSS_CA68':
      PIN_NUMBER='(0,0,0,0,0,0,0,0,0,0,0,0,0,0,0,0,0,0,0,0,0,0,0,0,0,0,0,0,0,0,0~
,0,0,0,0,0,CA68,0,0,0)';
      PINUSE='POWER';
      NO_LOAD_CHECK='Both';
      NO_IO_CHECK='Both';
      NO_ASSERT_CHECK='TRUE';
      NO_DIR_CHECK='TRUE';
      ALLOW_CONNECT='TRUE';
    'VSS_CA70':
      PIN_NUMBER='(0,0,0,0,0,0,0,0,0,0,0,0,0,0,0,0,0,0,0,0,0,0,0,0,0,0,0,0,0,0,0~
,0,0,0,0,0,CA70,0,0,0)';
      PINUSE='POWER';
      NO_LOAD_CHECK='Both';
      NO_IO_CHECK='Both';
      NO_ASSERT_CHECK='TRUE';
      NO_DIR_CHECK='TRUE';
      ALLOW_CONNECT='TRUE';
    'VSS_CA75':
      PIN_NUMBER='(0,0,0,0,0,0,0,0,0,0,0,0,0,0,0,0,0,0,0,0,0,0,0,0,0,0,0,0,0,0,0~
,0,0,0,0,0,CA75,0,0,0)';
      PINUSE='POWER';
      NO_LOAD_CHECK='Both';
      NO_IO_CHECK='Both';
      NO_ASSERT_CHECK='TRUE';
      NO_DIR_CHECK='TRUE';
      ALLOW_CONNECT='TRUE';
    'VSS_CB3':
      PIN_NUMBER='(0,0,0,0,0,0,0,0,0,0,0,0,0,0,0,0,0,0,0,0,0,0,0,0,0,0,0,0,0,0,0~
,0,0,0,0,0,CB3,0,0,0)';
      PINUSE='POWER';
      NO_LOAD_CHECK='Both';
      NO_IO_CHECK='Both';
      NO_ASSERT_CHECK='TRUE';
      NO_DIR_CHECK='TRUE';
      ALLOW_CONNECT='TRUE';
    'VSS_CB5':
      PIN_NUMBER='(0,0,0,0,0,0,0,0,0,0,0,0,0,0,0,0,0,0,0,0,0,0,0,0,0,0,0,0,0,0,0~
,0,0,0,0,0,CB5,0,0,0)';
      PINUSE='POWER';
      NO_LOAD_CHECK='Both';
      NO_IO_CHECK='Both';
      NO_ASSERT_CHECK='TRUE';
      NO_DIR_CHECK='TRUE';
      ALLOW_CONNECT='TRUE';
    'VSS_CB8':
      PIN_NUMBER='(0,0,0,0,0,0,0,0,0,0,0,0,0,0,0,0,0,0,0,0,0,0,0,0,0,0,0,0,0,0,0~
,0,0,0,0,0,CB8,0,0,0)';
      PINUSE='POWER';
      NO_LOAD_CHECK='Both';
      NO_IO_CHECK='Both';
      NO_ASSERT_CHECK='TRUE';
      NO_DIR_CHECK='TRUE';
      ALLOW_CONNECT='TRUE';
    'VSS_CB10':
      PIN_NUMBER='(0,0,0,0,0,0,0,0,0,0,0,0,0,0,0,0,0,0,0,0,0,0,0,0,0,0,0,0,0,0,0~
,0,0,0,0,0,CB10,0,0,0)';
      PINUSE='POWER';
      NO_LOAD_CHECK='Both';
      NO_IO_CHECK='Both';
      NO_ASSERT_CHECK='TRUE';
      NO_DIR_CHECK='TRUE';
      ALLOW_CONNECT='TRUE';
    'VSS_CB12':
      PIN_NUMBER='(0,0,0,0,0,0,0,0,0,0,0,0,0,0,0,0,0,0,0,0,0,0,0,0,0,0,0,0,0,0,0~
,0,0,0,0,0,CB12,0,0,0)';
      PINUSE='POWER';
      NO_LOAD_CHECK='Both';
      NO_IO_CHECK='Both';
      NO_ASSERT_CHECK='TRUE';
      NO_DIR_CHECK='TRUE';
      ALLOW_CONNECT='TRUE';
    'VSS_CB15':
      PIN_NUMBER='(0,0,0,0,0,0,0,0,0,0,0,0,0,0,0,0,0,0,0,0,0,0,0,0,0,0,0,0,0,0,0~
,0,0,0,0,0,CB15,0,0,0)';
      PINUSE='POWER';
      NO_LOAD_CHECK='Both';
      NO_IO_CHECK='Both';
      NO_ASSERT_CHECK='TRUE';
      NO_DIR_CHECK='TRUE';
      ALLOW_CONNECT='TRUE';
    'VSS_CB17':
      PIN_NUMBER='(0,0,0,0,0,0,0,0,0,0,0,0,0,0,0,0,0,0,0,0,0,0,0,0,0,0,0,0,0,0,0~
,0,0,0,0,0,CB17,0,0,0)';
      PINUSE='POWER';
      NO_LOAD_CHECK='Both';
      NO_IO_CHECK='Both';
      NO_ASSERT_CHECK='TRUE';
      NO_DIR_CHECK='TRUE';
      ALLOW_CONNECT='TRUE';
    'VSS_CB19':
      PIN_NUMBER='(0,0,0,0,0,0,0,0,0,0,0,0,0,0,0,0,0,0,0,0,0,0,0,0,0,0,0,0,0,0,0~
,0,0,0,0,0,CB19,0,0,0)';
      PINUSE='POWER';
      NO_LOAD_CHECK='Both';
      NO_IO_CHECK='Both';
      NO_ASSERT_CHECK='TRUE';
      NO_DIR_CHECK='TRUE';
      ALLOW_CONNECT='TRUE';
    'VSS_CB23':
      PIN_NUMBER='(0,0,0,0,0,0,0,0,0,0,0,0,0,0,0,0,0,0,0,0,0,0,0,0,0,0,0,0,0,0,0~
,0,0,0,0,0,CB23,0,0,0)';
      PINUSE='POWER';
      NO_LOAD_CHECK='Both';
      NO_IO_CHECK='Both';
      NO_ASSERT_CHECK='TRUE';
      NO_DIR_CHECK='TRUE';
      ALLOW_CONNECT='TRUE';
    'VSS_CB24':
      PIN_NUMBER='(0,0,0,0,0,0,0,0,0,0,0,0,0,0,0,0,0,0,0,0,0,0,0,0,0,0,0,0,0,0,0~
,0,0,0,0,0,CB24,0,0,0)';
      PINUSE='POWER';
      NO_LOAD_CHECK='Both';
      NO_IO_CHECK='Both';
      NO_ASSERT_CHECK='TRUE';
      NO_DIR_CHECK='TRUE';
      ALLOW_CONNECT='TRUE';
    'VSS_CB25':
      PIN_NUMBER='(0,0,0,0,0,0,0,0,0,0,0,0,0,0,0,0,0,0,0,0,0,0,0,0,0,0,0,0,0,0,0~
,0,0,0,0,0,CB25,0,0,0)';
      PINUSE='POWER';
      NO_LOAD_CHECK='Both';
      NO_IO_CHECK='Both';
      NO_ASSERT_CHECK='TRUE';
      NO_DIR_CHECK='TRUE';
      ALLOW_CONNECT='TRUE';
    'VSS_CB26':
      PIN_NUMBER='(0,0,0,0,0,0,0,0,0,0,0,0,0,0,0,0,0,0,0,0,0,0,0,0,0,0,0,0,0,0,0~
,0,0,0,0,0,CB26,0,0,0)';
      PINUSE='POWER';
      NO_LOAD_CHECK='Both';
      NO_IO_CHECK='Both';
      NO_ASSERT_CHECK='TRUE';
      NO_DIR_CHECK='TRUE';
      ALLOW_CONNECT='TRUE';
    'VSS_CB27':
      PIN_NUMBER='(0,0,0,0,0,0,0,0,0,0,0,0,0,0,0,0,0,0,0,0,0,0,0,0,0,0,0,0,0,0,0~
,0,0,0,0,0,CB27,0,0,0)';
      PINUSE='POWER';
      NO_LOAD_CHECK='Both';
      NO_IO_CHECK='Both';
      NO_ASSERT_CHECK='TRUE';
      NO_DIR_CHECK='TRUE';
      ALLOW_CONNECT='TRUE';
    'VSS_CB28':
      PIN_NUMBER='(0,0,0,0,0,0,0,0,0,0,0,0,0,0,0,0,0,0,0,0,0,0,0,0,0,0,0,0,0,0,0~
,0,0,0,0,0,CB28,0,0,0)';
      PINUSE='POWER';
      NO_LOAD_CHECK='Both';
      NO_IO_CHECK='Both';
      NO_ASSERT_CHECK='TRUE';
      NO_DIR_CHECK='TRUE';
      ALLOW_CONNECT='TRUE';
    'VSS_CB29':
      PIN_NUMBER='(0,0,0,0,0,0,0,0,0,0,0,0,0,0,0,0,0,0,0,0,0,0,0,0,0,0,0,0,0,0,0~
,0,0,0,0,0,CB29,0,0,0)';
      PINUSE='POWER';
      NO_LOAD_CHECK='Both';
      NO_IO_CHECK='Both';
      NO_ASSERT_CHECK='TRUE';
      NO_DIR_CHECK='TRUE';
      ALLOW_CONNECT='TRUE';
    'VSS_CB30':
      PIN_NUMBER='(0,0,0,0,0,0,0,0,0,0,0,0,0,0,0,0,0,0,0,0,0,0,0,0,0,0,0,0,0,0,0~
,0,0,0,0,0,CB30,0,0,0)';
      PINUSE='POWER';
      NO_LOAD_CHECK='Both';
      NO_IO_CHECK='Both';
      NO_ASSERT_CHECK='TRUE';
      NO_DIR_CHECK='TRUE';
      ALLOW_CONNECT='TRUE';
    'VSS_CB31':
      PIN_NUMBER='(0,0,0,0,0,0,0,0,0,0,0,0,0,0,0,0,0,0,0,0,0,0,0,0,0,0,0,0,0,0,0~
,0,0,0,0,0,CB31,0,0,0)';
      PINUSE='POWER';
      NO_LOAD_CHECK='Both';
      NO_IO_CHECK='Both';
      NO_ASSERT_CHECK='TRUE';
      NO_DIR_CHECK='TRUE';
      ALLOW_CONNECT='TRUE';
    'VSS_CB32':
      PIN_NUMBER='(0,0,0,0,0,0,0,0,0,0,0,0,0,0,0,0,0,0,0,0,0,0,0,0,0,0,0,0,0,0,0~
,0,0,0,0,0,CB32,0,0,0)';
      PINUSE='POWER';
      NO_LOAD_CHECK='Both';
      NO_IO_CHECK='Both';
      NO_ASSERT_CHECK='TRUE';
      NO_DIR_CHECK='TRUE';
      ALLOW_CONNECT='TRUE';
    'VSS_CB33':
      PIN_NUMBER='(0,0,0,0,0,0,0,0,0,0,0,0,0,0,0,0,0,0,0,0,0,0,0,0,0,0,0,0,0,0,0~
,0,0,0,0,0,CB33,0,0,0)';
      PINUSE='POWER';
      NO_LOAD_CHECK='Both';
      NO_IO_CHECK='Both';
      NO_ASSERT_CHECK='TRUE';
      NO_DIR_CHECK='TRUE';
      ALLOW_CONNECT='TRUE';
    'VSS_CB34':
      PIN_NUMBER='(0,0,0,0,0,0,0,0,0,0,0,0,0,0,0,0,0,0,0,0,0,0,0,0,0,0,0,0,0,0,0~
,0,0,0,0,0,CB34,0,0,0)';
      PINUSE='POWER';
      NO_LOAD_CHECK='Both';
      NO_IO_CHECK='Both';
      NO_ASSERT_CHECK='TRUE';
      NO_DIR_CHECK='TRUE';
      ALLOW_CONNECT='TRUE';
    'VSS_CB37':
      PIN_NUMBER='(0,0,0,0,0,0,0,0,0,0,0,0,0,0,0,0,0,0,0,0,0,0,0,0,0,0,0,0,0,0,0~
,0,0,0,0,0,CB37,0,0,0)';
      PINUSE='POWER';
      NO_LOAD_CHECK='Both';
      NO_IO_CHECK='Both';
      NO_ASSERT_CHECK='TRUE';
      NO_DIR_CHECK='TRUE';
      ALLOW_CONNECT='TRUE';
    'VSS_CB39':
      PIN_NUMBER='(0,0,0,0,0,0,0,0,0,0,0,0,0,0,0,0,0,0,0,0,0,0,0,0,0,0,0,0,0,0,0~
,0,0,0,0,0,CB39,0,0,0)';
      PINUSE='POWER';
      NO_LOAD_CHECK='Both';
      NO_IO_CHECK='Both';
      NO_ASSERT_CHECK='TRUE';
      NO_DIR_CHECK='TRUE';
      ALLOW_CONNECT='TRUE';
    'VSS_CB42':
      PIN_NUMBER='(0,0,0,0,0,0,0,0,0,0,0,0,0,0,0,0,0,0,0,0,0,0,0,0,0,0,0,0,0,0,0~
,0,0,0,0,0,CB42,0,0,0)';
      PINUSE='POWER';
      NO_LOAD_CHECK='Both';
      NO_IO_CHECK='Both';
      NO_ASSERT_CHECK='TRUE';
      NO_DIR_CHECK='TRUE';
      ALLOW_CONNECT='TRUE';
    'VSS_CB43':
      PIN_NUMBER='(0,0,0,0,0,0,0,0,0,0,0,0,0,0,0,0,0,0,0,0,0,0,0,0,0,0,0,0,0,0,0~
,0,0,0,0,0,CB43,0,0,0)';
      PINUSE='POWER';
      NO_LOAD_CHECK='Both';
      NO_IO_CHECK='Both';
      NO_ASSERT_CHECK='TRUE';
      NO_DIR_CHECK='TRUE';
      ALLOW_CONNECT='TRUE';
    'VSS_CB45':
      PIN_NUMBER='(0,0,0,0,0,0,0,0,0,0,0,0,0,0,0,0,0,0,0,0,0,0,0,0,0,0,0,0,0,0,0~
,0,0,0,0,0,CB45,0,0,0)';
      PINUSE='POWER';
      NO_LOAD_CHECK='Both';
      NO_IO_CHECK='Both';
      NO_ASSERT_CHECK='TRUE';
      NO_DIR_CHECK='TRUE';
      ALLOW_CONNECT='TRUE';
    'VSS_CB46':
      PIN_NUMBER='(0,0,0,0,0,0,0,0,0,0,0,0,0,0,0,0,0,0,0,0,0,0,0,0,0,0,0,0,0,0,0~
,0,0,0,0,0,CB46,0,0,0)';
      PINUSE='POWER';
      NO_LOAD_CHECK='Both';
      NO_IO_CHECK='Both';
      NO_ASSERT_CHECK='TRUE';
      NO_DIR_CHECK='TRUE';
      ALLOW_CONNECT='TRUE';
    'VSS_CB47':
      PIN_NUMBER='(0,0,0,0,0,0,0,0,0,0,0,0,0,0,0,0,0,0,0,0,0,0,0,0,0,0,0,0,0,0,0~
,0,0,0,0,0,CB47,0,0,0)';
      PINUSE='POWER';
      NO_LOAD_CHECK='Both';
      NO_IO_CHECK='Both';
      NO_ASSERT_CHECK='TRUE';
      NO_DIR_CHECK='TRUE';
      ALLOW_CONNECT='TRUE';
    'VSS_CB48':
      PIN_NUMBER='(0,0,0,0,0,0,0,0,0,0,0,0,0,0,0,0,0,0,0,0,0,0,0,0,0,0,0,0,0,0,0~
,0,0,0,0,0,CB48,0,0,0)';
      PINUSE='POWER';
      NO_LOAD_CHECK='Both';
      NO_IO_CHECK='Both';
      NO_ASSERT_CHECK='TRUE';
      NO_DIR_CHECK='TRUE';
      ALLOW_CONNECT='TRUE';
    'VSS_CB49':
      PIN_NUMBER='(0,0,0,0,0,0,0,0,0,0,0,0,0,0,0,0,0,0,0,0,0,0,0,0,0,0,0,0,0,0,0~
,0,0,0,0,0,CB49,0,0,0)';
      PINUSE='POWER';
      NO_LOAD_CHECK='Both';
      NO_IO_CHECK='Both';
      NO_ASSERT_CHECK='TRUE';
      NO_DIR_CHECK='TRUE';
      ALLOW_CONNECT='TRUE';
    'VSS_CB50':
      PIN_NUMBER='(0,0,0,0,0,0,0,0,0,0,0,0,0,0,0,0,0,0,0,0,0,0,0,0,0,0,0,0,0,0,0~
,0,0,0,0,0,CB50,0,0,0)';
      PINUSE='POWER';
      NO_LOAD_CHECK='Both';
      NO_IO_CHECK='Both';
      NO_ASSERT_CHECK='TRUE';
      NO_DIR_CHECK='TRUE';
      ALLOW_CONNECT='TRUE';
    'VSS_CB51':
      PIN_NUMBER='(0,0,0,0,0,0,0,0,0,0,0,0,0,0,0,0,0,0,0,0,0,0,0,0,0,0,0,0,0,0,0~
,0,0,0,0,0,CB51,0,0,0)';
      PINUSE='POWER';
      NO_LOAD_CHECK='Both';
      NO_IO_CHECK='Both';
      NO_ASSERT_CHECK='TRUE';
      NO_DIR_CHECK='TRUE';
      ALLOW_CONNECT='TRUE';
    'VSS_CB52':
      PIN_NUMBER='(0,0,0,0,0,0,0,0,0,0,0,0,0,0,0,0,0,0,0,0,0,0,0,0,0,0,0,0,0,0,0~
,0,0,0,0,0,CB52,0,0,0)';
      PINUSE='POWER';
      NO_LOAD_CHECK='Both';
      NO_IO_CHECK='Both';
      NO_ASSERT_CHECK='TRUE';
      NO_DIR_CHECK='TRUE';
      ALLOW_CONNECT='TRUE';
    'VSS_CB53':
      PIN_NUMBER='(0,0,0,0,0,0,0,0,0,0,0,0,0,0,0,0,0,0,0,0,0,0,0,0,0,0,0,0,0,0,0~
,0,0,0,0,0,CB53,0,0,0)';
      PINUSE='POWER';
      NO_LOAD_CHECK='Both';
      NO_IO_CHECK='Both';
      NO_ASSERT_CHECK='TRUE';
      NO_DIR_CHECK='TRUE';
      ALLOW_CONNECT='TRUE';
    'VSS_CB57':
      PIN_NUMBER='(0,0,0,0,0,0,0,0,0,0,0,0,0,0,0,0,0,0,0,0,0,0,0,0,0,0,0,0,0,0,0~
,0,0,0,0,0,CB57,0,0,0)';
      PINUSE='POWER';
      NO_LOAD_CHECK='Both';
      NO_IO_CHECK='Both';
      NO_ASSERT_CHECK='TRUE';
      NO_DIR_CHECK='TRUE';
      ALLOW_CONNECT='TRUE';
    'VSS_CB59':
      PIN_NUMBER='(0,0,0,0,0,0,0,0,0,0,0,0,0,0,0,0,0,0,0,0,0,0,0,0,0,0,0,0,0,0,0~
,0,0,0,0,0,CB59,0,0,0)';
      PINUSE='POWER';
      NO_LOAD_CHECK='Both';
      NO_IO_CHECK='Both';
      NO_ASSERT_CHECK='TRUE';
      NO_DIR_CHECK='TRUE';
      ALLOW_CONNECT='TRUE';
    'VSS_CB61':
      PIN_NUMBER='(0,0,0,0,0,0,0,0,0,0,0,0,0,0,0,0,0,0,0,0,0,0,0,0,0,0,0,0,0,0,0~
,0,0,0,0,0,CB61,0,0,0)';
      PINUSE='POWER';
      NO_LOAD_CHECK='Both';
      NO_IO_CHECK='Both';
      NO_ASSERT_CHECK='TRUE';
      NO_DIR_CHECK='TRUE';
      ALLOW_CONNECT='TRUE';
    'VSS_CB64':
      PIN_NUMBER='(0,0,0,0,0,0,0,0,0,0,0,0,0,0,0,0,0,0,0,0,0,0,0,0,0,0,0,0,0,0,0~
,0,0,0,0,0,CB64,0,0,0)';
      PINUSE='POWER';
      NO_LOAD_CHECK='Both';
      NO_IO_CHECK='Both';
      NO_ASSERT_CHECK='TRUE';
      NO_DIR_CHECK='TRUE';
      ALLOW_CONNECT='TRUE';
    'VSS_CB66':
      PIN_NUMBER='(0,0,0,0,0,0,0,0,0,0,0,0,0,0,0,0,0,0,0,0,0,0,0,0,0,0,0,0,0,0,0~
,0,0,0,0,0,CB66,0,0,0)';
      PINUSE='POWER';
      NO_LOAD_CHECK='Both';
      NO_IO_CHECK='Both';
      NO_ASSERT_CHECK='TRUE';
      NO_DIR_CHECK='TRUE';
      ALLOW_CONNECT='TRUE';
    'VSS_CB68':
      PIN_NUMBER='(0,0,0,0,0,0,0,0,0,0,0,0,0,0,0,0,0,0,0,0,0,0,0,0,0,0,0,0,0,0,0~
,0,0,0,0,0,CB68,0,0,0)';
      PINUSE='POWER';
      NO_LOAD_CHECK='Both';
      NO_IO_CHECK='Both';
      NO_ASSERT_CHECK='TRUE';
      NO_DIR_CHECK='TRUE';
      ALLOW_CONNECT='TRUE';
    'VSS_CB71':
      PIN_NUMBER='(0,0,0,0,0,0,0,0,0,0,0,0,0,0,0,0,0,0,0,0,0,0,0,0,0,0,0,0,0,0,0~
,0,0,0,0,0,CB71,0,0,0)';
      PINUSE='POWER';
      NO_LOAD_CHECK='Both';
      NO_IO_CHECK='Both';
      NO_ASSERT_CHECK='TRUE';
      NO_DIR_CHECK='TRUE';
      ALLOW_CONNECT='TRUE';
    'VSS_CB73':
      PIN_NUMBER='(0,0,0,0,0,0,0,0,0,0,0,0,0,0,0,0,0,0,0,0,0,0,0,0,0,0,0,0,0,0,0~
,0,0,0,0,0,CB73,0,0,0)';
      PINUSE='POWER';
      NO_LOAD_CHECK='Both';
      NO_IO_CHECK='Both';
      NO_ASSERT_CHECK='TRUE';
      NO_DIR_CHECK='TRUE';
      ALLOW_CONNECT='TRUE';
    'VSS_CC1':
      PIN_NUMBER='(0,0,0,0,0,0,0,0,0,0,0,0,0,0,0,0,0,0,0,0,0,0,0,0,0,0,0,0,0,0,0~
,0,0,0,0,0,CC1,0,0,0)';
      PINUSE='POWER';
      NO_LOAD_CHECK='Both';
      NO_IO_CHECK='Both';
      NO_ASSERT_CHECK='TRUE';
      NO_DIR_CHECK='TRUE';
      ALLOW_CONNECT='TRUE';
    'VSS_CC4':
      PIN_NUMBER='(0,0,0,0,0,0,0,0,0,0,0,0,0,0,0,0,0,0,0,0,0,0,0,0,0,0,0,0,0,0,0~
,0,0,0,0,0,CC4,0,0,0)';
      PINUSE='POWER';
      NO_LOAD_CHECK='Both';
      NO_IO_CHECK='Both';
      NO_ASSERT_CHECK='TRUE';
      NO_DIR_CHECK='TRUE';
      ALLOW_CONNECT='TRUE';
    'VSS_CC6':
      PIN_NUMBER='(0,0,0,0,0,0,0,0,0,0,0,0,0,0,0,0,0,0,0,0,0,0,0,0,0,0,0,0,0,0,0~
,0,0,0,0,0,CC6,0,0,0)';
      PINUSE='POWER';
      NO_LOAD_CHECK='Both';
      NO_IO_CHECK='Both';
      NO_ASSERT_CHECK='TRUE';
      NO_DIR_CHECK='TRUE';
      ALLOW_CONNECT='TRUE';
    'VSS_CC8':
      PIN_NUMBER='(0,0,0,0,0,0,0,0,0,0,0,0,0,0,0,0,0,0,0,0,0,0,0,0,0,0,0,0,0,0,0~
,0,0,0,0,0,CC8,0,0,0)';
      PINUSE='POWER';
      NO_LOAD_CHECK='Both';
      NO_IO_CHECK='Both';
      NO_ASSERT_CHECK='TRUE';
      NO_DIR_CHECK='TRUE';
      ALLOW_CONNECT='TRUE';
    'VSS_CC11':
      PIN_NUMBER='(0,0,0,0,0,0,0,0,0,0,0,0,0,0,0,0,0,0,0,0,0,0,0,0,0,0,0,0,0,0,0~
,0,0,0,0,0,CC11,0,0,0)';
      PINUSE='POWER';
      NO_LOAD_CHECK='Both';
      NO_IO_CHECK='Both';
      NO_ASSERT_CHECK='TRUE';
      NO_DIR_CHECK='TRUE';
      ALLOW_CONNECT='TRUE';
    'VSS_CC13':
      PIN_NUMBER='(0,0,0,0,0,0,0,0,0,0,0,0,0,0,0,0,0,0,0,0,0,0,0,0,0,0,0,0,0,0,0~
,0,0,0,0,0,CC13,0,0,0)';
      PINUSE='POWER';
      NO_LOAD_CHECK='Both';
      NO_IO_CHECK='Both';
      NO_ASSERT_CHECK='TRUE';
      NO_DIR_CHECK='TRUE';
      ALLOW_CONNECT='TRUE';
    'VSS_CC15':
      PIN_NUMBER='(0,0,0,0,0,0,0,0,0,0,0,0,0,0,0,0,0,0,0,0,0,0,0,0,0,0,0,0,0,0,0~
,0,0,0,0,0,CC15,0,0,0)';
      PINUSE='POWER';
      NO_LOAD_CHECK='Both';
      NO_IO_CHECK='Both';
      NO_ASSERT_CHECK='TRUE';
      NO_DIR_CHECK='TRUE';
      ALLOW_CONNECT='TRUE';
    'VSS_CC18':
      PIN_NUMBER='(0,0,0,0,0,0,0,0,0,0,0,0,0,0,0,0,0,0,0,0,0,0,0,0,0,0,0,0,0,0,0~
,0,0,0,0,0,CC18,0,0,0)';
      PINUSE='POWER';
      NO_LOAD_CHECK='Both';
      NO_IO_CHECK='Both';
      NO_ASSERT_CHECK='TRUE';
      NO_DIR_CHECK='TRUE';
      ALLOW_CONNECT='TRUE';
    'VSS_CC20':
      PIN_NUMBER='(0,0,0,0,0,0,0,0,0,0,0,0,0,0,0,0,0,0,0,0,0,0,0,0,0,0,0,0,0,0,0~
,0,0,0,0,0,CC20,0,0,0)';
      PINUSE='POWER';
      NO_LOAD_CHECK='Both';
      NO_IO_CHECK='Both';
      NO_ASSERT_CHECK='TRUE';
      NO_DIR_CHECK='TRUE';
      ALLOW_CONNECT='TRUE';
    'VSS_CC25':
      PIN_NUMBER='(0,0,0,0,0,0,0,0,0,0,0,0,0,0,0,0,0,0,0,0,0,0,0,0,0,0,0,0,0,0,0~
,0,0,0,0,0,CC25,0,0,0)';
      PINUSE='POWER';
      NO_LOAD_CHECK='Both';
      NO_IO_CHECK='Both';
      NO_ASSERT_CHECK='TRUE';
      NO_DIR_CHECK='TRUE';
      ALLOW_CONNECT='TRUE';
    'VSS_CC28':
      PIN_NUMBER='(0,0,0,0,0,0,0,0,0,0,0,0,0,0,0,0,0,0,0,0,0,0,0,0,0,0,0,0,0,0,0~
,0,0,0,0,0,CC28,0,0,0)';
      PINUSE='POWER';
      NO_LOAD_CHECK='Both';
      NO_IO_CHECK='Both';
      NO_ASSERT_CHECK='TRUE';
      NO_DIR_CHECK='TRUE';
      ALLOW_CONNECT='TRUE';
    'VSS_CC31':
      PIN_NUMBER='(0,0,0,0,0,0,0,0,0,0,0,0,0,0,0,0,0,0,0,0,0,0,0,0,0,0,0,0,0,0,0~
,0,0,0,0,0,CC31,0,0,0)';
      PINUSE='POWER';
      NO_LOAD_CHECK='Both';
      NO_IO_CHECK='Both';
      NO_ASSERT_CHECK='TRUE';
      NO_DIR_CHECK='TRUE';
      ALLOW_CONNECT='TRUE';
    'VSS_CC34':
      PIN_NUMBER='(0,0,0,0,0,0,0,0,0,0,0,0,0,0,0,0,0,0,0,0,0,0,0,0,0,0,0,0,0,0,0~
,0,0,0,0,0,CC34,0,0,0)';
      PINUSE='POWER';
      NO_LOAD_CHECK='Both';
      NO_IO_CHECK='Both';
      NO_ASSERT_CHECK='TRUE';
      NO_DIR_CHECK='TRUE';
      ALLOW_CONNECT='TRUE';
    'VSS_CC42':
      PIN_NUMBER='(0,0,0,0,0,0,0,0,0,0,0,0,0,0,0,0,0,0,0,0,0,0,0,0,0,0,0,0,0,0,0~
,0,0,0,0,0,CC42,0,0,0)';
      PINUSE='POWER';
      NO_LOAD_CHECK='Both';
      NO_IO_CHECK='Both';
      NO_ASSERT_CHECK='TRUE';
      NO_DIR_CHECK='TRUE';
      ALLOW_CONNECT='TRUE';
    'VSS_CC45':
      PIN_NUMBER='(0,0,0,0,0,0,0,0,0,0,0,0,0,0,0,0,0,0,0,0,0,0,0,0,0,0,0,0,0,0,0~
,0,0,0,0,0,CC45,0,0,0)';
      PINUSE='POWER';
      NO_LOAD_CHECK='Both';
      NO_IO_CHECK='Both';
      NO_ASSERT_CHECK='TRUE';
      NO_DIR_CHECK='TRUE';
      ALLOW_CONNECT='TRUE';
    'VSS_CC48':
      PIN_NUMBER='(0,0,0,0,0,0,0,0,0,0,0,0,0,0,0,0,0,0,0,0,0,0,0,0,0,0,0,0,0,0,0~
,0,0,0,0,0,CC48,0,0,0)';
      PINUSE='POWER';
      NO_LOAD_CHECK='Both';
      NO_IO_CHECK='Both';
      NO_ASSERT_CHECK='TRUE';
      NO_DIR_CHECK='TRUE';
      ALLOW_CONNECT='TRUE';
    'VSS_CC51':
      PIN_NUMBER='(0,0,0,0,0,0,0,0,0,0,0,0,0,0,0,0,0,0,0,0,0,0,0,0,0,0,0,0,0,0,0~
,0,0,0,0,0,CC51,0,0,0)';
      PINUSE='POWER';
      NO_LOAD_CHECK='Both';
      NO_IO_CHECK='Both';
      NO_ASSERT_CHECK='TRUE';
      NO_DIR_CHECK='TRUE';
      ALLOW_CONNECT='TRUE';
    'VSS_CC54':
      PIN_NUMBER='(0,0,0,0,0,0,0,0,0,0,0,0,0,0,0,0,0,0,0,0,0,0,0,0,0,0,0,0,0,0,0~
,0,0,0,0,0,CC54,0,0,0)';
      PINUSE='POWER';
      NO_LOAD_CHECK='Both';
      NO_IO_CHECK='Both';
      NO_ASSERT_CHECK='TRUE';
      NO_DIR_CHECK='TRUE';
      ALLOW_CONNECT='TRUE';
    'VSS_CC56':
      PIN_NUMBER='(0,0,0,0,0,0,0,0,0,0,0,0,0,0,0,0,0,0,0,0,0,0,0,0,0,0,0,0,0,0,0~
,0,0,0,0,0,CC56,0,0,0)';
      PINUSE='POWER';
      NO_LOAD_CHECK='Both';
      NO_IO_CHECK='Both';
      NO_ASSERT_CHECK='TRUE';
      NO_DIR_CHECK='TRUE';
      ALLOW_CONNECT='TRUE';
    'VSS_CC58':
      PIN_NUMBER='(0,0,0,0,0,0,0,0,0,0,0,0,0,0,0,0,0,0,0,0,0,0,0,0,0,0,0,0,0,0,0~
,0,0,0,0,0,CC58,0,0,0)';
      PINUSE='POWER';
      NO_LOAD_CHECK='Both';
      NO_IO_CHECK='Both';
      NO_ASSERT_CHECK='TRUE';
      NO_DIR_CHECK='TRUE';
      ALLOW_CONNECT='TRUE';
    'VSS_CC61':
      PIN_NUMBER='(0,0,0,0,0,0,0,0,0,0,0,0,0,0,0,0,0,0,0,0,0,0,0,0,0,0,0,0,0,0,0~
,0,0,0,0,0,CC61,0,0,0)';
      PINUSE='POWER';
      NO_LOAD_CHECK='Both';
      NO_IO_CHECK='Both';
      NO_ASSERT_CHECK='TRUE';
      NO_DIR_CHECK='TRUE';
      ALLOW_CONNECT='TRUE';
    'VSS_CC63':
      PIN_NUMBER='(0,0,0,0,0,0,0,0,0,0,0,0,0,0,0,0,0,0,0,0,0,0,0,0,0,0,0,0,0,0,0~
,0,0,0,0,0,CC63,0,0,0)';
      PINUSE='POWER';
      NO_LOAD_CHECK='Both';
      NO_IO_CHECK='Both';
      NO_ASSERT_CHECK='TRUE';
      NO_DIR_CHECK='TRUE';
      ALLOW_CONNECT='TRUE';
    'VSS_CC65':
      PIN_NUMBER='(0,0,0,0,0,0,0,0,0,0,0,0,0,0,0,0,0,0,0,0,0,0,0,0,0,0,0,0,0,0,0~
,0,0,0,0,0,CC65,0,0,0)';
      PINUSE='POWER';
      NO_LOAD_CHECK='Both';
      NO_IO_CHECK='Both';
      NO_ASSERT_CHECK='TRUE';
      NO_DIR_CHECK='TRUE';
      ALLOW_CONNECT='TRUE';
    'VSS_CC68':
      PIN_NUMBER='(0,0,0,0,0,0,0,0,0,0,0,0,0,0,0,0,0,0,0,0,0,0,0,0,0,0,0,0,0,0,0~
,0,0,0,0,0,CC68,0,0,0)';
      PINUSE='POWER';
      NO_LOAD_CHECK='Both';
      NO_IO_CHECK='Both';
      NO_ASSERT_CHECK='TRUE';
      NO_DIR_CHECK='TRUE';
      ALLOW_CONNECT='TRUE';
    'VSS_CC70':
      PIN_NUMBER='(0,0,0,0,0,0,0,0,0,0,0,0,0,0,0,0,0,0,0,0,0,0,0,0,0,0,0,0,0,0,0~
,0,0,0,0,0,CC70,0,0,0)';
      PINUSE='POWER';
      NO_LOAD_CHECK='Both';
      NO_IO_CHECK='Both';
      NO_ASSERT_CHECK='TRUE';
      NO_DIR_CHECK='TRUE';
      ALLOW_CONNECT='TRUE';
    'VSS_CC72':
      PIN_NUMBER='(0,0,0,0,0,0,0,0,0,0,0,0,0,0,0,0,0,0,0,0,0,0,0,0,0,0,0,0,0,0,0~
,0,0,0,0,0,CC72,0,0,0)';
      PINUSE='POWER';
      NO_LOAD_CHECK='Both';
      NO_IO_CHECK='Both';
      NO_ASSERT_CHECK='TRUE';
      NO_DIR_CHECK='TRUE';
      ALLOW_CONNECT='TRUE';
    'VSS_CC75':
      PIN_NUMBER='(0,0,0,0,0,0,0,0,0,0,0,0,0,0,0,0,0,0,0,0,0,0,0,0,0,0,0,0,0,0,0~
,0,0,0,0,0,CC75,0,0,0)';
      PINUSE='POWER';
      NO_LOAD_CHECK='Both';
      NO_IO_CHECK='Both';
      NO_ASSERT_CHECK='TRUE';
      NO_DIR_CHECK='TRUE';
      ALLOW_CONNECT='TRUE';
    'VSS_CD3':
      PIN_NUMBER='(0,0,0,0,0,0,0,0,0,0,0,0,0,0,0,0,0,0,0,0,0,0,0,0,0,0,0,0,0,0,0~
,0,0,0,0,0,CD3,0,0,0)';
      PINUSE='POWER';
      NO_LOAD_CHECK='Both';
      NO_IO_CHECK='Both';
      NO_ASSERT_CHECK='TRUE';
      NO_DIR_CHECK='TRUE';
      ALLOW_CONNECT='TRUE';
    'VSS_CD8':
      PIN_NUMBER='(0,0,0,0,0,0,0,0,0,0,0,0,0,0,0,0,0,0,0,0,0,0,0,0,0,0,0,0,0,0,0~
,0,0,0,0,0,CD8,0,0,0)';
      PINUSE='POWER';
      NO_LOAD_CHECK='Both';
      NO_IO_CHECK='Both';
      NO_ASSERT_CHECK='TRUE';
      NO_DIR_CHECK='TRUE';
      ALLOW_CONNECT='TRUE';
    'VSS_CD10':
      PIN_NUMBER='(0,0,0,0,0,0,0,0,0,0,0,0,0,0,0,0,0,0,0,0,0,0,0,0,0,0,0,0,0,0,0~
,0,0,0,0,0,CD10,0,0,0)';
      PINUSE='POWER';
      NO_LOAD_CHECK='Both';
      NO_IO_CHECK='Both';
      NO_ASSERT_CHECK='TRUE';
      NO_DIR_CHECK='TRUE';
      ALLOW_CONNECT='TRUE';
    'VSS_CD15':
      PIN_NUMBER='(0,0,0,0,0,0,0,0,0,0,0,0,0,0,0,0,0,0,0,0,0,0,0,0,0,0,0,0,0,0,0~
,0,0,0,0,0,CD15,0,0,0)';
      PINUSE='POWER';
      NO_LOAD_CHECK='Both';
      NO_IO_CHECK='Both';
      NO_ASSERT_CHECK='TRUE';
      NO_DIR_CHECK='TRUE';
      ALLOW_CONNECT='TRUE';
    'VSS_CD17':
      PIN_NUMBER='(0,0,0,0,0,0,0,0,0,0,0,0,0,0,0,0,0,0,0,0,0,0,0,0,0,0,0,0,0,0,0~
,0,0,0,0,0,CD17,0,0,0)';
      PINUSE='POWER';
      NO_LOAD_CHECK='Both';
      NO_IO_CHECK='Both';
      NO_ASSERT_CHECK='TRUE';
      NO_DIR_CHECK='TRUE';
      ALLOW_CONNECT='TRUE';
    'VSS_CD22':
      PIN_NUMBER='(0,0,0,0,0,0,0,0,0,0,0,0,0,0,0,0,0,0,0,0,0,0,0,0,0,0,0,0,0,0,0~
,0,0,0,0,0,CD22,0,0,0)';
      PINUSE='POWER';
      NO_LOAD_CHECK='Both';
      NO_IO_CHECK='Both';
      NO_ASSERT_CHECK='TRUE';
      NO_DIR_CHECK='TRUE';
      ALLOW_CONNECT='TRUE';
    'VSS_CD25':
      PIN_NUMBER='(0,0,0,0,0,0,0,0,0,0,0,0,0,0,0,0,0,0,0,0,0,0,0,0,0,0,0,0,0,0,0~
,0,0,0,0,0,CD25,0,0,0)';
      PINUSE='POWER';
      NO_LOAD_CHECK='Both';
      NO_IO_CHECK='Both';
      NO_ASSERT_CHECK='TRUE';
      NO_DIR_CHECK='TRUE';
      ALLOW_CONNECT='TRUE';
    'VSS_CD28':
      PIN_NUMBER='(0,0,0,0,0,0,0,0,0,0,0,0,0,0,0,0,0,0,0,0,0,0,0,0,0,0,0,0,0,0,0~
,0,0,0,0,0,CD28,0,0,0)';
      PINUSE='POWER';
      NO_LOAD_CHECK='Both';
      NO_IO_CHECK='Both';
      NO_ASSERT_CHECK='TRUE';
      NO_DIR_CHECK='TRUE';
      ALLOW_CONNECT='TRUE';
    'VSS_CD31':
      PIN_NUMBER='(0,0,0,0,0,0,0,0,0,0,0,0,0,0,0,0,0,0,0,0,0,0,0,0,0,0,0,0,0,0,0~
,0,0,0,0,0,CD31,0,0,0)';
      PINUSE='POWER';
      NO_LOAD_CHECK='Both';
      NO_IO_CHECK='Both';
      NO_ASSERT_CHECK='TRUE';
      NO_DIR_CHECK='TRUE';
      ALLOW_CONNECT='TRUE';
    'VSS_CD34':
      PIN_NUMBER='(0,0,0,0,0,0,0,0,0,0,0,0,0,0,0,0,0,0,0,0,0,0,0,0,0,0,0,0,0,0,0~
,0,0,0,0,0,CD34,0,0,0)';
      PINUSE='POWER';
      NO_LOAD_CHECK='Both';
      NO_IO_CHECK='Both';
      NO_ASSERT_CHECK='TRUE';
      NO_DIR_CHECK='TRUE';
      ALLOW_CONNECT='TRUE';
    'VSS_CD37':
      PIN_NUMBER='(0,0,0,0,0,0,0,0,0,0,0,0,0,0,0,0,0,0,0,0,0,0,0,0,0,0,0,0,0,0,0~
,0,0,0,0,0,CD37,0,0,0)';
      PINUSE='POWER';
      NO_LOAD_CHECK='Both';
      NO_IO_CHECK='Both';
      NO_ASSERT_CHECK='TRUE';
      NO_DIR_CHECK='TRUE';
      ALLOW_CONNECT='TRUE';
    'VSS_CD39':
      PIN_NUMBER='(0,0,0,0,0,0,0,0,0,0,0,0,0,0,0,0,0,0,0,0,0,0,0,0,0,0,0,0,0,0,0~
,0,0,0,0,0,CD39,0,0,0)';
      PINUSE='POWER';
      NO_LOAD_CHECK='Both';
      NO_IO_CHECK='Both';
      NO_ASSERT_CHECK='TRUE';
      NO_DIR_CHECK='TRUE';
      ALLOW_CONNECT='TRUE';
    'VSS_CD42':
      PIN_NUMBER='(0,0,0,0,0,0,0,0,0,0,0,0,0,0,0,0,0,0,0,0,0,0,0,0,0,0,0,0,0,0,0~
,0,0,0,0,0,CD42,0,0,0)';
      PINUSE='POWER';
      NO_LOAD_CHECK='Both';
      NO_IO_CHECK='Both';
      NO_ASSERT_CHECK='TRUE';
      NO_DIR_CHECK='TRUE';
      ALLOW_CONNECT='TRUE';
    'VSS_CD45':
      PIN_NUMBER='(0,0,0,0,0,0,0,0,0,0,0,0,0,0,0,0,0,0,0,0,0,0,0,0,0,0,0,0,0,0,0~
,0,0,0,0,0,CD45,0,0,0)';
      PINUSE='POWER';
      NO_LOAD_CHECK='Both';
      NO_IO_CHECK='Both';
      NO_ASSERT_CHECK='TRUE';
      NO_DIR_CHECK='TRUE';
      ALLOW_CONNECT='TRUE';
    'VSS_CD48':
      PIN_NUMBER='(0,0,0,0,0,0,0,0,0,0,0,0,0,0,0,0,0,0,0,0,0,0,0,0,0,0,0,0,0,0,0~
,0,0,0,0,0,CD48,0,0,0)';
      PINUSE='POWER';
      NO_LOAD_CHECK='Both';
      NO_IO_CHECK='Both';
      NO_ASSERT_CHECK='TRUE';
      NO_DIR_CHECK='TRUE';
      ALLOW_CONNECT='TRUE';
    'VSS_CD51':
      PIN_NUMBER='(0,0,0,0,0,0,0,0,0,0,0,0,0,0,0,0,0,0,0,0,0,0,0,0,0,0,0,0,0,0,0~
,0,0,0,0,0,CD51,0,0,0)';
      PINUSE='POWER';
      NO_LOAD_CHECK='Both';
      NO_IO_CHECK='Both';
      NO_ASSERT_CHECK='TRUE';
      NO_DIR_CHECK='TRUE';
      ALLOW_CONNECT='TRUE';
    'VSS_CD54':
      PIN_NUMBER='(0,0,0,0,0,0,0,0,0,0,0,0,0,0,0,0,0,0,0,0,0,0,0,0,0,0,0,0,0,0,0~
,0,0,0,0,0,CD54,0,0,0)';
      PINUSE='POWER';
      NO_LOAD_CHECK='Both';
      NO_IO_CHECK='Both';
      NO_ASSERT_CHECK='TRUE';
      NO_DIR_CHECK='TRUE';
      ALLOW_CONNECT='TRUE';
    'VSS_CD59':
      PIN_NUMBER='(0,0,0,0,0,0,0,0,0,0,0,0,0,0,0,0,0,0,0,0,0,0,0,0,0,0,0,0,0,0,0~
,0,0,0,0,0,CD59,0,0,0)';
      PINUSE='POWER';
      NO_LOAD_CHECK='Both';
      NO_IO_CHECK='Both';
      NO_ASSERT_CHECK='TRUE';
      NO_DIR_CHECK='TRUE';
      ALLOW_CONNECT='TRUE';
    'VSS_CD61':
      PIN_NUMBER='(0,0,0,0,0,0,0,0,0,0,0,0,0,0,0,0,0,0,0,0,0,0,0,0,0,0,0,0,0,0,0~
,0,0,0,0,0,CD61,0,0,0)';
      PINUSE='POWER';
      NO_LOAD_CHECK='Both';
      NO_IO_CHECK='Both';
      NO_ASSERT_CHECK='TRUE';
      NO_DIR_CHECK='TRUE';
      ALLOW_CONNECT='TRUE';
    'VSS_CD66':
      PIN_NUMBER='(0,0,0,0,0,0,0,0,0,0,0,0,0,0,0,0,0,0,0,0,0,0,0,0,0,0,0,0,0,0,0~
,0,0,0,0,0,CD66,0,0,0)';
      PINUSE='POWER';
      NO_LOAD_CHECK='Both';
      NO_IO_CHECK='Both';
      NO_ASSERT_CHECK='TRUE';
      NO_DIR_CHECK='TRUE';
      ALLOW_CONNECT='TRUE';
    'VSS_CD68':
      PIN_NUMBER='(0,0,0,0,0,0,0,0,0,0,0,0,0,0,0,0,0,0,0,0,0,0,0,0,0,0,0,0,0,0,0~
,0,0,0,0,0,CD68,0,0,0)';
      PINUSE='POWER';
      NO_LOAD_CHECK='Both';
      NO_IO_CHECK='Both';
      NO_ASSERT_CHECK='TRUE';
      NO_DIR_CHECK='TRUE';
      ALLOW_CONNECT='TRUE';
    'VSS_CD73':
      PIN_NUMBER='(0,0,0,0,0,0,0,0,0,0,0,0,0,0,0,0,0,0,0,0,0,0,0,0,0,0,0,0,0,0,0~
,0,0,0,0,0,CD73,0,0,0)';
      PINUSE='POWER';
      NO_LOAD_CHECK='Both';
      NO_IO_CHECK='Both';
      NO_ASSERT_CHECK='TRUE';
      NO_DIR_CHECK='TRUE';
      ALLOW_CONNECT='TRUE';
    'VSS_CE1':
      PIN_NUMBER='(0,0,0,0,0,0,0,0,0,0,0,0,0,0,0,0,0,0,0,0,0,0,0,0,0,0,0,0,0,0,0~
,0,0,0,0,0,CE1,0,0,0)';
      PINUSE='POWER';
      NO_LOAD_CHECK='Both';
      NO_IO_CHECK='Both';
      NO_ASSERT_CHECK='TRUE';
      NO_DIR_CHECK='TRUE';
      ALLOW_CONNECT='TRUE';
    'VSS_CE4':
      PIN_NUMBER='(0,0,0,0,0,0,0,0,0,0,0,0,0,0,0,0,0,0,0,0,0,0,0,0,0,0,0,0,0,0,0~
,0,0,0,0,0,CE4,0,0,0)';
      PINUSE='POWER';
      NO_LOAD_CHECK='Both';
      NO_IO_CHECK='Both';
      NO_ASSERT_CHECK='TRUE';
      NO_DIR_CHECK='TRUE';
      ALLOW_CONNECT='TRUE';
    'VSS_CE6':
      PIN_NUMBER='(0,0,0,0,0,0,0,0,0,0,0,0,0,0,0,0,0,0,0,0,0,0,0,0,0,0,0,0,0,0,0~
,0,0,0,0,0,CE6,0,0,0)';
      PINUSE='POWER';
      NO_LOAD_CHECK='Both';
      NO_IO_CHECK='Both';
      NO_ASSERT_CHECK='TRUE';
      NO_DIR_CHECK='TRUE';
      ALLOW_CONNECT='TRUE';
    'VSS_CE8':
      PIN_NUMBER='(0,0,0,0,0,0,0,0,0,0,0,0,0,0,0,0,0,0,0,0,0,0,0,0,0,0,0,0,0,0,0~
,0,0,0,0,0,CE8,0,0,0)';
      PINUSE='POWER';
      NO_LOAD_CHECK='Both';
      NO_IO_CHECK='Both';
      NO_ASSERT_CHECK='TRUE';
      NO_DIR_CHECK='TRUE';
      ALLOW_CONNECT='TRUE';
    'VSS_CE11':
      PIN_NUMBER='(0,0,0,0,0,0,0,0,0,0,0,0,0,0,0,0,0,0,0,0,0,0,0,0,0,0,0,0,0,0,0~
,0,0,0,0,0,CE11,0,0,0)';
      PINUSE='POWER';
      NO_LOAD_CHECK='Both';
      NO_IO_CHECK='Both';
      NO_ASSERT_CHECK='TRUE';
      NO_DIR_CHECK='TRUE';
      ALLOW_CONNECT='TRUE';
    'VSS_CE13':
      PIN_NUMBER='(0,0,0,0,0,0,0,0,0,0,0,0,0,0,0,0,0,0,0,0,0,0,0,0,0,0,0,0,0,0,0~
,0,0,0,0,0,CE13,0,0,0)';
      PINUSE='POWER';
      NO_LOAD_CHECK='Both';
      NO_IO_CHECK='Both';
      NO_ASSERT_CHECK='TRUE';
      NO_DIR_CHECK='TRUE';
      ALLOW_CONNECT='TRUE';
    'VSS_CE15':
      PIN_NUMBER='(0,0,0,0,0,0,0,0,0,0,0,0,0,0,0,0,0,0,0,0,0,0,0,0,0,0,0,0,0,0,0~
,0,0,0,0,0,CE15,0,0,0)';
      PINUSE='POWER';
      NO_LOAD_CHECK='Both';
      NO_IO_CHECK='Both';
      NO_ASSERT_CHECK='TRUE';
      NO_DIR_CHECK='TRUE';
      ALLOW_CONNECT='TRUE';
    'VSS_CE18':
      PIN_NUMBER='(0,0,0,0,0,0,0,0,0,0,0,0,0,0,0,0,0,0,0,0,0,0,0,0,0,0,0,0,0,0,0~
,0,0,0,0,0,CE18,0,0,0)';
      PINUSE='POWER';
      NO_LOAD_CHECK='Both';
      NO_IO_CHECK='Both';
      NO_ASSERT_CHECK='TRUE';
      NO_DIR_CHECK='TRUE';
      ALLOW_CONNECT='TRUE';
    'VSS_CE20':
      PIN_NUMBER='(0,0,0,0,0,0,0,0,0,0,0,0,0,0,0,0,0,0,0,0,0,0,0,0,0,0,0,0,0,0,0~
,0,0,0,0,0,CE20,0,0,0)';
      PINUSE='POWER';
      NO_LOAD_CHECK='Both';
      NO_IO_CHECK='Both';
      NO_ASSERT_CHECK='TRUE';
      NO_DIR_CHECK='TRUE';
      ALLOW_CONNECT='TRUE';
    'VSS_CE22':
      PIN_NUMBER='(0,0,0,0,0,0,0,0,0,0,0,0,0,0,0,0,0,0,0,0,0,0,0,0,0,0,0,0,0,0,0~
,0,0,0,0,0,CE22,0,0,0)';
      PINUSE='POWER';
      NO_LOAD_CHECK='Both';
      NO_IO_CHECK='Both';
      NO_ASSERT_CHECK='TRUE';
      NO_DIR_CHECK='TRUE';
      ALLOW_CONNECT='TRUE';
    'VSS_CE25':
      PIN_NUMBER='(0,0,0,0,0,0,0,0,0,0,0,0,0,0,0,0,0,0,0,0,0,0,0,0,0,0,0,0,0,0,0~
,0,0,0,0,0,CE25,0,0,0)';
      PINUSE='POWER';
      NO_LOAD_CHECK='Both';
      NO_IO_CHECK='Both';
      NO_ASSERT_CHECK='TRUE';
      NO_DIR_CHECK='TRUE';
      ALLOW_CONNECT='TRUE';
    'VSS_CE28':
      PIN_NUMBER='(0,0,0,0,0,0,0,0,0,0,0,0,0,0,0,0,0,0,0,0,0,0,0,0,0,0,0,0,0,0,0~
,0,0,0,0,0,CE28,0,0,0)';
      PINUSE='POWER';
      NO_LOAD_CHECK='Both';
      NO_IO_CHECK='Both';
      NO_ASSERT_CHECK='TRUE';
      NO_DIR_CHECK='TRUE';
      ALLOW_CONNECT='TRUE';
    'VSS_CE31':
      PIN_NUMBER='(0,0,0,0,0,0,0,0,0,0,0,0,0,0,0,0,0,0,0,0,0,0,0,0,0,0,0,0,0,0,0~
,0,0,0,0,0,CE31,0,0,0)';
      PINUSE='POWER';
      NO_LOAD_CHECK='Both';
      NO_IO_CHECK='Both';
      NO_ASSERT_CHECK='TRUE';
      NO_DIR_CHECK='TRUE';
      ALLOW_CONNECT='TRUE';
    'VSS_CE34':
      PIN_NUMBER='(0,0,0,0,0,0,0,0,0,0,0,0,0,0,0,0,0,0,0,0,0,0,0,0,0,0,0,0,0,0,0~
,0,0,0,0,0,CE34,0,0,0)';
      PINUSE='POWER';
      NO_LOAD_CHECK='Both';
      NO_IO_CHECK='Both';
      NO_ASSERT_CHECK='TRUE';
      NO_DIR_CHECK='TRUE';
      ALLOW_CONNECT='TRUE';
    'VSS_CE35':
      PIN_NUMBER='(0,0,0,0,0,0,0,0,0,0,0,0,0,0,0,0,0,0,0,0,0,0,0,0,0,0,0,0,0,0,0~
,0,0,0,0,0,CE35,0,0,0)';
      PINUSE='POWER';
      NO_LOAD_CHECK='Both';
      NO_IO_CHECK='Both';
      NO_ASSERT_CHECK='TRUE';
      NO_DIR_CHECK='TRUE';
      ALLOW_CONNECT='TRUE';
    'VSS_CE36':
      PIN_NUMBER='(0,0,0,0,0,0,0,0,0,0,0,0,0,0,0,0,0,0,0,0,0,0,0,0,0,0,0,0,0,0,0~
,0,0,0,0,0,CE36,0,0,0)';
      PINUSE='POWER';
      NO_LOAD_CHECK='Both';
      NO_IO_CHECK='Both';
      NO_ASSERT_CHECK='TRUE';
      NO_DIR_CHECK='TRUE';
      ALLOW_CONNECT='TRUE';
    'VSS_CE40':
      PIN_NUMBER='(0,0,0,0,0,0,0,0,0,0,0,0,0,0,0,0,0,0,0,0,0,0,0,0,0,0,0,0,0,0,0~
,0,0,0,0,0,CE40,0,0,0)';
      PINUSE='POWER';
      NO_LOAD_CHECK='Both';
      NO_IO_CHECK='Both';
      NO_ASSERT_CHECK='TRUE';
      NO_DIR_CHECK='TRUE';
      ALLOW_CONNECT='TRUE';
    'VSS_CE41':
      PIN_NUMBER='(0,0,0,0,0,0,0,0,0,0,0,0,0,0,0,0,0,0,0,0,0,0,0,0,0,0,0,0,0,0,0~
,0,0,0,0,0,CE41,0,0,0)';
      PINUSE='POWER';
      NO_LOAD_CHECK='Both';
      NO_IO_CHECK='Both';
      NO_ASSERT_CHECK='TRUE';
      NO_DIR_CHECK='TRUE';
      ALLOW_CONNECT='TRUE';
    'VSS_CE42':
      PIN_NUMBER='(0,0,0,0,0,0,0,0,0,0,0,0,0,0,0,0,0,0,0,0,0,0,0,0,0,0,0,0,0,0,0~
,0,0,0,0,0,CE42,0,0,0)';
      PINUSE='POWER';
      NO_LOAD_CHECK='Both';
      NO_IO_CHECK='Both';
      NO_ASSERT_CHECK='TRUE';
      NO_DIR_CHECK='TRUE';
      ALLOW_CONNECT='TRUE';
    'VSS_CE45':
      PIN_NUMBER='(0,0,0,0,0,0,0,0,0,0,0,0,0,0,0,0,0,0,0,0,0,0,0,0,0,0,0,0,0,0,0~
,0,0,0,0,0,CE45,0,0,0)';
      PINUSE='POWER';
      NO_LOAD_CHECK='Both';
      NO_IO_CHECK='Both';
      NO_ASSERT_CHECK='TRUE';
      NO_DIR_CHECK='TRUE';
      ALLOW_CONNECT='TRUE';
    'VSS_CE48':
      PIN_NUMBER='(0,0,0,0,0,0,0,0,0,0,0,0,0,0,0,0,0,0,0,0,0,0,0,0,0,0,0,0,0,0,0~
,0,0,0,0,0,CE48,0,0,0)';
      PINUSE='POWER';
      NO_LOAD_CHECK='Both';
      NO_IO_CHECK='Both';
      NO_ASSERT_CHECK='TRUE';
      NO_DIR_CHECK='TRUE';
      ALLOW_CONNECT='TRUE';
    'VSS_CE51':
      PIN_NUMBER='(0,0,0,0,0,0,0,0,0,0,0,0,0,0,0,0,0,0,0,0,0,0,0,0,0,0,0,0,0,0,0~
,0,0,0,0,0,CE51,0,0,0)';
      PINUSE='POWER';
      NO_LOAD_CHECK='Both';
      NO_IO_CHECK='Both';
      NO_ASSERT_CHECK='TRUE';
      NO_DIR_CHECK='TRUE';
      ALLOW_CONNECT='TRUE';
    'VSS_CE54':
      PIN_NUMBER='(0,0,0,0,0,0,0,0,0,0,0,0,0,0,0,0,0,0,0,0,0,0,0,0,0,0,0,0,0,0,0~
,0,0,0,0,0,CE54,0,0,0)';
      PINUSE='POWER';
      NO_LOAD_CHECK='Both';
      NO_IO_CHECK='Both';
      NO_ASSERT_CHECK='TRUE';
      NO_DIR_CHECK='TRUE';
      ALLOW_CONNECT='TRUE';
    'VSS_CE56':
      PIN_NUMBER='(0,0,0,0,0,0,0,0,0,0,0,0,0,0,0,0,0,0,0,0,0,0,0,0,0,0,0,0,0,0,0~
,0,0,0,0,0,CE56,0,0,0)';
      PINUSE='POWER';
      NO_LOAD_CHECK='Both';
      NO_IO_CHECK='Both';
      NO_ASSERT_CHECK='TRUE';
      NO_DIR_CHECK='TRUE';
      ALLOW_CONNECT='TRUE';
    'VSS_CE58':
      PIN_NUMBER='(0,0,0,0,0,0,0,0,0,0,0,0,0,0,0,0,0,0,0,0,0,0,0,0,0,0,0,0,0,0,0~
,0,0,0,0,0,CE58,0,0,0)';
      PINUSE='POWER';
      NO_LOAD_CHECK='Both';
      NO_IO_CHECK='Both';
      NO_ASSERT_CHECK='TRUE';
      NO_DIR_CHECK='TRUE';
      ALLOW_CONNECT='TRUE';
    'VSS_CE61':
      PIN_NUMBER='(0,0,0,0,0,0,0,0,0,0,0,0,0,0,0,0,0,0,0,0,0,0,0,0,0,0,0,0,0,0,0~
,0,0,0,0,0,CE61,0,0,0)';
      PINUSE='POWER';
      NO_LOAD_CHECK='Both';
      NO_IO_CHECK='Both';
      NO_ASSERT_CHECK='TRUE';
      NO_DIR_CHECK='TRUE';
      ALLOW_CONNECT='TRUE';
    'VSS_CE63':
      PIN_NUMBER='(0,0,0,0,0,0,0,0,0,0,0,0,0,0,0,0,0,0,0,0,0,0,0,0,0,0,0,0,0,0,0~
,0,0,0,0,0,CE63,0,0,0)';
      PINUSE='POWER';
      NO_LOAD_CHECK='Both';
      NO_IO_CHECK='Both';
      NO_ASSERT_CHECK='TRUE';
      NO_DIR_CHECK='TRUE';
      ALLOW_CONNECT='TRUE';
    'VSS_CE65':
      PIN_NUMBER='(0,0,0,0,0,0,0,0,0,0,0,0,0,0,0,0,0,0,0,0,0,0,0,0,0,0,0,0,0,0,0~
,0,0,0,0,0,CE65,0,0,0)';
      PINUSE='POWER';
      NO_LOAD_CHECK='Both';
      NO_IO_CHECK='Both';
      NO_ASSERT_CHECK='TRUE';
      NO_DIR_CHECK='TRUE';
      ALLOW_CONNECT='TRUE';
    'VSS_CE68':
      PIN_NUMBER='(0,0,0,0,0,0,0,0,0,0,0,0,0,0,0,0,0,0,0,0,0,0,0,0,0,0,0,0,0,0,0~
,0,0,0,0,0,CE68,0,0,0)';
      PINUSE='POWER';
      NO_LOAD_CHECK='Both';
      NO_IO_CHECK='Both';
      NO_ASSERT_CHECK='TRUE';
      NO_DIR_CHECK='TRUE';
      ALLOW_CONNECT='TRUE';
    'VSS_CE70':
      PIN_NUMBER='(0,0,0,0,0,0,0,0,0,0,0,0,0,0,0,0,0,0,0,0,0,0,0,0,0,0,0,0,0,0,0~
,0,0,0,0,0,CE70,0,0,0)';
      PINUSE='POWER';
      NO_LOAD_CHECK='Both';
      NO_IO_CHECK='Both';
      NO_ASSERT_CHECK='TRUE';
      NO_DIR_CHECK='TRUE';
      ALLOW_CONNECT='TRUE';
    'VSS_CE72':
      PIN_NUMBER='(0,0,0,0,0,0,0,0,0,0,0,0,0,0,0,0,0,0,0,0,0,0,0,0,0,0,0,0,0,0,0~
,0,0,0,0,0,CE72,0,0,0)';
      PINUSE='POWER';
      NO_LOAD_CHECK='Both';
      NO_IO_CHECK='Both';
      NO_ASSERT_CHECK='TRUE';
      NO_DIR_CHECK='TRUE';
      ALLOW_CONNECT='TRUE';
    'VSS_CE75':
      PIN_NUMBER='(0,0,0,0,0,0,0,0,0,0,0,0,0,0,0,0,0,0,0,0,0,0,0,0,0,0,0,0,0,0,0~
,0,0,0,0,0,CE75,0,0,0)';
      PINUSE='POWER';
      NO_LOAD_CHECK='Both';
      NO_IO_CHECK='Both';
      NO_ASSERT_CHECK='TRUE';
      NO_DIR_CHECK='TRUE';
      ALLOW_CONNECT='TRUE';
    'VSS_CF3':
      PIN_NUMBER='(0,0,0,0,0,0,0,0,0,0,0,0,0,0,0,0,0,0,0,0,0,0,0,0,0,0,0,0,0,0,0~
,0,0,0,0,0,CF3,0,0,0)';
      PINUSE='POWER';
      NO_LOAD_CHECK='Both';
      NO_IO_CHECK='Both';
      NO_ASSERT_CHECK='TRUE';
      NO_DIR_CHECK='TRUE';
      ALLOW_CONNECT='TRUE';
    'VSS_CF5':
      PIN_NUMBER='(0,0,0,0,0,0,0,0,0,0,0,0,0,0,0,0,0,0,0,0,0,0,0,0,0,0,0,0,0,0,0~
,0,0,0,0,0,CF5,0,0,0)';
      PINUSE='POWER';
      NO_LOAD_CHECK='Both';
      NO_IO_CHECK='Both';
      NO_ASSERT_CHECK='TRUE';
      NO_DIR_CHECK='TRUE';
      ALLOW_CONNECT='TRUE';
    'VSS_CF8':
      PIN_NUMBER='(0,0,0,0,0,0,0,0,0,0,0,0,0,0,0,0,0,0,0,0,0,0,0,0,0,0,0,0,0,0,0~
,0,0,0,0,0,CF8,0,0,0)';
      PINUSE='POWER';
      NO_LOAD_CHECK='Both';
      NO_IO_CHECK='Both';
      NO_ASSERT_CHECK='TRUE';
      NO_DIR_CHECK='TRUE';
      ALLOW_CONNECT='TRUE';
    'VSS_CF10':
      PIN_NUMBER='(0,0,0,0,0,0,0,0,0,0,0,0,0,0,0,0,0,0,0,0,0,0,0,0,0,0,0,0,0,0,0~
,0,0,0,0,0,CF10,0,0,0)';
      PINUSE='POWER';
      NO_LOAD_CHECK='Both';
      NO_IO_CHECK='Both';
      NO_ASSERT_CHECK='TRUE';
      NO_DIR_CHECK='TRUE';
      ALLOW_CONNECT='TRUE';
    'VSS_CF12':
      PIN_NUMBER='(0,0,0,0,0,0,0,0,0,0,0,0,0,0,0,0,0,0,0,0,0,0,0,0,0,0,0,0,0,0,0~
,0,0,0,0,0,CF12,0,0,0)';
      PINUSE='POWER';
      NO_LOAD_CHECK='Both';
      NO_IO_CHECK='Both';
      NO_ASSERT_CHECK='TRUE';
      NO_DIR_CHECK='TRUE';
      ALLOW_CONNECT='TRUE';
    'VSS_CF15':
      PIN_NUMBER='(0,0,0,0,0,0,0,0,0,0,0,0,0,0,0,0,0,0,0,0,0,0,0,0,0,0,0,0,0,0,0~
,0,0,0,0,0,CF15,0,0,0)';
      PINUSE='POWER';
      NO_LOAD_CHECK='Both';
      NO_IO_CHECK='Both';
      NO_ASSERT_CHECK='TRUE';
      NO_DIR_CHECK='TRUE';
      ALLOW_CONNECT='TRUE';
    'VSS_CF17':
      PIN_NUMBER='(0,0,0,0,0,0,0,0,0,0,0,0,0,0,0,0,0,0,0,0,0,0,0,0,0,0,0,0,0,0,0~
,0,0,0,0,0,CF17,0,0,0)';
      PINUSE='POWER';
      NO_LOAD_CHECK='Both';
      NO_IO_CHECK='Both';
      NO_ASSERT_CHECK='TRUE';
      NO_DIR_CHECK='TRUE';
      ALLOW_CONNECT='TRUE';
    'VSS_CF19':
      PIN_NUMBER='(0,0,0,0,0,0,0,0,0,0,0,0,0,0,0,0,0,0,0,0,0,0,0,0,0,0,0,0,0,0,0~
,0,0,0,0,0,CF19,0,0,0)';
      PINUSE='POWER';
      NO_LOAD_CHECK='Both';
      NO_IO_CHECK='Both';
      NO_ASSERT_CHECK='TRUE';
      NO_DIR_CHECK='TRUE';
      ALLOW_CONNECT='TRUE';
    'VSS_CF23':
      PIN_NUMBER='(0,0,0,0,0,0,0,0,0,0,0,0,0,0,0,0,0,0,0,0,0,0,0,0,0,0,0,0,0,0,0~
,0,0,0,0,0,CF23,0,0,0)';
      PINUSE='POWER';
      NO_LOAD_CHECK='Both';
      NO_IO_CHECK='Both';
      NO_ASSERT_CHECK='TRUE';
      NO_DIR_CHECK='TRUE';
      ALLOW_CONNECT='TRUE';
    'VSS_CF24':
      PIN_NUMBER='(0,0,0,0,0,0,0,0,0,0,0,0,0,0,0,0,0,0,0,0,0,0,0,0,0,0,0,0,0,0,0~
,0,0,0,0,0,CF24,0,0,0)';
      PINUSE='POWER';
      NO_LOAD_CHECK='Both';
      NO_IO_CHECK='Both';
      NO_ASSERT_CHECK='TRUE';
      NO_DIR_CHECK='TRUE';
      ALLOW_CONNECT='TRUE';
    'VSS_CF25':
      PIN_NUMBER='(0,0,0,0,0,0,0,0,0,0,0,0,0,0,0,0,0,0,0,0,0,0,0,0,0,0,0,0,0,0,0~
,0,0,0,0,0,CF25,0,0,0)';
      PINUSE='POWER';
      NO_LOAD_CHECK='Both';
      NO_IO_CHECK='Both';
      NO_ASSERT_CHECK='TRUE';
      NO_DIR_CHECK='TRUE';
      ALLOW_CONNECT='TRUE';
    'VSS_CF26':
      PIN_NUMBER='(0,0,0,0,0,0,0,0,0,0,0,0,0,0,0,0,0,0,0,0,0,0,0,0,0,0,0,0,0,0,0~
,0,0,0,0,0,CF26,0,0,0)';
      PINUSE='POWER';
      NO_LOAD_CHECK='Both';
      NO_IO_CHECK='Both';
      NO_ASSERT_CHECK='TRUE';
      NO_DIR_CHECK='TRUE';
      ALLOW_CONNECT='TRUE';
    'VSS_CF27':
      PIN_NUMBER='(0,0,0,0,0,0,0,0,0,0,0,0,0,0,0,0,0,0,0,0,0,0,0,0,0,0,0,0,0,0,0~
,0,0,0,0,0,CF27,0,0,0)';
      PINUSE='POWER';
      NO_LOAD_CHECK='Both';
      NO_IO_CHECK='Both';
      NO_ASSERT_CHECK='TRUE';
      NO_DIR_CHECK='TRUE';
      ALLOW_CONNECT='TRUE';
    'VSS_CF28':
      PIN_NUMBER='(0,0,0,0,0,0,0,0,0,0,0,0,0,0,0,0,0,0,0,0,0,0,0,0,0,0,0,0,0,0,0~
,0,0,0,0,0,CF28,0,0,0)';
      PINUSE='POWER';
      NO_LOAD_CHECK='Both';
      NO_IO_CHECK='Both';
      NO_ASSERT_CHECK='TRUE';
      NO_DIR_CHECK='TRUE';
      ALLOW_CONNECT='TRUE';
    'VSS_CF29':
      PIN_NUMBER='(0,0,0,0,0,0,0,0,0,0,0,0,0,0,0,0,0,0,0,0,0,0,0,0,0,0,0,0,0,0,0~
,0,0,0,0,0,CF29,0,0,0)';
      PINUSE='POWER';
      NO_LOAD_CHECK='Both';
      NO_IO_CHECK='Both';
      NO_ASSERT_CHECK='TRUE';
      NO_DIR_CHECK='TRUE';
      ALLOW_CONNECT='TRUE';
    'VSS_CF30':
      PIN_NUMBER='(0,0,0,0,0,0,0,0,0,0,0,0,0,0,0,0,0,0,0,0,0,0,0,0,0,0,0,0,0,0,0~
,0,0,0,0,0,CF30,0,0,0)';
      PINUSE='POWER';
      NO_LOAD_CHECK='Both';
      NO_IO_CHECK='Both';
      NO_ASSERT_CHECK='TRUE';
      NO_DIR_CHECK='TRUE';
      ALLOW_CONNECT='TRUE';
    'VSS_CF31':
      PIN_NUMBER='(0,0,0,0,0,0,0,0,0,0,0,0,0,0,0,0,0,0,0,0,0,0,0,0,0,0,0,0,0,0,0~
,0,0,0,0,0,CF31,0,0,0)';
      PINUSE='POWER';
      NO_LOAD_CHECK='Both';
      NO_IO_CHECK='Both';
      NO_ASSERT_CHECK='TRUE';
      NO_DIR_CHECK='TRUE';
      ALLOW_CONNECT='TRUE';
    'VSS_CF32':
      PIN_NUMBER='(0,0,0,0,0,0,0,0,0,0,0,0,0,0,0,0,0,0,0,0,0,0,0,0,0,0,0,0,0,0,0~
,0,0,0,0,0,CF32,0,0,0)';
      PINUSE='POWER';
      NO_LOAD_CHECK='Both';
      NO_IO_CHECK='Both';
      NO_ASSERT_CHECK='TRUE';
      NO_DIR_CHECK='TRUE';
      ALLOW_CONNECT='TRUE';
    'VSS_CF33':
      PIN_NUMBER='(0,0,0,0,0,0,0,0,0,0,0,0,0,0,0,0,0,0,0,0,0,0,0,0,0,0,0,0,0,0,0~
,0,0,0,0,0,CF33,0,0,0)';
      PINUSE='POWER';
      NO_LOAD_CHECK='Both';
      NO_IO_CHECK='Both';
      NO_ASSERT_CHECK='TRUE';
      NO_DIR_CHECK='TRUE';
      ALLOW_CONNECT='TRUE';
    'VSS_CN56':
      PIN_NUMBER='(0,0,0,0,0,0,0,0,0,0,0,0,0,0,0,0,0,0,0,0,0,0,0,0,0,0,0,0,0,0,0~
,0,0,0,0,0,0,CN56,0,0)';
      PINUSE='POWER';
      NO_LOAD_CHECK='Both';
      NO_IO_CHECK='Both';
      NO_ASSERT_CHECK='TRUE';
      NO_DIR_CHECK='TRUE';
      ALLOW_CONNECT='TRUE';
    'VSS_CN20':
      PIN_NUMBER='(0,0,0,0,0,0,0,0,0,0,0,0,0,0,0,0,0,0,0,0,0,0,0,0,0,0,0,0,0,0,0~
,0,0,0,0,0,0,CN20,0,0)';
      PINUSE='POWER';
      NO_LOAD_CHECK='Both';
      NO_IO_CHECK='Both';
      NO_ASSERT_CHECK='TRUE';
      NO_DIR_CHECK='TRUE';
      ALLOW_CONNECT='TRUE';
    'VSS_CM61':
      PIN_NUMBER='(0,0,0,0,0,0,0,0,0,0,0,0,0,0,0,0,0,0,0,0,0,0,0,0,0,0,0,0,0,0,0~
,0,0,0,0,0,0,CM61,0,0)';
      PINUSE='POWER';
      NO_LOAD_CHECK='Both';
      NO_IO_CHECK='Both';
      NO_ASSERT_CHECK='TRUE';
      NO_DIR_CHECK='TRUE';
      ALLOW_CONNECT='TRUE';
    'VSS_CM34':
      PIN_NUMBER='(0,0,0,0,0,0,0,0,0,0,0,0,0,0,0,0,0,0,0,0,0,0,0,0,0,0,0,0,0,0,0~
,0,0,0,0,0,0,CM34,0,0)';
      PINUSE='POWER';
      NO_LOAD_CHECK='Both';
      NO_IO_CHECK='Both';
      NO_ASSERT_CHECK='TRUE';
      NO_DIR_CHECK='TRUE';
      ALLOW_CONNECT='TRUE';
    'VSS_CK33':
      PIN_NUMBER='(0,0,0,0,0,0,0,0,0,0,0,0,0,0,0,0,0,0,0,0,0,0,0,0,0,0,0,0,0,0,0~
,0,0,0,0,0,0,CK33,0,0)';
      PINUSE='POWER';
      NO_LOAD_CHECK='Both';
      NO_IO_CHECK='Both';
      NO_ASSERT_CHECK='TRUE';
      NO_DIR_CHECK='TRUE';
      ALLOW_CONNECT='TRUE';
    'VSS_CK15':
      PIN_NUMBER='(0,0,0,0,0,0,0,0,0,0,0,0,0,0,0,0,0,0,0,0,0,0,0,0,0,0,0,0,0,0,0~
,0,0,0,0,0,0,CK15,0,0)';
      PINUSE='POWER';
      NO_LOAD_CHECK='Both';
      NO_IO_CHECK='Both';
      NO_ASSERT_CHECK='TRUE';
      NO_DIR_CHECK='TRUE';
      ALLOW_CONNECT='TRUE';
    'VSS_CJ58':
      PIN_NUMBER='(0,0,0,0,0,0,0,0,0,0,0,0,0,0,0,0,0,0,0,0,0,0,0,0,0,0,0,0,0,0,0~
,0,0,0,0,0,0,CJ58,0,0)';
      PINUSE='POWER';
      NO_LOAD_CHECK='Both';
      NO_IO_CHECK='Both';
      NO_ASSERT_CHECK='TRUE';
      NO_DIR_CHECK='TRUE';
      ALLOW_CONNECT='TRUE';
    'VSS_CJ20':
      PIN_NUMBER='(0,0,0,0,0,0,0,0,0,0,0,0,0,0,0,0,0,0,0,0,0,0,0,0,0,0,0,0,0,0,0~
,0,0,0,0,0,0,CJ20,0,0)';
      PINUSE='POWER';
      NO_LOAD_CHECK='Both';
      NO_IO_CHECK='Both';
      NO_ASSERT_CHECK='TRUE';
      NO_DIR_CHECK='TRUE';
      ALLOW_CONNECT='TRUE';
    'VSS_CH68':
      PIN_NUMBER='(0,0,0,0,0,0,0,0,0,0,0,0,0,0,0,0,0,0,0,0,0,0,0,0,0,0,0,0,0,0,0~
,0,0,0,0,0,0,CH68,0,0)';
      PINUSE='POWER';
      NO_LOAD_CHECK='Both';
      NO_IO_CHECK='Both';
      NO_ASSERT_CHECK='TRUE';
      NO_DIR_CHECK='TRUE';
      ALLOW_CONNECT='TRUE';
    'VSS_CH39':
      PIN_NUMBER='(0,0,0,0,0,0,0,0,0,0,0,0,0,0,0,0,0,0,0,0,0,0,0,0,0,0,0,0,0,0,0~
,0,0,0,0,0,0,CH39,0,0)';
      PINUSE='POWER';
      NO_LOAD_CHECK='Both';
      NO_IO_CHECK='Both';
      NO_ASSERT_CHECK='TRUE';
      NO_DIR_CHECK='TRUE';
      ALLOW_CONNECT='TRUE';
    'VSS_CH10':
      PIN_NUMBER='(0,0,0,0,0,0,0,0,0,0,0,0,0,0,0,0,0,0,0,0,0,0,0,0,0,0,0,0,0,0,0~
,0,0,0,0,0,0,CH10,0,0)';
      PINUSE='POWER';
      NO_LOAD_CHECK='Both';
      NO_IO_CHECK='Both';
      NO_ASSERT_CHECK='TRUE';
      NO_DIR_CHECK='TRUE';
      ALLOW_CONNECT='TRUE';
    'VSS_CN22':
      PIN_NUMBER='(0,0,0,0,0,0,0,0,0,0,0,0,0,0,0,0,0,0,0,0,0,0,0,0,0,0,0,0,0,0,0~
,0,0,0,0,0,0,CN22,0,0)';
      PINUSE='POWER';
      NO_LOAD_CHECK='Both';
      NO_IO_CHECK='Both';
      NO_ASSERT_CHECK='TRUE';
      NO_DIR_CHECK='TRUE';
      ALLOW_CONNECT='TRUE';
    'VSS_CM64':
      PIN_NUMBER='(0,0,0,0,0,0,0,0,0,0,0,0,0,0,0,0,0,0,0,0,0,0,0,0,0,0,0,0,0,0,0~
,0,0,0,0,0,0,CM64,0,0)';
      PINUSE='POWER';
      NO_LOAD_CHECK='Both';
      NO_IO_CHECK='Both';
      NO_ASSERT_CHECK='TRUE';
      NO_DIR_CHECK='TRUE';
      ALLOW_CONNECT='TRUE';
    'VSS_CM37':
      PIN_NUMBER='(0,0,0,0,0,0,0,0,0,0,0,0,0,0,0,0,0,0,0,0,0,0,0,0,0,0,0,0,0,0,0~
,0,0,0,0,0,0,CM37,0,0)';
      PINUSE='POWER';
      NO_LOAD_CHECK='Both';
      NO_IO_CHECK='Both';
      NO_ASSERT_CHECK='TRUE';
      NO_DIR_CHECK='TRUE';
      ALLOW_CONNECT='TRUE';
    'VSS_CM24':
      PIN_NUMBER='(0,0,0,0,0,0,0,0,0,0,0,0,0,0,0,0,0,0,0,0,0,0,0,0,0,0,0,0,0,0,0~
,0,0,0,0,0,0,CM24,0,0)';
      PINUSE='POWER';
      NO_LOAD_CHECK='Both';
      NO_IO_CHECK='Both';
      NO_ASSERT_CHECK='TRUE';
      NO_DIR_CHECK='TRUE';
      ALLOW_CONNECT='TRUE';
    'VSS_CK17':
      PIN_NUMBER='(0,0,0,0,0,0,0,0,0,0,0,0,0,0,0,0,0,0,0,0,0,0,0,0,0,0,0,0,0,0,0~
,0,0,0,0,0,0,CK17,0,0)';
      PINUSE='POWER';
      NO_LOAD_CHECK='Both';
      NO_IO_CHECK='Both';
      NO_ASSERT_CHECK='TRUE';
      NO_DIR_CHECK='TRUE';
      ALLOW_CONNECT='TRUE';
    'VSS_CJ61':
      PIN_NUMBER='(0,0,0,0,0,0,0,0,0,0,0,0,0,0,0,0,0,0,0,0,0,0,0,0,0,0,0,0,0,0,0~
,0,0,0,0,0,0,CJ61,0,0)';
      PINUSE='POWER';
      NO_LOAD_CHECK='Both';
      NO_IO_CHECK='Both';
      NO_ASSERT_CHECK='TRUE';
      NO_DIR_CHECK='TRUE';
      ALLOW_CONNECT='TRUE';
    'VSS_CJ23':
      PIN_NUMBER='(0,0,0,0,0,0,0,0,0,0,0,0,0,0,0,0,0,0,0,0,0,0,0,0,0,0,0,0,0,0,0~
,0,0,0,0,0,0,CJ23,0,0)';
      PINUSE='POWER';
      NO_LOAD_CHECK='Both';
      NO_IO_CHECK='Both';
      NO_ASSERT_CHECK='TRUE';
      NO_DIR_CHECK='TRUE';
      ALLOW_CONNECT='TRUE';
    'VSS_CH71':
      PIN_NUMBER='(0,0,0,0,0,0,0,0,0,0,0,0,0,0,0,0,0,0,0,0,0,0,0,0,0,0,0,0,0,0,0~
,0,0,0,0,0,0,CH71,0,0)';
      PINUSE='POWER';
      NO_LOAD_CHECK='Both';
      NO_IO_CHECK='Both';
      NO_ASSERT_CHECK='TRUE';
      NO_DIR_CHECK='TRUE';
      ALLOW_CONNECT='TRUE';
    'VSS_CH42':
      PIN_NUMBER='(0,0,0,0,0,0,0,0,0,0,0,0,0,0,0,0,0,0,0,0,0,0,0,0,0,0,0,0,0,0,0~
,0,0,0,0,0,0,CH42,0,0)';
      PINUSE='POWER';
      NO_LOAD_CHECK='Both';
      NO_IO_CHECK='Both';
      NO_ASSERT_CHECK='TRUE';
      NO_DIR_CHECK='TRUE';
      ALLOW_CONNECT='TRUE';
    'VSS_CH12':
      PIN_NUMBER='(0,0,0,0,0,0,0,0,0,0,0,0,0,0,0,0,0,0,0,0,0,0,0,0,0,0,0,0,0,0,0~
,0,0,0,0,0,0,CH12,0,0)';
      PINUSE='POWER';
      NO_LOAD_CHECK='Both';
      NO_IO_CHECK='Both';
      NO_ASSERT_CHECK='TRUE';
      NO_DIR_CHECK='TRUE';
      ALLOW_CONNECT='TRUE';
    'VSS_CM66':
      PIN_NUMBER='(0,0,0,0,0,0,0,0,0,0,0,0,0,0,0,0,0,0,0,0,0,0,0,0,0,0,0,0,0,0,0~
,0,0,0,0,0,0,CM66,0,0)';
      PINUSE='POWER';
      NO_LOAD_CHECK='Both';
      NO_IO_CHECK='Both';
      NO_ASSERT_CHECK='TRUE';
      NO_DIR_CHECK='TRUE';
      ALLOW_CONNECT='TRUE';
    'VSS_CM39':
      PIN_NUMBER='(0,0,0,0,0,0,0,0,0,0,0,0,0,0,0,0,0,0,0,0,0,0,0,0,0,0,0,0,0,0,0~
,0,0,0,0,0,0,CM39,0,0)';
      PINUSE='POWER';
      NO_LOAD_CHECK='Both';
      NO_IO_CHECK='Both';
      NO_ASSERT_CHECK='TRUE';
      NO_DIR_CHECK='TRUE';
      ALLOW_CONNECT='TRUE';
    'VSS_CM25':
      PIN_NUMBER='(0,0,0,0,0,0,0,0,0,0,0,0,0,0,0,0,0,0,0,0,0,0,0,0,0,0,0,0,0,0,0~
,0,0,0,0,0,0,CM25,0,0)';
      PINUSE='POWER';
      NO_LOAD_CHECK='Both';
      NO_IO_CHECK='Both';
      NO_ASSERT_CHECK='TRUE';
      NO_DIR_CHECK='TRUE';
      ALLOW_CONNECT='TRUE';
    'VSS_CL75':
      PIN_NUMBER='(0,0,0,0,0,0,0,0,0,0,0,0,0,0,0,0,0,0,0,0,0,0,0,0,0,0,0,0,0,0,0~
,0,0,0,0,0,0,CL75,0,0)';
      PINUSE='POWER';
      NO_LOAD_CHECK='Both';
      NO_IO_CHECK='Both';
      NO_ASSERT_CHECK='TRUE';
      NO_DIR_CHECK='TRUE';
      ALLOW_CONNECT='TRUE';
    'VSS_CJ63':
      PIN_NUMBER='(0,0,0,0,0,0,0,0,0,0,0,0,0,0,0,0,0,0,0,0,0,0,0,0,0,0,0,0,0,0,0~
,0,0,0,0,0,0,CJ63,0,0)';
      PINUSE='POWER';
      NO_LOAD_CHECK='Both';
      NO_IO_CHECK='Both';
      NO_ASSERT_CHECK='TRUE';
      NO_DIR_CHECK='TRUE';
      ALLOW_CONNECT='TRUE';
    'VSS_CJ31':
      PIN_NUMBER='(0,0,0,0,0,0,0,0,0,0,0,0,0,0,0,0,0,0,0,0,0,0,0,0,0,0,0,0,0,0,0~
,0,0,0,0,0,0,CJ31,0,0)';
      PINUSE='POWER';
      NO_LOAD_CHECK='Both';
      NO_IO_CHECK='Both';
      NO_ASSERT_CHECK='TRUE';
      NO_DIR_CHECK='TRUE';
      ALLOW_CONNECT='TRUE';
    'VSS_CH73':
      PIN_NUMBER='(0,0,0,0,0,0,0,0,0,0,0,0,0,0,0,0,0,0,0,0,0,0,0,0,0,0,0,0,0,0,0~
,0,0,0,0,0,0,CH73,0,0)';
      PINUSE='POWER';
      NO_LOAD_CHECK='Both';
      NO_IO_CHECK='Both';
      NO_ASSERT_CHECK='TRUE';
      NO_DIR_CHECK='TRUE';
      ALLOW_CONNECT='TRUE';
    'VSS_CH45':
      PIN_NUMBER='(0,0,0,0,0,0,0,0,0,0,0,0,0,0,0,0,0,0,0,0,0,0,0,0,0,0,0,0,0,0,0~
,0,0,0,0,0,0,CH45,0,0)';
      PINUSE='POWER';
      NO_LOAD_CHECK='Both';
      NO_IO_CHECK='Both';
      NO_ASSERT_CHECK='TRUE';
      NO_DIR_CHECK='TRUE';
      ALLOW_CONNECT='TRUE';
    'VSS_CH15':
      PIN_NUMBER='(0,0,0,0,0,0,0,0,0,0,0,0,0,0,0,0,0,0,0,0,0,0,0,0,0,0,0,0,0,0,0~
,0,0,0,0,0,0,CH15,0,0)';
      PINUSE='POWER';
      NO_LOAD_CHECK='Both';
      NO_IO_CHECK='Both';
      NO_ASSERT_CHECK='TRUE';
      NO_DIR_CHECK='TRUE';
      ALLOW_CONNECT='TRUE';
    'VSS_CM42':
      PIN_NUMBER='(0,0,0,0,0,0,0,0,0,0,0,0,0,0,0,0,0,0,0,0,0,0,0,0,0,0,0,0,0,0,0~
,0,0,0,0,0,0,CM42,0,0)';
      PINUSE='POWER';
      NO_LOAD_CHECK='Both';
      NO_IO_CHECK='Both';
      NO_ASSERT_CHECK='TRUE';
      NO_DIR_CHECK='TRUE';
      ALLOW_CONNECT='TRUE';
    'VSS_CM26':
      PIN_NUMBER='(0,0,0,0,0,0,0,0,0,0,0,0,0,0,0,0,0,0,0,0,0,0,0,0,0,0,0,0,0,0,0~
,0,0,0,0,0,0,CM26,0,0)';
      PINUSE='POWER';
      NO_LOAD_CHECK='Both';
      NO_IO_CHECK='Both';
      NO_ASSERT_CHECK='TRUE';
      NO_DIR_CHECK='TRUE';
      ALLOW_CONNECT='TRUE';
    'VSS_CM3':
      PIN_NUMBER='(0,0,0,0,0,0,0,0,0,0,0,0,0,0,0,0,0,0,0,0,0,0,0,0,0,0,0,0,0,0,0~
,0,0,0,0,0,0,CM3,0,0)';
      PINUSE='POWER';
      NO_LOAD_CHECK='Both';
      NO_IO_CHECK='Both';
      NO_ASSERT_CHECK='TRUE';
      NO_DIR_CHECK='TRUE';
      ALLOW_CONNECT='TRUE';
    'VSS_CL51':
      PIN_NUMBER='(0,0,0,0,0,0,0,0,0,0,0,0,0,0,0,0,0,0,0,0,0,0,0,0,0,0,0,0,0,0,0~
,0,0,0,0,0,0,CL51,0,0)';
      PINUSE='POWER';
      NO_LOAD_CHECK='Both';
      NO_IO_CHECK='Both';
      NO_ASSERT_CHECK='TRUE';
      NO_DIR_CHECK='TRUE';
      ALLOW_CONNECT='TRUE';
    'VSS_CJ34':
      PIN_NUMBER='(0,0,0,0,0,0,0,0,0,0,0,0,0,0,0,0,0,0,0,0,0,0,0,0,0,0,0,0,0,0,0~
,0,0,0,0,0,0,CJ34,0,0)';
      PINUSE='POWER';
      NO_LOAD_CHECK='Both';
      NO_IO_CHECK='Both';
      NO_ASSERT_CHECK='TRUE';
      NO_DIR_CHECK='TRUE';
      ALLOW_CONNECT='TRUE';
    'VSS_CJ1':
      PIN_NUMBER='(0,0,0,0,0,0,0,0,0,0,0,0,0,0,0,0,0,0,0,0,0,0,0,0,0,0,0,0,0,0,0~
,0,0,0,0,0,0,CJ1,0,0)';
      PINUSE='POWER';
      NO_LOAD_CHECK='Both';
      NO_IO_CHECK='Both';
      NO_ASSERT_CHECK='TRUE';
      NO_DIR_CHECK='TRUE';
      ALLOW_CONNECT='TRUE';
    'VSS_CH48':
      PIN_NUMBER='(0,0,0,0,0,0,0,0,0,0,0,0,0,0,0,0,0,0,0,0,0,0,0,0,0,0,0,0,0,0,0~
,0,0,0,0,0,0,CH48,0,0)';
      PINUSE='POWER';
      NO_LOAD_CHECK='Both';
      NO_IO_CHECK='Both';
      NO_ASSERT_CHECK='TRUE';
      NO_DIR_CHECK='TRUE';
      ALLOW_CONNECT='TRUE';
    'VSS_CH17':
      PIN_NUMBER='(0,0,0,0,0,0,0,0,0,0,0,0,0,0,0,0,0,0,0,0,0,0,0,0,0,0,0,0,0,0,0~
,0,0,0,0,0,0,CH17,0,0)';
      PINUSE='POWER';
      NO_LOAD_CHECK='Both';
      NO_IO_CHECK='Both';
      NO_ASSERT_CHECK='TRUE';
      NO_DIR_CHECK='TRUE';
      ALLOW_CONNECT='TRUE';
    'VSS_CM43':
      PIN_NUMBER='(0,0,0,0,0,0,0,0,0,0,0,0,0,0,0,0,0,0,0,0,0,0,0,0,0,0,0,0,0,0,0~
,0,0,0,0,0,0,CM43,0,0)';
      PINUSE='POWER';
      NO_LOAD_CHECK='Both';
      NO_IO_CHECK='Both';
      NO_ASSERT_CHECK='TRUE';
      NO_DIR_CHECK='TRUE';
      ALLOW_CONNECT='TRUE';
    'VSS_CM27':
      PIN_NUMBER='(0,0,0,0,0,0,0,0,0,0,0,0,0,0,0,0,0,0,0,0,0,0,0,0,0,0,0,0,0,0,0~
,0,0,0,0,0,0,CM27,0,0)';
      PINUSE='POWER';
      NO_LOAD_CHECK='Both';
      NO_IO_CHECK='Both';
      NO_ASSERT_CHECK='TRUE';
      NO_DIR_CHECK='TRUE';
      ALLOW_CONNECT='TRUE';
    'VSS_CM5':
      PIN_NUMBER='(0,0,0,0,0,0,0,0,0,0,0,0,0,0,0,0,0,0,0,0,0,0,0,0,0,0,0,0,0,0,0~
,0,0,0,0,0,0,CM5,0,0)';
      PINUSE='POWER';
      NO_LOAD_CHECK='Both';
      NO_IO_CHECK='Both';
      NO_ASSERT_CHECK='TRUE';
      NO_DIR_CHECK='TRUE';
      ALLOW_CONNECT='TRUE';
    'VSS_CL54':
      PIN_NUMBER='(0,0,0,0,0,0,0,0,0,0,0,0,0,0,0,0,0,0,0,0,0,0,0,0,0,0,0,0,0,0,0~
,0,0,0,0,0,0,CL54,0,0)';
      PINUSE='POWER';
      NO_LOAD_CHECK='Both';
      NO_IO_CHECK='Both';
      NO_ASSERT_CHECK='TRUE';
      NO_DIR_CHECK='TRUE';
      ALLOW_CONNECT='TRUE';
    'VSS_CL28':
      PIN_NUMBER='(0,0,0,0,0,0,0,0,0,0,0,0,0,0,0,0,0,0,0,0,0,0,0,0,0,0,0,0,0,0,0~
,0,0,0,0,0,0,CL28,0,0)';
      PINUSE='POWER';
      NO_LOAD_CHECK='Both';
      NO_IO_CHECK='Both';
      NO_ASSERT_CHECK='TRUE';
      NO_DIR_CHECK='TRUE';
      ALLOW_CONNECT='TRUE';
    'VSS_CJ4':
      PIN_NUMBER='(0,0,0,0,0,0,0,0,0,0,0,0,0,0,0,0,0,0,0,0,0,0,0,0,0,0,0,0,0,0,0~
,0,0,0,0,0,0,CJ4,0,0)';
      PINUSE='POWER';
      NO_LOAD_CHECK='Both';
      NO_IO_CHECK='Both';
      NO_ASSERT_CHECK='TRUE';
      NO_DIR_CHECK='TRUE';
      ALLOW_CONNECT='TRUE';
    'VSS_CH51':
      PIN_NUMBER='(0,0,0,0,0,0,0,0,0,0,0,0,0,0,0,0,0,0,0,0,0,0,0,0,0,0,0,0,0,0,0~
,0,0,0,0,0,0,CH51,0,0)';
      PINUSE='POWER';
      NO_LOAD_CHECK='Both';
      NO_IO_CHECK='Both';
      NO_ASSERT_CHECK='TRUE';
      NO_DIR_CHECK='TRUE';
      ALLOW_CONNECT='TRUE';
    'VSS_CH19':
      PIN_NUMBER='(0,0,0,0,0,0,0,0,0,0,0,0,0,0,0,0,0,0,0,0,0,0,0,0,0,0,0,0,0,0,0~
,0,0,0,0,0,0,CH19,0,0)';
      PINUSE='POWER';
      NO_LOAD_CHECK='Both';
      NO_IO_CHECK='Both';
      NO_ASSERT_CHECK='TRUE';
      NO_DIR_CHECK='TRUE';
      ALLOW_CONNECT='TRUE';
    'VSS_CF34':
      PIN_NUMBER='(0,0,0,0,0,0,0,0,0,0,0,0,0,0,0,0,0,0,0,0,0,0,0,0,0,0,0,0,0,0,0~
,0,0,0,0,0,0,CF34,0,0)';
      PINUSE='POWER';
      NO_LOAD_CHECK='Both';
      NO_IO_CHECK='Both';
      NO_ASSERT_CHECK='TRUE';
      NO_DIR_CHECK='TRUE';
      ALLOW_CONNECT='TRUE';
    'VSS_CF37':
      PIN_NUMBER='(0,0,0,0,0,0,0,0,0,0,0,0,0,0,0,0,0,0,0,0,0,0,0,0,0,0,0,0,0,0,0~
,0,0,0,0,0,0,CF37,0,0)';
      PINUSE='POWER';
      NO_LOAD_CHECK='Both';
      NO_IO_CHECK='Both';
      NO_ASSERT_CHECK='TRUE';
      NO_DIR_CHECK='TRUE';
      ALLOW_CONNECT='TRUE';
    'VSS_CF39':
      PIN_NUMBER='(0,0,0,0,0,0,0,0,0,0,0,0,0,0,0,0,0,0,0,0,0,0,0,0,0,0,0,0,0,0,0~
,0,0,0,0,0,0,CF39,0,0)';
      PINUSE='POWER';
      NO_LOAD_CHECK='Both';
      NO_IO_CHECK='Both';
      NO_ASSERT_CHECK='TRUE';
      NO_DIR_CHECK='TRUE';
      ALLOW_CONNECT='TRUE';
    'VSS_CF42':
      PIN_NUMBER='(0,0,0,0,0,0,0,0,0,0,0,0,0,0,0,0,0,0,0,0,0,0,0,0,0,0,0,0,0,0,0~
,0,0,0,0,0,0,CF42,0,0)';
      PINUSE='POWER';
      NO_LOAD_CHECK='Both';
      NO_IO_CHECK='Both';
      NO_ASSERT_CHECK='TRUE';
      NO_DIR_CHECK='TRUE';
      ALLOW_CONNECT='TRUE';
    'VSS_CF43':
      PIN_NUMBER='(0,0,0,0,0,0,0,0,0,0,0,0,0,0,0,0,0,0,0,0,0,0,0,0,0,0,0,0,0,0,0~
,0,0,0,0,0,0,CF43,0,0)';
      PINUSE='POWER';
      NO_LOAD_CHECK='Both';
      NO_IO_CHECK='Both';
      NO_ASSERT_CHECK='TRUE';
      NO_DIR_CHECK='TRUE';
      ALLOW_CONNECT='TRUE';
    'VSS_CF44':
      PIN_NUMBER='(0,0,0,0,0,0,0,0,0,0,0,0,0,0,0,0,0,0,0,0,0,0,0,0,0,0,0,0,0,0,0~
,0,0,0,0,0,0,CF44,0,0)';
      PINUSE='POWER';
      NO_LOAD_CHECK='Both';
      NO_IO_CHECK='Both';
      NO_ASSERT_CHECK='TRUE';
      NO_DIR_CHECK='TRUE';
      ALLOW_CONNECT='TRUE';
    'VSS_CF45':
      PIN_NUMBER='(0,0,0,0,0,0,0,0,0,0,0,0,0,0,0,0,0,0,0,0,0,0,0,0,0,0,0,0,0,0,0~
,0,0,0,0,0,0,CF45,0,0)';
      PINUSE='POWER';
      NO_LOAD_CHECK='Both';
      NO_IO_CHECK='Both';
      NO_ASSERT_CHECK='TRUE';
      NO_DIR_CHECK='TRUE';
      ALLOW_CONNECT='TRUE';
    'VSS_CF47':
      PIN_NUMBER='(0,0,0,0,0,0,0,0,0,0,0,0,0,0,0,0,0,0,0,0,0,0,0,0,0,0,0,0,0,0,0~
,0,0,0,0,0,0,CF47,0,0)';
      PINUSE='POWER';
      NO_LOAD_CHECK='Both';
      NO_IO_CHECK='Both';
      NO_ASSERT_CHECK='TRUE';
      NO_DIR_CHECK='TRUE';
      ALLOW_CONNECT='TRUE';
    'VSS_CF48':
      PIN_NUMBER='(0,0,0,0,0,0,0,0,0,0,0,0,0,0,0,0,0,0,0,0,0,0,0,0,0,0,0,0,0,0,0~
,0,0,0,0,0,0,CF48,0,0)';
      PINUSE='POWER';
      NO_LOAD_CHECK='Both';
      NO_IO_CHECK='Both';
      NO_ASSERT_CHECK='TRUE';
      NO_DIR_CHECK='TRUE';
      ALLOW_CONNECT='TRUE';
    'VSS_CF49':
      PIN_NUMBER='(0,0,0,0,0,0,0,0,0,0,0,0,0,0,0,0,0,0,0,0,0,0,0,0,0,0,0,0,0,0,0~
,0,0,0,0,0,0,CF49,0,0)';
      PINUSE='POWER';
      NO_LOAD_CHECK='Both';
      NO_IO_CHECK='Both';
      NO_ASSERT_CHECK='TRUE';
      NO_DIR_CHECK='TRUE';
      ALLOW_CONNECT='TRUE';
    'VSS_CF50':
      PIN_NUMBER='(0,0,0,0,0,0,0,0,0,0,0,0,0,0,0,0,0,0,0,0,0,0,0,0,0,0,0,0,0,0,0~
,0,0,0,0,0,0,CF50,0,0)';
      PINUSE='POWER';
      NO_LOAD_CHECK='Both';
      NO_IO_CHECK='Both';
      NO_ASSERT_CHECK='TRUE';
      NO_DIR_CHECK='TRUE';
      ALLOW_CONNECT='TRUE';
    'VSS_CF51':
      PIN_NUMBER='(0,0,0,0,0,0,0,0,0,0,0,0,0,0,0,0,0,0,0,0,0,0,0,0,0,0,0,0,0,0,0~
,0,0,0,0,0,0,CF51,0,0)';
      PINUSE='POWER';
      NO_LOAD_CHECK='Both';
      NO_IO_CHECK='Both';
      NO_ASSERT_CHECK='TRUE';
      NO_DIR_CHECK='TRUE';
      ALLOW_CONNECT='TRUE';
    'VSS_CF52':
      PIN_NUMBER='(0,0,0,0,0,0,0,0,0,0,0,0,0,0,0,0,0,0,0,0,0,0,0,0,0,0,0,0,0,0,0~
,0,0,0,0,0,0,CF52,0,0)';
      PINUSE='POWER';
      NO_LOAD_CHECK='Both';
      NO_IO_CHECK='Both';
      NO_ASSERT_CHECK='TRUE';
      NO_DIR_CHECK='TRUE';
      ALLOW_CONNECT='TRUE';
    'VSS_CF53':
      PIN_NUMBER='(0,0,0,0,0,0,0,0,0,0,0,0,0,0,0,0,0,0,0,0,0,0,0,0,0,0,0,0,0,0,0~
,0,0,0,0,0,0,CF53,0,0)';
      PINUSE='POWER';
      NO_LOAD_CHECK='Both';
      NO_IO_CHECK='Both';
      NO_ASSERT_CHECK='TRUE';
      NO_DIR_CHECK='TRUE';
      ALLOW_CONNECT='TRUE';
    'VSS_CF57':
      PIN_NUMBER='(0,0,0,0,0,0,0,0,0,0,0,0,0,0,0,0,0,0,0,0,0,0,0,0,0,0,0,0,0,0,0~
,0,0,0,0,0,0,CF57,0,0)';
      PINUSE='POWER';
      NO_LOAD_CHECK='Both';
      NO_IO_CHECK='Both';
      NO_ASSERT_CHECK='TRUE';
      NO_DIR_CHECK='TRUE';
      ALLOW_CONNECT='TRUE';
    'VSS_CF59':
      PIN_NUMBER='(0,0,0,0,0,0,0,0,0,0,0,0,0,0,0,0,0,0,0,0,0,0,0,0,0,0,0,0,0,0,0~
,0,0,0,0,0,0,CF59,0,0)';
      PINUSE='POWER';
      NO_LOAD_CHECK='Both';
      NO_IO_CHECK='Both';
      NO_ASSERT_CHECK='TRUE';
      NO_DIR_CHECK='TRUE';
      ALLOW_CONNECT='TRUE';
    'VSS_CF61':
      PIN_NUMBER='(0,0,0,0,0,0,0,0,0,0,0,0,0,0,0,0,0,0,0,0,0,0,0,0,0,0,0,0,0,0,0~
,0,0,0,0,0,0,CF61,0,0)';
      PINUSE='POWER';
      NO_LOAD_CHECK='Both';
      NO_IO_CHECK='Both';
      NO_ASSERT_CHECK='TRUE';
      NO_DIR_CHECK='TRUE';
      ALLOW_CONNECT='TRUE';
    'VSS_CF64':
      PIN_NUMBER='(0,0,0,0,0,0,0,0,0,0,0,0,0,0,0,0,0,0,0,0,0,0,0,0,0,0,0,0,0,0,0~
,0,0,0,0,0,0,CF64,0,0)';
      PINUSE='POWER';
      NO_LOAD_CHECK='Both';
      NO_IO_CHECK='Both';
      NO_ASSERT_CHECK='TRUE';
      NO_DIR_CHECK='TRUE';
      ALLOW_CONNECT='TRUE';
    'VSS_CF66':
      PIN_NUMBER='(0,0,0,0,0,0,0,0,0,0,0,0,0,0,0,0,0,0,0,0,0,0,0,0,0,0,0,0,0,0,0~
,0,0,0,0,0,0,CF66,0,0)';
      PINUSE='POWER';
      NO_LOAD_CHECK='Both';
      NO_IO_CHECK='Both';
      NO_ASSERT_CHECK='TRUE';
      NO_DIR_CHECK='TRUE';
      ALLOW_CONNECT='TRUE';
    'VSS_CF68':
      PIN_NUMBER='(0,0,0,0,0,0,0,0,0,0,0,0,0,0,0,0,0,0,0,0,0,0,0,0,0,0,0,0,0,0,0~
,0,0,0,0,0,0,CF68,0,0)';
      PINUSE='POWER';
      NO_LOAD_CHECK='Both';
      NO_IO_CHECK='Both';
      NO_ASSERT_CHECK='TRUE';
      NO_DIR_CHECK='TRUE';
      ALLOW_CONNECT='TRUE';
    'VSS_CF71':
      PIN_NUMBER='(0,0,0,0,0,0,0,0,0,0,0,0,0,0,0,0,0,0,0,0,0,0,0,0,0,0,0,0,0,0,0~
,0,0,0,0,0,0,CF71,0,0)';
      PINUSE='POWER';
      NO_LOAD_CHECK='Both';
      NO_IO_CHECK='Both';
      NO_ASSERT_CHECK='TRUE';
      NO_DIR_CHECK='TRUE';
      ALLOW_CONNECT='TRUE';
    'VSS_CF73':
      PIN_NUMBER='(0,0,0,0,0,0,0,0,0,0,0,0,0,0,0,0,0,0,0,0,0,0,0,0,0,0,0,0,0,0,0~
,0,0,0,0,0,0,CF73,0,0)';
      PINUSE='POWER';
      NO_LOAD_CHECK='Both';
      NO_IO_CHECK='Both';
      NO_ASSERT_CHECK='TRUE';
      NO_DIR_CHECK='TRUE';
      ALLOW_CONNECT='TRUE';
    'VSS_CG1':
      PIN_NUMBER='(0,0,0,0,0,0,0,0,0,0,0,0,0,0,0,0,0,0,0,0,0,0,0,0,0,0,0,0,0,0,0~
,0,0,0,0,0,0,CG1,0,0)';
      PINUSE='POWER';
      NO_LOAD_CHECK='Both';
      NO_IO_CHECK='Both';
      NO_ASSERT_CHECK='TRUE';
      NO_DIR_CHECK='TRUE';
      ALLOW_CONNECT='TRUE';
    'VSS_CG6':
      PIN_NUMBER='(0,0,0,0,0,0,0,0,0,0,0,0,0,0,0,0,0,0,0,0,0,0,0,0,0,0,0,0,0,0,0~
,0,0,0,0,0,0,CG6,0,0)';
      PINUSE='POWER';
      NO_LOAD_CHECK='Both';
      NO_IO_CHECK='Both';
      NO_ASSERT_CHECK='TRUE';
      NO_DIR_CHECK='TRUE';
      ALLOW_CONNECT='TRUE';
    'VSS_CG8':
      PIN_NUMBER='(0,0,0,0,0,0,0,0,0,0,0,0,0,0,0,0,0,0,0,0,0,0,0,0,0,0,0,0,0,0,0~
,0,0,0,0,0,0,CG8,0,0)';
      PINUSE='POWER';
      NO_LOAD_CHECK='Both';
      NO_IO_CHECK='Both';
      NO_ASSERT_CHECK='TRUE';
      NO_DIR_CHECK='TRUE';
      ALLOW_CONNECT='TRUE';
    'VSS_CG13':
      PIN_NUMBER='(0,0,0,0,0,0,0,0,0,0,0,0,0,0,0,0,0,0,0,0,0,0,0,0,0,0,0,0,0,0,0~
,0,0,0,0,0,0,CG13,0,0)';
      PINUSE='POWER';
      NO_LOAD_CHECK='Both';
      NO_IO_CHECK='Both';
      NO_ASSERT_CHECK='TRUE';
      NO_DIR_CHECK='TRUE';
      ALLOW_CONNECT='TRUE';
    'VSS_CG15':
      PIN_NUMBER='(0,0,0,0,0,0,0,0,0,0,0,0,0,0,0,0,0,0,0,0,0,0,0,0,0,0,0,0,0,0,0~
,0,0,0,0,0,0,CG15,0,0)';
      PINUSE='POWER';
      NO_LOAD_CHECK='Both';
      NO_IO_CHECK='Both';
      NO_ASSERT_CHECK='TRUE';
      NO_DIR_CHECK='TRUE';
      ALLOW_CONNECT='TRUE';
    'VSS_CG20':
      PIN_NUMBER='(0,0,0,0,0,0,0,0,0,0,0,0,0,0,0,0,0,0,0,0,0,0,0,0,0,0,0,0,0,0,0~
,0,0,0,0,0,0,CG20,0,0)';
      PINUSE='POWER';
      NO_LOAD_CHECK='Both';
      NO_IO_CHECK='Both';
      NO_ASSERT_CHECK='TRUE';
      NO_DIR_CHECK='TRUE';
      ALLOW_CONNECT='TRUE';
    'VSS_CG22':
      PIN_NUMBER='(0,0,0,0,0,0,0,0,0,0,0,0,0,0,0,0,0,0,0,0,0,0,0,0,0,0,0,0,0,0,0~
,0,0,0,0,0,0,CG22,0,0)';
      PINUSE='POWER';
      NO_LOAD_CHECK='Both';
      NO_IO_CHECK='Both';
      NO_ASSERT_CHECK='TRUE';
      NO_DIR_CHECK='TRUE';
      ALLOW_CONNECT='TRUE';
    'VSS_CG25':
      PIN_NUMBER='(0,0,0,0,0,0,0,0,0,0,0,0,0,0,0,0,0,0,0,0,0,0,0,0,0,0,0,0,0,0,0~
,0,0,0,0,0,0,CG25,0,0)';
      PINUSE='POWER';
      NO_LOAD_CHECK='Both';
      NO_IO_CHECK='Both';
      NO_ASSERT_CHECK='TRUE';
      NO_DIR_CHECK='TRUE';
      ALLOW_CONNECT='TRUE';
    'VSS_CG28':
      PIN_NUMBER='(0,0,0,0,0,0,0,0,0,0,0,0,0,0,0,0,0,0,0,0,0,0,0,0,0,0,0,0,0,0,0~
,0,0,0,0,0,0,CG28,0,0)';
      PINUSE='POWER';
      NO_LOAD_CHECK='Both';
      NO_IO_CHECK='Both';
      NO_ASSERT_CHECK='TRUE';
      NO_DIR_CHECK='TRUE';
      ALLOW_CONNECT='TRUE';
    'VSS_CG31':
      PIN_NUMBER='(0,0,0,0,0,0,0,0,0,0,0,0,0,0,0,0,0,0,0,0,0,0,0,0,0,0,0,0,0,0,0~
,0,0,0,0,0,0,CG31,0,0)';
      PINUSE='POWER';
      NO_LOAD_CHECK='Both';
      NO_IO_CHECK='Both';
      NO_ASSERT_CHECK='TRUE';
      NO_DIR_CHECK='TRUE';
      ALLOW_CONNECT='TRUE';
    'VSS_CG34':
      PIN_NUMBER='(0,0,0,0,0,0,0,0,0,0,0,0,0,0,0,0,0,0,0,0,0,0,0,0,0,0,0,0,0,0,0~
,0,0,0,0,0,0,CG34,0,0)';
      PINUSE='POWER';
      NO_LOAD_CHECK='Both';
      NO_IO_CHECK='Both';
      NO_ASSERT_CHECK='TRUE';
      NO_DIR_CHECK='TRUE';
      ALLOW_CONNECT='TRUE';
    'VSS_CG45':
      PIN_NUMBER='(0,0,0,0,0,0,0,0,0,0,0,0,0,0,0,0,0,0,0,0,0,0,0,0,0,0,0,0,0,0,0~
,0,0,0,0,0,0,CG45,0,0)';
      PINUSE='POWER';
      NO_LOAD_CHECK='Both';
      NO_IO_CHECK='Both';
      NO_ASSERT_CHECK='TRUE';
      NO_DIR_CHECK='TRUE';
      ALLOW_CONNECT='TRUE';
    'VSS_CG48':
      PIN_NUMBER='(0,0,0,0,0,0,0,0,0,0,0,0,0,0,0,0,0,0,0,0,0,0,0,0,0,0,0,0,0,0,0~
,0,0,0,0,0,0,CG48,0,0)';
      PINUSE='POWER';
      NO_LOAD_CHECK='Both';
      NO_IO_CHECK='Both';
      NO_ASSERT_CHECK='TRUE';
      NO_DIR_CHECK='TRUE';
      ALLOW_CONNECT='TRUE';
    'VSS_CG51':
      PIN_NUMBER='(0,0,0,0,0,0,0,0,0,0,0,0,0,0,0,0,0,0,0,0,0,0,0,0,0,0,0,0,0,0,0~
,0,0,0,0,0,0,CG51,0,0)';
      PINUSE='POWER';
      NO_LOAD_CHECK='Both';
      NO_IO_CHECK='Both';
      NO_ASSERT_CHECK='TRUE';
      NO_DIR_CHECK='TRUE';
      ALLOW_CONNECT='TRUE';
    'VSS_CG54':
      PIN_NUMBER='(0,0,0,0,0,0,0,0,0,0,0,0,0,0,0,0,0,0,0,0,0,0,0,0,0,0,0,0,0,0,0~
,0,0,0,0,0,0,CG54,0,0)';
      PINUSE='POWER';
      NO_LOAD_CHECK='Both';
      NO_IO_CHECK='Both';
      NO_ASSERT_CHECK='TRUE';
      NO_DIR_CHECK='TRUE';
      ALLOW_CONNECT='TRUE';
    'VSS_CG56':
      PIN_NUMBER='(0,0,0,0,0,0,0,0,0,0,0,0,0,0,0,0,0,0,0,0,0,0,0,0,0,0,0,0,0,0,0~
,0,0,0,0,0,0,CG56,0,0)';
      PINUSE='POWER';
      NO_LOAD_CHECK='Both';
      NO_IO_CHECK='Both';
      NO_ASSERT_CHECK='TRUE';
      NO_DIR_CHECK='TRUE';
      ALLOW_CONNECT='TRUE';
    'VSS_CG61':
      PIN_NUMBER='(0,0,0,0,0,0,0,0,0,0,0,0,0,0,0,0,0,0,0,0,0,0,0,0,0,0,0,0,0,0,0~
,0,0,0,0,0,0,CG61,0,0)';
      PINUSE='POWER';
      NO_LOAD_CHECK='Both';
      NO_IO_CHECK='Both';
      NO_ASSERT_CHECK='TRUE';
      NO_DIR_CHECK='TRUE';
      ALLOW_CONNECT='TRUE';
    'VSS_CG63':
      PIN_NUMBER='(0,0,0,0,0,0,0,0,0,0,0,0,0,0,0,0,0,0,0,0,0,0,0,0,0,0,0,0,0,0,0~
,0,0,0,0,0,0,CG63,0,0)';
      PINUSE='POWER';
      NO_LOAD_CHECK='Both';
      NO_IO_CHECK='Both';
      NO_ASSERT_CHECK='TRUE';
      NO_DIR_CHECK='TRUE';
      ALLOW_CONNECT='TRUE';
    'VSS_CG68':
      PIN_NUMBER='(0,0,0,0,0,0,0,0,0,0,0,0,0,0,0,0,0,0,0,0,0,0,0,0,0,0,0,0,0,0,0~
,0,0,0,0,0,0,CG68,0,0)';
      PINUSE='POWER';
      NO_LOAD_CHECK='Both';
      NO_IO_CHECK='Both';
      NO_ASSERT_CHECK='TRUE';
      NO_DIR_CHECK='TRUE';
      ALLOW_CONNECT='TRUE';
    'VSS_CG70':
      PIN_NUMBER='(0,0,0,0,0,0,0,0,0,0,0,0,0,0,0,0,0,0,0,0,0,0,0,0,0,0,0,0,0,0,0~
,0,0,0,0,0,0,CG70,0,0)';
      PINUSE='POWER';
      NO_LOAD_CHECK='Both';
      NO_IO_CHECK='Both';
      NO_ASSERT_CHECK='TRUE';
      NO_DIR_CHECK='TRUE';
      ALLOW_CONNECT='TRUE';
    'VSS_CG75':
      PIN_NUMBER='(0,0,0,0,0,0,0,0,0,0,0,0,0,0,0,0,0,0,0,0,0,0,0,0,0,0,0,0,0,0,0~
,0,0,0,0,0,0,CG75,0,0)';
      PINUSE='POWER';
      NO_LOAD_CHECK='Both';
      NO_IO_CHECK='Both';
      NO_ASSERT_CHECK='TRUE';
      NO_DIR_CHECK='TRUE';
      ALLOW_CONNECT='TRUE';
    'VSS_CH3':
      PIN_NUMBER='(0,0,0,0,0,0,0,0,0,0,0,0,0,0,0,0,0,0,0,0,0,0,0,0,0,0,0,0,0,0,0~
,0,0,0,0,0,0,CH3,0,0)';
      PINUSE='POWER';
      NO_LOAD_CHECK='Both';
      NO_IO_CHECK='Both';
      NO_ASSERT_CHECK='TRUE';
      NO_DIR_CHECK='TRUE';
      ALLOW_CONNECT='TRUE';
    'VSS_CH5':
      PIN_NUMBER='(0,0,0,0,0,0,0,0,0,0,0,0,0,0,0,0,0,0,0,0,0,0,0,0,0,0,0,0,0,0,0~
,0,0,0,0,0,0,CH5,0,0)';
      PINUSE='POWER';
      NO_LOAD_CHECK='Both';
      NO_IO_CHECK='Both';
      NO_ASSERT_CHECK='TRUE';
      NO_DIR_CHECK='TRUE';
      ALLOW_CONNECT='TRUE';
    'VSS_CH8':
      PIN_NUMBER='(0,0,0,0,0,0,0,0,0,0,0,0,0,0,0,0,0,0,0,0,0,0,0,0,0,0,0,0,0,0,0~
,0,0,0,0,0,0,CH8,0,0)';
      PINUSE='POWER';
      NO_LOAD_CHECK='Both';
      NO_IO_CHECK='Both';
      NO_ASSERT_CHECK='TRUE';
      NO_DIR_CHECK='TRUE';
      ALLOW_CONNECT='TRUE';
    'VSS_CH22':
      PIN_NUMBER='(0,0,0,0,0,0,0,0,0,0,0,0,0,0,0,0,0,0,0,0,0,0,0,0,0,0,0,0,0,0,0~
,0,0,0,0,0,0,CH22,0,0)';
      PINUSE='POWER';
      NO_LOAD_CHECK='Both';
      NO_IO_CHECK='Both';
      NO_ASSERT_CHECK='TRUE';
      NO_DIR_CHECK='TRUE';
      ALLOW_CONNECT='TRUE';
    'VSS_CH25':
      PIN_NUMBER='(0,0,0,0,0,0,0,0,0,0,0,0,0,0,0,0,0,0,0,0,0,0,0,0,0,0,0,0,0,0,0~
,0,0,0,0,0,0,CH25,0,0)';
      PINUSE='POWER';
      NO_LOAD_CHECK='Both';
      NO_IO_CHECK='Both';
      NO_ASSERT_CHECK='TRUE';
      NO_DIR_CHECK='TRUE';
      ALLOW_CONNECT='TRUE';
    'VSS_CH28':
      PIN_NUMBER='(0,0,0,0,0,0,0,0,0,0,0,0,0,0,0,0,0,0,0,0,0,0,0,0,0,0,0,0,0,0,0~
,0,0,0,0,0,0,CH28,0,0)';
      PINUSE='POWER';
      NO_LOAD_CHECK='Both';
      NO_IO_CHECK='Both';
      NO_ASSERT_CHECK='TRUE';
      NO_DIR_CHECK='TRUE';
      ALLOW_CONNECT='TRUE';
    'VSS_CH31':
      PIN_NUMBER='(0,0,0,0,0,0,0,0,0,0,0,0,0,0,0,0,0,0,0,0,0,0,0,0,0,0,0,0,0,0,0~
,0,0,0,0,0,0,CH31,0,0)';
      PINUSE='POWER';
      NO_LOAD_CHECK='Both';
      NO_IO_CHECK='Both';
      NO_ASSERT_CHECK='TRUE';
      NO_DIR_CHECK='TRUE';
      ALLOW_CONNECT='TRUE';
    'VSS_CH34':
      PIN_NUMBER='(0,0,0,0,0,0,0,0,0,0,0,0,0,0,0,0,0,0,0,0,0,0,0,0,0,0,0,0,0,0,0~
,0,0,0,0,0,0,CH34,0,0)';
      PINUSE='POWER';
      NO_LOAD_CHECK='Both';
      NO_IO_CHECK='Both';
      NO_ASSERT_CHECK='TRUE';
      NO_DIR_CHECK='TRUE';
      ALLOW_CONNECT='TRUE';
    'VSS_CH37':
      PIN_NUMBER='(0,0,0,0,0,0,0,0,0,0,0,0,0,0,0,0,0,0,0,0,0,0,0,0,0,0,0,0,0,0,0~
,0,0,0,0,0,0,CH37,0,0)';
      PINUSE='POWER';
      NO_LOAD_CHECK='Both';
      NO_IO_CHECK='Both';
      NO_ASSERT_CHECK='TRUE';
      NO_DIR_CHECK='TRUE';
      ALLOW_CONNECT='TRUE';
    'VSS_CH54':
      PIN_NUMBER='(0,0,0,0,0,0,0,0,0,0,0,0,0,0,0,0,0,0,0,0,0,0,0,0,0,0,0,0,0,0,0~
,0,0,0,0,0,0,CH54,0,0)';
      PINUSE='POWER';
      NO_LOAD_CHECK='Both';
      NO_IO_CHECK='Both';
      NO_ASSERT_CHECK='TRUE';
      NO_DIR_CHECK='TRUE';
      ALLOW_CONNECT='TRUE';
    'VSS_CH57':
      PIN_NUMBER='(0,0,0,0,0,0,0,0,0,0,0,0,0,0,0,0,0,0,0,0,0,0,0,0,0,0,0,0,0,0,0~
,0,0,0,0,0,0,CH57,0,0)';
      PINUSE='POWER';
      NO_LOAD_CHECK='Both';
      NO_IO_CHECK='Both';
      NO_ASSERT_CHECK='TRUE';
      NO_DIR_CHECK='TRUE';
      ALLOW_CONNECT='TRUE';
    'VSS_CH59':
      PIN_NUMBER='(0,0,0,0,0,0,0,0,0,0,0,0,0,0,0,0,0,0,0,0,0,0,0,0,0,0,0,0,0,0,0~
,0,0,0,0,0,0,CH59,0,0)';
      PINUSE='POWER';
      NO_LOAD_CHECK='Both';
      NO_IO_CHECK='Both';
      NO_ASSERT_CHECK='TRUE';
      NO_DIR_CHECK='TRUE';
      ALLOW_CONNECT='TRUE';
    'VSS_CH61':
      PIN_NUMBER='(0,0,0,0,0,0,0,0,0,0,0,0,0,0,0,0,0,0,0,0,0,0,0,0,0,0,0,0,0,0,0~
,0,0,0,0,0,0,CH61,0,0)';
      PINUSE='POWER';
      NO_LOAD_CHECK='Both';
      NO_IO_CHECK='Both';
      NO_ASSERT_CHECK='TRUE';
      NO_DIR_CHECK='TRUE';
      ALLOW_CONNECT='TRUE';
    'VSS_CH64':
      PIN_NUMBER='(0,0,0,0,0,0,0,0,0,0,0,0,0,0,0,0,0,0,0,0,0,0,0,0,0,0,0,0,0,0,0~
,0,0,0,0,0,0,CH64,0,0)';
      PINUSE='POWER';
      NO_LOAD_CHECK='Both';
      NO_IO_CHECK='Both';
      NO_ASSERT_CHECK='TRUE';
      NO_DIR_CHECK='TRUE';
      ALLOW_CONNECT='TRUE';
    'VSS_CH66':
      PIN_NUMBER='(0,0,0,0,0,0,0,0,0,0,0,0,0,0,0,0,0,0,0,0,0,0,0,0,0,0,0,0,0,0,0~
,0,0,0,0,0,0,CH66,0,0)';
      PINUSE='POWER';
      NO_LOAD_CHECK='Both';
      NO_IO_CHECK='Both';
      NO_ASSERT_CHECK='TRUE';
      NO_DIR_CHECK='TRUE';
      ALLOW_CONNECT='TRUE';
    'VSS_CJ6':
      PIN_NUMBER='(0,0,0,0,0,0,0,0,0,0,0,0,0,0,0,0,0,0,0,0,0,0,0,0,0,0,0,0,0,0,0~
,0,0,0,0,0,0,CJ6,0,0)';
      PINUSE='POWER';
      NO_LOAD_CHECK='Both';
      NO_IO_CHECK='Both';
      NO_ASSERT_CHECK='TRUE';
      NO_DIR_CHECK='TRUE';
      ALLOW_CONNECT='TRUE';
    'VSS_CJ8':
      PIN_NUMBER='(0,0,0,0,0,0,0,0,0,0,0,0,0,0,0,0,0,0,0,0,0,0,0,0,0,0,0,0,0,0,0~
,0,0,0,0,0,0,CJ8,0,0)';
      PINUSE='POWER';
      NO_LOAD_CHECK='Both';
      NO_IO_CHECK='Both';
      NO_ASSERT_CHECK='TRUE';
      NO_DIR_CHECK='TRUE';
      ALLOW_CONNECT='TRUE';
    'VSS_CJ11':
      PIN_NUMBER='(0,0,0,0,0,0,0,0,0,0,0,0,0,0,0,0,0,0,0,0,0,0,0,0,0,0,0,0,0,0,0~
,0,0,0,0,0,0,CJ11,0,0)';
      PINUSE='POWER';
      NO_LOAD_CHECK='Both';
      NO_IO_CHECK='Both';
      NO_ASSERT_CHECK='TRUE';
      NO_DIR_CHECK='TRUE';
      ALLOW_CONNECT='TRUE';
    'VSS_CJ13':
      PIN_NUMBER='(0,0,0,0,0,0,0,0,0,0,0,0,0,0,0,0,0,0,0,0,0,0,0,0,0,0,0,0,0,0,0~
,0,0,0,0,0,0,CJ13,0,0)';
      PINUSE='POWER';
      NO_LOAD_CHECK='Both';
      NO_IO_CHECK='Both';
      NO_ASSERT_CHECK='TRUE';
      NO_DIR_CHECK='TRUE';
      ALLOW_CONNECT='TRUE';
    'VSS_CJ15':
      PIN_NUMBER='(0,0,0,0,0,0,0,0,0,0,0,0,0,0,0,0,0,0,0,0,0,0,0,0,0,0,0,0,0,0,0~
,0,0,0,0,0,0,CJ15,0,0)';
      PINUSE='POWER';
      NO_LOAD_CHECK='Both';
      NO_IO_CHECK='Both';
      NO_ASSERT_CHECK='TRUE';
      NO_DIR_CHECK='TRUE';
      ALLOW_CONNECT='TRUE';
    'VSS_CJ18':
      PIN_NUMBER='(0,0,0,0,0,0,0,0,0,0,0,0,0,0,0,0,0,0,0,0,0,0,0,0,0,0,0,0,0,0,0~
,0,0,0,0,0,0,CJ18,0,0)';
      PINUSE='POWER';
      NO_LOAD_CHECK='Both';
      NO_IO_CHECK='Both';
      NO_ASSERT_CHECK='TRUE';
      NO_DIR_CHECK='TRUE';
      ALLOW_CONNECT='TRUE';
    'VSS_CJ35':
      PIN_NUMBER='(0,0,0,0,0,0,0,0,0,0,0,0,0,0,0,0,0,0,0,0,0,0,0,0,0,0,0,0,0,0,0~
,0,0,0,0,0,0,CJ35,0,0)';
      PINUSE='POWER';
      NO_LOAD_CHECK='Both';
      NO_IO_CHECK='Both';
      NO_ASSERT_CHECK='TRUE';
      NO_DIR_CHECK='TRUE';
      ALLOW_CONNECT='TRUE';
    'VSS_CJ36':
      PIN_NUMBER='(0,0,0,0,0,0,0,0,0,0,0,0,0,0,0,0,0,0,0,0,0,0,0,0,0,0,0,0,0,0,0~
,0,0,0,0,0,0,CJ36,0,0)';
      PINUSE='POWER';
      NO_LOAD_CHECK='Both';
      NO_IO_CHECK='Both';
      NO_ASSERT_CHECK='TRUE';
      NO_DIR_CHECK='TRUE';
      ALLOW_CONNECT='TRUE';
    'VSS_CJ40':
      PIN_NUMBER='(0,0,0,0,0,0,0,0,0,0,0,0,0,0,0,0,0,0,0,0,0,0,0,0,0,0,0,0,0,0,0~
,0,0,0,0,0,0,CJ40,0,0)';
      PINUSE='POWER';
      NO_LOAD_CHECK='Both';
      NO_IO_CHECK='Both';
      NO_ASSERT_CHECK='TRUE';
      NO_DIR_CHECK='TRUE';
      ALLOW_CONNECT='TRUE';
    'VSS_CJ41':
      PIN_NUMBER='(0,0,0,0,0,0,0,0,0,0,0,0,0,0,0,0,0,0,0,0,0,0,0,0,0,0,0,0,0,0,0~
,0,0,0,0,0,0,CJ41,0,0)';
      PINUSE='POWER';
      NO_LOAD_CHECK='Both';
      NO_IO_CHECK='Both';
      NO_ASSERT_CHECK='TRUE';
      NO_DIR_CHECK='TRUE';
      ALLOW_CONNECT='TRUE';
    'VSS_CJ42':
      PIN_NUMBER='(0,0,0,0,0,0,0,0,0,0,0,0,0,0,0,0,0,0,0,0,0,0,0,0,0,0,0,0,0,0,0~
,0,0,0,0,0,0,CJ42,0,0)';
      PINUSE='POWER';
      NO_LOAD_CHECK='Both';
      NO_IO_CHECK='Both';
      NO_ASSERT_CHECK='TRUE';
      NO_DIR_CHECK='TRUE';
      ALLOW_CONNECT='TRUE';
    'VSS_CJ45':
      PIN_NUMBER='(0,0,0,0,0,0,0,0,0,0,0,0,0,0,0,0,0,0,0,0,0,0,0,0,0,0,0,0,0,0,0~
,0,0,0,0,0,0,CJ45,0,0)';
      PINUSE='POWER';
      NO_LOAD_CHECK='Both';
      NO_IO_CHECK='Both';
      NO_ASSERT_CHECK='TRUE';
      NO_DIR_CHECK='TRUE';
      ALLOW_CONNECT='TRUE';
    'VSS_CJ56':
      PIN_NUMBER='(0,0,0,0,0,0,0,0,0,0,0,0,0,0,0,0,0,0,0,0,0,0,0,0,0,0,0,0,0,0,0~
,0,0,0,0,0,0,CJ56,0,0)';
      PINUSE='POWER';
      NO_LOAD_CHECK='Both';
      NO_IO_CHECK='Both';
      NO_ASSERT_CHECK='TRUE';
      NO_DIR_CHECK='TRUE';
      ALLOW_CONNECT='TRUE';
    'VSS_CJ65':
      PIN_NUMBER='(0,0,0,0,0,0,0,0,0,0,0,0,0,0,0,0,0,0,0,0,0,0,0,0,0,0,0,0,0,0,0~
,0,0,0,0,0,0,CJ65,0,0)';
      PINUSE='POWER';
      NO_LOAD_CHECK='Both';
      NO_IO_CHECK='Both';
      NO_ASSERT_CHECK='TRUE';
      NO_DIR_CHECK='TRUE';
      ALLOW_CONNECT='TRUE';
    'VSS_CJ68':
      PIN_NUMBER='(0,0,0,0,0,0,0,0,0,0,0,0,0,0,0,0,0,0,0,0,0,0,0,0,0,0,0,0,0,0,0~
,0,0,0,0,0,0,CJ68,0,0)';
      PINUSE='POWER';
      NO_LOAD_CHECK='Both';
      NO_IO_CHECK='Both';
      NO_ASSERT_CHECK='TRUE';
      NO_DIR_CHECK='TRUE';
      ALLOW_CONNECT='TRUE';
    'VSS_CJ70':
      PIN_NUMBER='(0,0,0,0,0,0,0,0,0,0,0,0,0,0,0,0,0,0,0,0,0,0,0,0,0,0,0,0,0,0,0~
,0,0,0,0,0,0,CJ70,0,0)';
      PINUSE='POWER';
      NO_LOAD_CHECK='Both';
      NO_IO_CHECK='Both';
      NO_ASSERT_CHECK='TRUE';
      NO_DIR_CHECK='TRUE';
      ALLOW_CONNECT='TRUE';
    'VSS_CJ72':
      PIN_NUMBER='(0,0,0,0,0,0,0,0,0,0,0,0,0,0,0,0,0,0,0,0,0,0,0,0,0,0,0,0,0,0,0~
,0,0,0,0,0,0,CJ72,0,0)';
      PINUSE='POWER';
      NO_LOAD_CHECK='Both';
      NO_IO_CHECK='Both';
      NO_ASSERT_CHECK='TRUE';
      NO_DIR_CHECK='TRUE';
      ALLOW_CONNECT='TRUE';
    'VSS_CJ75':
      PIN_NUMBER='(0,0,0,0,0,0,0,0,0,0,0,0,0,0,0,0,0,0,0,0,0,0,0,0,0,0,0,0,0,0,0~
,0,0,0,0,0,0,CJ75,0,0)';
      PINUSE='POWER';
      NO_LOAD_CHECK='Both';
      NO_IO_CHECK='Both';
      NO_ASSERT_CHECK='TRUE';
      NO_DIR_CHECK='TRUE';
      ALLOW_CONNECT='TRUE';
    'VSS_CK3':
      PIN_NUMBER='(0,0,0,0,0,0,0,0,0,0,0,0,0,0,0,0,0,0,0,0,0,0,0,0,0,0,0,0,0,0,0~
,0,0,0,0,0,0,CK3,0,0)';
      PINUSE='POWER';
      NO_LOAD_CHECK='Both';
      NO_IO_CHECK='Both';
      NO_ASSERT_CHECK='TRUE';
      NO_DIR_CHECK='TRUE';
      ALLOW_CONNECT='TRUE';
    'VSS_CK8':
      PIN_NUMBER='(0,0,0,0,0,0,0,0,0,0,0,0,0,0,0,0,0,0,0,0,0,0,0,0,0,0,0,0,0,0,0~
,0,0,0,0,0,0,CK8,0,0)';
      PINUSE='POWER';
      NO_LOAD_CHECK='Both';
      NO_IO_CHECK='Both';
      NO_ASSERT_CHECK='TRUE';
      NO_DIR_CHECK='TRUE';
      ALLOW_CONNECT='TRUE';
    'VSS_CK22':
      PIN_NUMBER='(0,0,0,0,0,0,0,0,0,0,0,0,0,0,0,0,0,0,0,0,0,0,0,0,0,0,0,0,0,0,0~
,0,0,0,0,0,0,CK22,0,0)';
      PINUSE='POWER';
      NO_LOAD_CHECK='Both';
      NO_IO_CHECK='Both';
      NO_ASSERT_CHECK='TRUE';
      NO_DIR_CHECK='TRUE';
      ALLOW_CONNECT='TRUE';
    'VSS_CK23':
      PIN_NUMBER='(0,0,0,0,0,0,0,0,0,0,0,0,0,0,0,0,0,0,0,0,0,0,0,0,0,0,0,0,0,0,0~
,0,0,0,0,0,0,CK23,0,0)';
      PINUSE='POWER';
      NO_LOAD_CHECK='Both';
      NO_IO_CHECK='Both';
      NO_ASSERT_CHECK='TRUE';
      NO_DIR_CHECK='TRUE';
      ALLOW_CONNECT='TRUE';
    'VSS_CK24':
      PIN_NUMBER='(0,0,0,0,0,0,0,0,0,0,0,0,0,0,0,0,0,0,0,0,0,0,0,0,0,0,0,0,0,0,0~
,0,0,0,0,0,0,CK24,0,0)';
      PINUSE='POWER';
      NO_LOAD_CHECK='Both';
      NO_IO_CHECK='Both';
      NO_ASSERT_CHECK='TRUE';
      NO_DIR_CHECK='TRUE';
      ALLOW_CONNECT='TRUE';
    'VSS_CK25':
      PIN_NUMBER='(0,0,0,0,0,0,0,0,0,0,0,0,0,0,0,0,0,0,0,0,0,0,0,0,0,0,0,0,0,0,0~
,0,0,0,0,0,0,CK25,0,0)';
      PINUSE='POWER';
      NO_LOAD_CHECK='Both';
      NO_IO_CHECK='Both';
      NO_ASSERT_CHECK='TRUE';
      NO_DIR_CHECK='TRUE';
      ALLOW_CONNECT='TRUE';
    'VSS_CK26':
      PIN_NUMBER='(0,0,0,0,0,0,0,0,0,0,0,0,0,0,0,0,0,0,0,0,0,0,0,0,0,0,0,0,0,0,0~
,0,0,0,0,0,0,CK26,0,0)';
      PINUSE='POWER';
      NO_LOAD_CHECK='Both';
      NO_IO_CHECK='Both';
      NO_ASSERT_CHECK='TRUE';
      NO_DIR_CHECK='TRUE';
      ALLOW_CONNECT='TRUE';
    'VSS_CK27':
      PIN_NUMBER='(0,0,0,0,0,0,0,0,0,0,0,0,0,0,0,0,0,0,0,0,0,0,0,0,0,0,0,0,0,0,0~
,0,0,0,0,0,0,CK27,0,0)';
      PINUSE='POWER';
      NO_LOAD_CHECK='Both';
      NO_IO_CHECK='Both';
      NO_ASSERT_CHECK='TRUE';
      NO_DIR_CHECK='TRUE';
      ALLOW_CONNECT='TRUE';
    'VSS_CK28':
      PIN_NUMBER='(0,0,0,0,0,0,0,0,0,0,0,0,0,0,0,0,0,0,0,0,0,0,0,0,0,0,0,0,0,0,0~
,0,0,0,0,0,0,CK28,0,0)';
      PINUSE='POWER';
      NO_LOAD_CHECK='Both';
      NO_IO_CHECK='Both';
      NO_ASSERT_CHECK='TRUE';
      NO_DIR_CHECK='TRUE';
      ALLOW_CONNECT='TRUE';
    'VSS_CK32':
      PIN_NUMBER='(0,0,0,0,0,0,0,0,0,0,0,0,0,0,0,0,0,0,0,0,0,0,0,0,0,0,0,0,0,0,0~
,0,0,0,0,0,0,CK32,0,0)';
      PINUSE='POWER';
      NO_LOAD_CHECK='Both';
      NO_IO_CHECK='Both';
      NO_ASSERT_CHECK='TRUE';
      NO_DIR_CHECK='TRUE';
      ALLOW_CONNECT='TRUE';
    'VSS_CK34':
      PIN_NUMBER='(0,0,0,0,0,0,0,0,0,0,0,0,0,0,0,0,0,0,0,0,0,0,0,0,0,0,0,0,0,0,0~
,0,0,0,0,0,0,CK34,0,0)';
      PINUSE='POWER';
      NO_LOAD_CHECK='Both';
      NO_IO_CHECK='Both';
      NO_ASSERT_CHECK='TRUE';
      NO_DIR_CHECK='TRUE';
      ALLOW_CONNECT='TRUE';
    'VSS_CK37':
      PIN_NUMBER='(0,0,0,0,0,0,0,0,0,0,0,0,0,0,0,0,0,0,0,0,0,0,0,0,0,0,0,0,0,0,0~
,0,0,0,0,0,0,CK37,0,0)';
      PINUSE='POWER';
      NO_LOAD_CHECK='Both';
      NO_IO_CHECK='Both';
      NO_ASSERT_CHECK='TRUE';
      NO_DIR_CHECK='TRUE';
      ALLOW_CONNECT='TRUE';
    'VSS_CK39':
      PIN_NUMBER='(0,0,0,0,0,0,0,0,0,0,0,0,0,0,0,0,0,0,0,0,0,0,0,0,0,0,0,0,0,0,0~
,0,0,0,0,0,0,CK39,0,0)';
      PINUSE='POWER';
      NO_LOAD_CHECK='Both';
      NO_IO_CHECK='Both';
      NO_ASSERT_CHECK='TRUE';
      NO_DIR_CHECK='TRUE';
      ALLOW_CONNECT='TRUE';
    'VSS_CK42':
      PIN_NUMBER='(0,0,0,0,0,0,0,0,0,0,0,0,0,0,0,0,0,0,0,0,0,0,0,0,0,0,0,0,0,0,0~
,0,0,0,0,0,0,CK42,0,0)';
      PINUSE='POWER';
      NO_LOAD_CHECK='Both';
      NO_IO_CHECK='Both';
      NO_ASSERT_CHECK='TRUE';
      NO_DIR_CHECK='TRUE';
      ALLOW_CONNECT='TRUE';
    'VSS_CK43':
      PIN_NUMBER='(0,0,0,0,0,0,0,0,0,0,0,0,0,0,0,0,0,0,0,0,0,0,0,0,0,0,0,0,0,0,0~
,0,0,0,0,0,0,CK43,0,0)';
      PINUSE='POWER';
      NO_LOAD_CHECK='Both';
      NO_IO_CHECK='Both';
      NO_ASSERT_CHECK='TRUE';
      NO_DIR_CHECK='TRUE';
      ALLOW_CONNECT='TRUE';
    'VSS_CK44':
      PIN_NUMBER='(0,0,0,0,0,0,0,0,0,0,0,0,0,0,0,0,0,0,0,0,0,0,0,0,0,0,0,0,0,0,0~
,0,0,0,0,0,0,CK44,0,0)';
      PINUSE='POWER';
      NO_LOAD_CHECK='Both';
      NO_IO_CHECK='Both';
      NO_ASSERT_CHECK='TRUE';
      NO_DIR_CHECK='TRUE';
      ALLOW_CONNECT='TRUE';
    'VSS_CK45':
      PIN_NUMBER='(0,0,0,0,0,0,0,0,0,0,0,0,0,0,0,0,0,0,0,0,0,0,0,0,0,0,0,0,0,0,0~
,0,0,0,0,0,0,CK45,0,0)';
      PINUSE='POWER';
      NO_LOAD_CHECK='Both';
      NO_IO_CHECK='Both';
      NO_ASSERT_CHECK='TRUE';
      NO_DIR_CHECK='TRUE';
      ALLOW_CONNECT='TRUE';
    'VSS_CK48':
      PIN_NUMBER='(0,0,0,0,0,0,0,0,0,0,0,0,0,0,0,0,0,0,0,0,0,0,0,0,0,0,0,0,0,0,0~
,0,0,0,0,0,0,CK48,0,0)';
      PINUSE='POWER';
      NO_LOAD_CHECK='Both';
      NO_IO_CHECK='Both';
      NO_ASSERT_CHECK='TRUE';
      NO_DIR_CHECK='TRUE';
      ALLOW_CONNECT='TRUE';
    'VSS_CK49':
      PIN_NUMBER='(0,0,0,0,0,0,0,0,0,0,0,0,0,0,0,0,0,0,0,0,0,0,0,0,0,0,0,0,0,0,0~
,0,0,0,0,0,0,CK49,0,0)';
      PINUSE='POWER';
      NO_LOAD_CHECK='Both';
      NO_IO_CHECK='Both';
      NO_ASSERT_CHECK='TRUE';
      NO_DIR_CHECK='TRUE';
      ALLOW_CONNECT='TRUE';
    'VSS_CK50':
      PIN_NUMBER='(0,0,0,0,0,0,0,0,0,0,0,0,0,0,0,0,0,0,0,0,0,0,0,0,0,0,0,0,0,0,0~
,0,0,0,0,0,0,CK50,0,0)';
      PINUSE='POWER';
      NO_LOAD_CHECK='Both';
      NO_IO_CHECK='Both';
      NO_ASSERT_CHECK='TRUE';
      NO_DIR_CHECK='TRUE';
      ALLOW_CONNECT='TRUE';
    'VSS_CK51':
      PIN_NUMBER='(0,0,0,0,0,0,0,0,0,0,0,0,0,0,0,0,0,0,0,0,0,0,0,0,0,0,0,0,0,0,0~
,0,0,0,0,0,0,CK51,0,0)';
      PINUSE='POWER';
      NO_LOAD_CHECK='Both';
      NO_IO_CHECK='Both';
      NO_ASSERT_CHECK='TRUE';
      NO_DIR_CHECK='TRUE';
      ALLOW_CONNECT='TRUE';
    'VSS_CK52':
      PIN_NUMBER='(0,0,0,0,0,0,0,0,0,0,0,0,0,0,0,0,0,0,0,0,0,0,0,0,0,0,0,0,0,0,0~
,0,0,0,0,0,0,CK52,0,0)';
      PINUSE='POWER';
      NO_LOAD_CHECK='Both';
      NO_IO_CHECK='Both';
      NO_ASSERT_CHECK='TRUE';
      NO_DIR_CHECK='TRUE';
      ALLOW_CONNECT='TRUE';
    'VSS_CK53':
      PIN_NUMBER='(0,0,0,0,0,0,0,0,0,0,0,0,0,0,0,0,0,0,0,0,0,0,0,0,0,0,0,0,0,0,0~
,0,0,0,0,0,0,CK53,0,0)';
      PINUSE='POWER';
      NO_LOAD_CHECK='Both';
      NO_IO_CHECK='Both';
      NO_ASSERT_CHECK='TRUE';
      NO_DIR_CHECK='TRUE';
      ALLOW_CONNECT='TRUE';
    'VSS_CK54':
      PIN_NUMBER='(0,0,0,0,0,0,0,0,0,0,0,0,0,0,0,0,0,0,0,0,0,0,0,0,0,0,0,0,0,0,0~
,0,0,0,0,0,0,CK54,0,0)';
      PINUSE='POWER';
      NO_LOAD_CHECK='Both';
      NO_IO_CHECK='Both';
      NO_ASSERT_CHECK='TRUE';
      NO_DIR_CHECK='TRUE';
      ALLOW_CONNECT='TRUE';
    'VSS_CK59':
      PIN_NUMBER='(0,0,0,0,0,0,0,0,0,0,0,0,0,0,0,0,0,0,0,0,0,0,0,0,0,0,0,0,0,0,0~
,0,0,0,0,0,0,CK59,0,0)';
      PINUSE='POWER';
      NO_LOAD_CHECK='Both';
      NO_IO_CHECK='Both';
      NO_ASSERT_CHECK='TRUE';
      NO_DIR_CHECK='TRUE';
      ALLOW_CONNECT='TRUE';
    'VSS_CK61':
      PIN_NUMBER='(0,0,0,0,0,0,0,0,0,0,0,0,0,0,0,0,0,0,0,0,0,0,0,0,0,0,0,0,0,0,0~
,0,0,0,0,0,0,CK61,0,0)';
      PINUSE='POWER';
      NO_LOAD_CHECK='Both';
      NO_IO_CHECK='Both';
      NO_ASSERT_CHECK='TRUE';
      NO_DIR_CHECK='TRUE';
      ALLOW_CONNECT='TRUE';
    'VSS_CK66':
      PIN_NUMBER='(0,0,0,0,0,0,0,0,0,0,0,0,0,0,0,0,0,0,0,0,0,0,0,0,0,0,0,0,0,0,0~
,0,0,0,0,0,0,CK66,0,0)';
      PINUSE='POWER';
      NO_LOAD_CHECK='Both';
      NO_IO_CHECK='Both';
      NO_ASSERT_CHECK='TRUE';
      NO_DIR_CHECK='TRUE';
      ALLOW_CONNECT='TRUE';
    'VSS_CK68':
      PIN_NUMBER='(0,0,0,0,0,0,0,0,0,0,0,0,0,0,0,0,0,0,0,0,0,0,0,0,0,0,0,0,0,0,0~
,0,0,0,0,0,0,CK68,0,0)';
      PINUSE='POWER';
      NO_LOAD_CHECK='Both';
      NO_IO_CHECK='Both';
      NO_ASSERT_CHECK='TRUE';
      NO_DIR_CHECK='TRUE';
      ALLOW_CONNECT='TRUE';
    'VSS_CK73':
      PIN_NUMBER='(0,0,0,0,0,0,0,0,0,0,0,0,0,0,0,0,0,0,0,0,0,0,0,0,0,0,0,0,0,0,0~
,0,0,0,0,0,0,CK73,0,0)';
      PINUSE='POWER';
      NO_LOAD_CHECK='Both';
      NO_IO_CHECK='Both';
      NO_ASSERT_CHECK='TRUE';
      NO_DIR_CHECK='TRUE';
      ALLOW_CONNECT='TRUE';
    'VSS_CL1':
      PIN_NUMBER='(0,0,0,0,0,0,0,0,0,0,0,0,0,0,0,0,0,0,0,0,0,0,0,0,0,0,0,0,0,0,0~
,0,0,0,0,0,0,CL1,0,0)';
      PINUSE='POWER';
      NO_LOAD_CHECK='Both';
      NO_IO_CHECK='Both';
      NO_ASSERT_CHECK='TRUE';
      NO_DIR_CHECK='TRUE';
      ALLOW_CONNECT='TRUE';
    'VSS_CL4':
      PIN_NUMBER='(0,0,0,0,0,0,0,0,0,0,0,0,0,0,0,0,0,0,0,0,0,0,0,0,0,0,0,0,0,0,0~
,0,0,0,0,0,0,CL4,0,0)';
      PINUSE='POWER';
      NO_LOAD_CHECK='Both';
      NO_IO_CHECK='Both';
      NO_ASSERT_CHECK='TRUE';
      NO_DIR_CHECK='TRUE';
      ALLOW_CONNECT='TRUE';
    'VSS_CL6':
      PIN_NUMBER='(0,0,0,0,0,0,0,0,0,0,0,0,0,0,0,0,0,0,0,0,0,0,0,0,0,0,0,0,0,0,0~
,0,0,0,0,0,0,CL6,0,0)';
      PINUSE='POWER';
      NO_LOAD_CHECK='Both';
      NO_IO_CHECK='Both';
      NO_ASSERT_CHECK='TRUE';
      NO_DIR_CHECK='TRUE';
      ALLOW_CONNECT='TRUE';
    'VSS_CL8':
      PIN_NUMBER='(0,0,0,0,0,0,0,0,0,0,0,0,0,0,0,0,0,0,0,0,0,0,0,0,0,0,0,0,0,0,0~
,0,0,0,0,0,0,CL8,0,0)';
      PINUSE='POWER';
      NO_LOAD_CHECK='Both';
      NO_IO_CHECK='Both';
      NO_ASSERT_CHECK='TRUE';
      NO_DIR_CHECK='TRUE';
      ALLOW_CONNECT='TRUE';
    'VSS_CL11':
      PIN_NUMBER='(0,0,0,0,0,0,0,0,0,0,0,0,0,0,0,0,0,0,0,0,0,0,0,0,0,0,0,0,0,0,0~
,0,0,0,0,0,0,CL11,0,0)';
      PINUSE='POWER';
      NO_LOAD_CHECK='Both';
      NO_IO_CHECK='Both';
      NO_ASSERT_CHECK='TRUE';
      NO_DIR_CHECK='TRUE';
      ALLOW_CONNECT='TRUE';
    'VSS_CL13':
      PIN_NUMBER='(0,0,0,0,0,0,0,0,0,0,0,0,0,0,0,0,0,0,0,0,0,0,0,0,0,0,0,0,0,0,0~
,0,0,0,0,0,0,CL13,0,0)';
      PINUSE='POWER';
      NO_LOAD_CHECK='Both';
      NO_IO_CHECK='Both';
      NO_ASSERT_CHECK='TRUE';
      NO_DIR_CHECK='TRUE';
      ALLOW_CONNECT='TRUE';
    'VSS_CL15':
      PIN_NUMBER='(0,0,0,0,0,0,0,0,0,0,0,0,0,0,0,0,0,0,0,0,0,0,0,0,0,0,0,0,0,0,0~
,0,0,0,0,0,0,CL15,0,0)';
      PINUSE='POWER';
      NO_LOAD_CHECK='Both';
      NO_IO_CHECK='Both';
      NO_ASSERT_CHECK='TRUE';
      NO_DIR_CHECK='TRUE';
      ALLOW_CONNECT='TRUE';
    'VSS_CL18':
      PIN_NUMBER='(0,0,0,0,0,0,0,0,0,0,0,0,0,0,0,0,0,0,0,0,0,0,0,0,0,0,0,0,0,0,0~
,0,0,0,0,0,0,CL18,0,0)';
      PINUSE='POWER';
      NO_LOAD_CHECK='Both';
      NO_IO_CHECK='Both';
      NO_ASSERT_CHECK='TRUE';
      NO_DIR_CHECK='TRUE';
      ALLOW_CONNECT='TRUE';
    'VSS_CL20':
      PIN_NUMBER='(0,0,0,0,0,0,0,0,0,0,0,0,0,0,0,0,0,0,0,0,0,0,0,0,0,0,0,0,0,0,0~
,0,0,0,0,0,0,CL20,0,0)';
      PINUSE='POWER';
      NO_LOAD_CHECK='Both';
      NO_IO_CHECK='Both';
      NO_ASSERT_CHECK='TRUE';
      NO_DIR_CHECK='TRUE';
      ALLOW_CONNECT='TRUE';
    'VSS_CL22':
      PIN_NUMBER='(0,0,0,0,0,0,0,0,0,0,0,0,0,0,0,0,0,0,0,0,0,0,0,0,0,0,0,0,0,0,0~
,0,0,0,0,0,0,CL22,0,0)';
      PINUSE='POWER';
      NO_LOAD_CHECK='Both';
      NO_IO_CHECK='Both';
      NO_ASSERT_CHECK='TRUE';
      NO_DIR_CHECK='TRUE';
      ALLOW_CONNECT='TRUE';
    'VSS_CL25':
      PIN_NUMBER='(0,0,0,0,0,0,0,0,0,0,0,0,0,0,0,0,0,0,0,0,0,0,0,0,0,0,0,0,0,0,0~
,0,0,0,0,0,0,CL25,0,0)';
      PINUSE='POWER';
      NO_LOAD_CHECK='Both';
      NO_IO_CHECK='Both';
      NO_ASSERT_CHECK='TRUE';
      NO_DIR_CHECK='TRUE';
      ALLOW_CONNECT='TRUE';
    'VSS_CL31':
      PIN_NUMBER='(0,0,0,0,0,0,0,0,0,0,0,0,0,0,0,0,0,0,0,0,0,0,0,0,0,0,0,0,0,0,0~
,0,0,0,0,0,0,CL31,0,0)';
      PINUSE='POWER';
      NO_LOAD_CHECK='Both';
      NO_IO_CHECK='Both';
      NO_ASSERT_CHECK='TRUE';
      NO_DIR_CHECK='TRUE';
      ALLOW_CONNECT='TRUE';
    'VSS_CL34':
      PIN_NUMBER='(0,0,0,0,0,0,0,0,0,0,0,0,0,0,0,0,0,0,0,0,0,0,0,0,0,0,0,0,0,0,0~
,0,0,0,0,0,0,CL34,0,0)';
      PINUSE='POWER';
      NO_LOAD_CHECK='Both';
      NO_IO_CHECK='Both';
      NO_ASSERT_CHECK='TRUE';
      NO_DIR_CHECK='TRUE';
      ALLOW_CONNECT='TRUE';
    'VSS_CL35':
      PIN_NUMBER='(0,0,0,0,0,0,0,0,0,0,0,0,0,0,0,0,0,0,0,0,0,0,0,0,0,0,0,0,0,0,0~
,0,0,0,0,0,0,CL35,0,0)';
      PINUSE='POWER';
      NO_LOAD_CHECK='Both';
      NO_IO_CHECK='Both';
      NO_ASSERT_CHECK='TRUE';
      NO_DIR_CHECK='TRUE';
      ALLOW_CONNECT='TRUE';
    'VSS_CL36':
      PIN_NUMBER='(0,0,0,0,0,0,0,0,0,0,0,0,0,0,0,0,0,0,0,0,0,0,0,0,0,0,0,0,0,0,0~
,0,0,0,0,0,0,CL36,0,0)';
      PINUSE='POWER';
      NO_LOAD_CHECK='Both';
      NO_IO_CHECK='Both';
      NO_ASSERT_CHECK='TRUE';
      NO_DIR_CHECK='TRUE';
      ALLOW_CONNECT='TRUE';
    'VSS_CL40':
      PIN_NUMBER='(0,0,0,0,0,0,0,0,0,0,0,0,0,0,0,0,0,0,0,0,0,0,0,0,0,0,0,0,0,0,0~
,0,0,0,0,0,0,CL40,0,0)';
      PINUSE='POWER';
      NO_LOAD_CHECK='Both';
      NO_IO_CHECK='Both';
      NO_ASSERT_CHECK='TRUE';
      NO_DIR_CHECK='TRUE';
      ALLOW_CONNECT='TRUE';
    'VSS_CL41':
      PIN_NUMBER='(0,0,0,0,0,0,0,0,0,0,0,0,0,0,0,0,0,0,0,0,0,0,0,0,0,0,0,0,0,0,0~
,0,0,0,0,0,0,CL41,0,0)';
      PINUSE='POWER';
      NO_LOAD_CHECK='Both';
      NO_IO_CHECK='Both';
      NO_ASSERT_CHECK='TRUE';
      NO_DIR_CHECK='TRUE';
      ALLOW_CONNECT='TRUE';
    'VSS_CL42':
      PIN_NUMBER='(0,0,0,0,0,0,0,0,0,0,0,0,0,0,0,0,0,0,0,0,0,0,0,0,0,0,0,0,0,0,0~
,0,0,0,0,0,0,CL42,0,0)';
      PINUSE='POWER';
      NO_LOAD_CHECK='Both';
      NO_IO_CHECK='Both';
      NO_ASSERT_CHECK='TRUE';
      NO_DIR_CHECK='TRUE';
      ALLOW_CONNECT='TRUE';
    'VSS_CL45':
      PIN_NUMBER='(0,0,0,0,0,0,0,0,0,0,0,0,0,0,0,0,0,0,0,0,0,0,0,0,0,0,0,0,0,0,0~
,0,0,0,0,0,0,CL45,0,0)';
      PINUSE='POWER';
      NO_LOAD_CHECK='Both';
      NO_IO_CHECK='Both';
      NO_ASSERT_CHECK='TRUE';
      NO_DIR_CHECK='TRUE';
      ALLOW_CONNECT='TRUE';
    'VSS_CL48':
      PIN_NUMBER='(0,0,0,0,0,0,0,0,0,0,0,0,0,0,0,0,0,0,0,0,0,0,0,0,0,0,0,0,0,0,0~
,0,0,0,0,0,0,CL48,0,0)';
      PINUSE='POWER';
      NO_LOAD_CHECK='Both';
      NO_IO_CHECK='Both';
      NO_ASSERT_CHECK='TRUE';
      NO_DIR_CHECK='TRUE';
      ALLOW_CONNECT='TRUE';
    'VSS_CL56':
      PIN_NUMBER='(0,0,0,0,0,0,0,0,0,0,0,0,0,0,0,0,0,0,0,0,0,0,0,0,0,0,0,0,0,0,0~
,0,0,0,0,0,0,CL56,0,0)';
      PINUSE='POWER';
      NO_LOAD_CHECK='Both';
      NO_IO_CHECK='Both';
      NO_ASSERT_CHECK='TRUE';
      NO_DIR_CHECK='TRUE';
      ALLOW_CONNECT='TRUE';
    'VSS_CL58':
      PIN_NUMBER='(0,0,0,0,0,0,0,0,0,0,0,0,0,0,0,0,0,0,0,0,0,0,0,0,0,0,0,0,0,0,0~
,0,0,0,0,0,0,CL58,0,0)';
      PINUSE='POWER';
      NO_LOAD_CHECK='Both';
      NO_IO_CHECK='Both';
      NO_ASSERT_CHECK='TRUE';
      NO_DIR_CHECK='TRUE';
      ALLOW_CONNECT='TRUE';
    'VSS_CL61':
      PIN_NUMBER='(0,0,0,0,0,0,0,0,0,0,0,0,0,0,0,0,0,0,0,0,0,0,0,0,0,0,0,0,0,0,0~
,0,0,0,0,0,0,CL61,0,0)';
      PINUSE='POWER';
      NO_LOAD_CHECK='Both';
      NO_IO_CHECK='Both';
      NO_ASSERT_CHECK='TRUE';
      NO_DIR_CHECK='TRUE';
      ALLOW_CONNECT='TRUE';
    'VSS_CL63':
      PIN_NUMBER='(0,0,0,0,0,0,0,0,0,0,0,0,0,0,0,0,0,0,0,0,0,0,0,0,0,0,0,0,0,0,0~
,0,0,0,0,0,0,CL63,0,0)';
      PINUSE='POWER';
      NO_LOAD_CHECK='Both';
      NO_IO_CHECK='Both';
      NO_ASSERT_CHECK='TRUE';
      NO_DIR_CHECK='TRUE';
      ALLOW_CONNECT='TRUE';
    'VSS_CL65':
      PIN_NUMBER='(0,0,0,0,0,0,0,0,0,0,0,0,0,0,0,0,0,0,0,0,0,0,0,0,0,0,0,0,0,0,0~
,0,0,0,0,0,0,CL65,0,0)';
      PINUSE='POWER';
      NO_LOAD_CHECK='Both';
      NO_IO_CHECK='Both';
      NO_ASSERT_CHECK='TRUE';
      NO_DIR_CHECK='TRUE';
      ALLOW_CONNECT='TRUE';
    'VSS_CL68':
      PIN_NUMBER='(0,0,0,0,0,0,0,0,0,0,0,0,0,0,0,0,0,0,0,0,0,0,0,0,0,0,0,0,0,0,0~
,0,0,0,0,0,0,CL68,0,0)';
      PINUSE='POWER';
      NO_LOAD_CHECK='Both';
      NO_IO_CHECK='Both';
      NO_ASSERT_CHECK='TRUE';
      NO_DIR_CHECK='TRUE';
      ALLOW_CONNECT='TRUE';
    'VSS_CL70':
      PIN_NUMBER='(0,0,0,0,0,0,0,0,0,0,0,0,0,0,0,0,0,0,0,0,0,0,0,0,0,0,0,0,0,0,0~
,0,0,0,0,0,0,CL70,0,0)';
      PINUSE='POWER';
      NO_LOAD_CHECK='Both';
      NO_IO_CHECK='Both';
      NO_ASSERT_CHECK='TRUE';
      NO_DIR_CHECK='TRUE';
      ALLOW_CONNECT='TRUE';
    'VSS_CL72':
      PIN_NUMBER='(0,0,0,0,0,0,0,0,0,0,0,0,0,0,0,0,0,0,0,0,0,0,0,0,0,0,0,0,0,0,0~
,0,0,0,0,0,0,CL72,0,0)';
      PINUSE='POWER';
      NO_LOAD_CHECK='Both';
      NO_IO_CHECK='Both';
      NO_ASSERT_CHECK='TRUE';
      NO_DIR_CHECK='TRUE';
      ALLOW_CONNECT='TRUE';
    'VSS_CM8':
      PIN_NUMBER='(0,0,0,0,0,0,0,0,0,0,0,0,0,0,0,0,0,0,0,0,0,0,0,0,0,0,0,0,0,0,0~
,0,0,0,0,0,0,CM8,0,0)';
      PINUSE='POWER';
      NO_LOAD_CHECK='Both';
      NO_IO_CHECK='Both';
      NO_ASSERT_CHECK='TRUE';
      NO_DIR_CHECK='TRUE';
      ALLOW_CONNECT='TRUE';
    'VSS_CM10':
      PIN_NUMBER='(0,0,0,0,0,0,0,0,0,0,0,0,0,0,0,0,0,0,0,0,0,0,0,0,0,0,0,0,0,0,0~
,0,0,0,0,0,0,CM10,0,0)';
      PINUSE='POWER';
      NO_LOAD_CHECK='Both';
      NO_IO_CHECK='Both';
      NO_ASSERT_CHECK='TRUE';
      NO_DIR_CHECK='TRUE';
      ALLOW_CONNECT='TRUE';
    'VSS_CM12':
      PIN_NUMBER='(0,0,0,0,0,0,0,0,0,0,0,0,0,0,0,0,0,0,0,0,0,0,0,0,0,0,0,0,0,0,0~
,0,0,0,0,0,0,CM12,0,0)';
      PINUSE='POWER';
      NO_LOAD_CHECK='Both';
      NO_IO_CHECK='Both';
      NO_ASSERT_CHECK='TRUE';
      NO_DIR_CHECK='TRUE';
      ALLOW_CONNECT='TRUE';
    'VSS_CM15':
      PIN_NUMBER='(0,0,0,0,0,0,0,0,0,0,0,0,0,0,0,0,0,0,0,0,0,0,0,0,0,0,0,0,0,0,0~
,0,0,0,0,0,0,CM15,0,0)';
      PINUSE='POWER';
      NO_LOAD_CHECK='Both';
      NO_IO_CHECK='Both';
      NO_ASSERT_CHECK='TRUE';
      NO_DIR_CHECK='TRUE';
      ALLOW_CONNECT='TRUE';
    'VSS_CM17':
      PIN_NUMBER='(0,0,0,0,0,0,0,0,0,0,0,0,0,0,0,0,0,0,0,0,0,0,0,0,0,0,0,0,0,0,0~
,0,0,0,0,0,0,CM17,0,0)';
      PINUSE='POWER';
      NO_LOAD_CHECK='Both';
      NO_IO_CHECK='Both';
      NO_ASSERT_CHECK='TRUE';
      NO_DIR_CHECK='TRUE';
      ALLOW_CONNECT='TRUE';
    'VSS_CM19':
      PIN_NUMBER='(0,0,0,0,0,0,0,0,0,0,0,0,0,0,0,0,0,0,0,0,0,0,0,0,0,0,0,0,0,0,0~
,0,0,0,0,0,0,CM19,0,0)';
      PINUSE='POWER';
      NO_LOAD_CHECK='Both';
      NO_IO_CHECK='Both';
      NO_ASSERT_CHECK='TRUE';
      NO_DIR_CHECK='TRUE';
      ALLOW_CONNECT='TRUE';
    'VSS_CM23':
      PIN_NUMBER='(0,0,0,0,0,0,0,0,0,0,0,0,0,0,0,0,0,0,0,0,0,0,0,0,0,0,0,0,0,0,0~
,0,0,0,0,0,0,CM23,0,0)';
      PINUSE='POWER';
      NO_LOAD_CHECK='Both';
      NO_IO_CHECK='Both';
      NO_ASSERT_CHECK='TRUE';
      NO_DIR_CHECK='TRUE';
      ALLOW_CONNECT='TRUE';
    'VSS_CM28':
      PIN_NUMBER='(0,0,0,0,0,0,0,0,0,0,0,0,0,0,0,0,0,0,0,0,0,0,0,0,0,0,0,0,0,0,0~
,0,0,0,0,0,0,CM28,0,0)';
      PINUSE='POWER';
      NO_LOAD_CHECK='Both';
      NO_IO_CHECK='Both';
      NO_ASSERT_CHECK='TRUE';
      NO_DIR_CHECK='TRUE';
      ALLOW_CONNECT='TRUE';
    'VSS_CM29':
      PIN_NUMBER='(0,0,0,0,0,0,0,0,0,0,0,0,0,0,0,0,0,0,0,0,0,0,0,0,0,0,0,0,0,0,0~
,0,0,0,0,0,0,CM29,0,0)';
      PINUSE='POWER';
      NO_LOAD_CHECK='Both';
      NO_IO_CHECK='Both';
      NO_ASSERT_CHECK='TRUE';
      NO_DIR_CHECK='TRUE';
      ALLOW_CONNECT='TRUE';
    'VSS_CM30':
      PIN_NUMBER='(0,0,0,0,0,0,0,0,0,0,0,0,0,0,0,0,0,0,0,0,0,0,0,0,0,0,0,0,0,0,0~
,0,0,0,0,0,0,CM30,0,0)';
      PINUSE='POWER';
      NO_LOAD_CHECK='Both';
      NO_IO_CHECK='Both';
      NO_ASSERT_CHECK='TRUE';
      NO_DIR_CHECK='TRUE';
      ALLOW_CONNECT='TRUE';
    'VSS_CM31':
      PIN_NUMBER='(0,0,0,0,0,0,0,0,0,0,0,0,0,0,0,0,0,0,0,0,0,0,0,0,0,0,0,0,0,0,0~
,0,0,0,0,0,0,CM31,0,0)';
      PINUSE='POWER';
      NO_LOAD_CHECK='Both';
      NO_IO_CHECK='Both';
      NO_ASSERT_CHECK='TRUE';
      NO_DIR_CHECK='TRUE';
      ALLOW_CONNECT='TRUE';
    'VSS_CM32':
      PIN_NUMBER='(0,0,0,0,0,0,0,0,0,0,0,0,0,0,0,0,0,0,0,0,0,0,0,0,0,0,0,0,0,0,0~
,0,0,0,0,0,0,CM32,0,0)';
      PINUSE='POWER';
      NO_LOAD_CHECK='Both';
      NO_IO_CHECK='Both';
      NO_ASSERT_CHECK='TRUE';
      NO_DIR_CHECK='TRUE';
      ALLOW_CONNECT='TRUE';
    'VSS_CM33':
      PIN_NUMBER='(0,0,0,0,0,0,0,0,0,0,0,0,0,0,0,0,0,0,0,0,0,0,0,0,0,0,0,0,0,0,0~
,0,0,0,0,0,0,CM33,0,0)';
      PINUSE='POWER';
      NO_LOAD_CHECK='Both';
      NO_IO_CHECK='Both';
      NO_ASSERT_CHECK='TRUE';
      NO_DIR_CHECK='TRUE';
      ALLOW_CONNECT='TRUE';
    'VSS_CM44':
      PIN_NUMBER='(0,0,0,0,0,0,0,0,0,0,0,0,0,0,0,0,0,0,0,0,0,0,0,0,0,0,0,0,0,0,0~
,0,0,0,0,0,0,CM44,0,0)';
      PINUSE='POWER';
      NO_LOAD_CHECK='Both';
      NO_IO_CHECK='Both';
      NO_ASSERT_CHECK='TRUE';
      NO_DIR_CHECK='TRUE';
      ALLOW_CONNECT='TRUE';
    'VSS_CM45':
      PIN_NUMBER='(0,0,0,0,0,0,0,0,0,0,0,0,0,0,0,0,0,0,0,0,0,0,0,0,0,0,0,0,0,0,0~
,0,0,0,0,0,0,CM45,0,0)';
      PINUSE='POWER';
      NO_LOAD_CHECK='Both';
      NO_IO_CHECK='Both';
      NO_ASSERT_CHECK='TRUE';
      NO_DIR_CHECK='TRUE';
      ALLOW_CONNECT='TRUE';
    'VSS_CM46':
      PIN_NUMBER='(0,0,0,0,0,0,0,0,0,0,0,0,0,0,0,0,0,0,0,0,0,0,0,0,0,0,0,0,0,0,0~
,0,0,0,0,0,0,CM46,0,0)';
      PINUSE='POWER';
      NO_LOAD_CHECK='Both';
      NO_IO_CHECK='Both';
      NO_ASSERT_CHECK='TRUE';
      NO_DIR_CHECK='TRUE';
      ALLOW_CONNECT='TRUE';
    'VSS_CM47':
      PIN_NUMBER='(0,0,0,0,0,0,0,0,0,0,0,0,0,0,0,0,0,0,0,0,0,0,0,0,0,0,0,0,0,0,0~
,0,0,0,0,0,0,CM47,0,0)';
      PINUSE='POWER';
      NO_LOAD_CHECK='Both';
      NO_IO_CHECK='Both';
      NO_ASSERT_CHECK='TRUE';
      NO_DIR_CHECK='TRUE';
      ALLOW_CONNECT='TRUE';
    'VSS_CM48':
      PIN_NUMBER='(0,0,0,0,0,0,0,0,0,0,0,0,0,0,0,0,0,0,0,0,0,0,0,0,0,0,0,0,0,0,0~
,0,0,0,0,0,0,CM48,0,0)';
      PINUSE='POWER';
      NO_LOAD_CHECK='Both';
      NO_IO_CHECK='Both';
      NO_ASSERT_CHECK='TRUE';
      NO_DIR_CHECK='TRUE';
      ALLOW_CONNECT='TRUE';
    'VSS_CM49':
      PIN_NUMBER='(0,0,0,0,0,0,0,0,0,0,0,0,0,0,0,0,0,0,0,0,0,0,0,0,0,0,0,0,0,0,0~
,0,0,0,0,0,0,CM49,0,0)';
      PINUSE='POWER';
      NO_LOAD_CHECK='Both';
      NO_IO_CHECK='Both';
      NO_ASSERT_CHECK='TRUE';
      NO_DIR_CHECK='TRUE';
      ALLOW_CONNECT='TRUE';
    'VSS_CM51':
      PIN_NUMBER='(0,0,0,0,0,0,0,0,0,0,0,0,0,0,0,0,0,0,0,0,0,0,0,0,0,0,0,0,0,0,0~
,0,0,0,0,0,0,CM51,0,0)';
      PINUSE='POWER';
      NO_LOAD_CHECK='Both';
      NO_IO_CHECK='Both';
      NO_ASSERT_CHECK='TRUE';
      NO_DIR_CHECK='TRUE';
      ALLOW_CONNECT='TRUE';
    'VSS_CM52':
      PIN_NUMBER='(0,0,0,0,0,0,0,0,0,0,0,0,0,0,0,0,0,0,0,0,0,0,0,0,0,0,0,0,0,0,0~
,0,0,0,0,0,0,CM52,0,0)';
      PINUSE='POWER';
      NO_LOAD_CHECK='Both';
      NO_IO_CHECK='Both';
      NO_ASSERT_CHECK='TRUE';
      NO_DIR_CHECK='TRUE';
      ALLOW_CONNECT='TRUE';
    'VSS_CM53':
      PIN_NUMBER='(0,0,0,0,0,0,0,0,0,0,0,0,0,0,0,0,0,0,0,0,0,0,0,0,0,0,0,0,0,0,0~
,0,0,0,0,0,0,CM53,0,0)';
      PINUSE='POWER';
      NO_LOAD_CHECK='Both';
      NO_IO_CHECK='Both';
      NO_ASSERT_CHECK='TRUE';
      NO_DIR_CHECK='TRUE';
      ALLOW_CONNECT='TRUE';
    'VSS_CM57':
      PIN_NUMBER='(0,0,0,0,0,0,0,0,0,0,0,0,0,0,0,0,0,0,0,0,0,0,0,0,0,0,0,0,0,0,0~
,0,0,0,0,0,0,CM57,0,0)';
      PINUSE='POWER';
      NO_LOAD_CHECK='Both';
      NO_IO_CHECK='Both';
      NO_ASSERT_CHECK='TRUE';
      NO_DIR_CHECK='TRUE';
      ALLOW_CONNECT='TRUE';
    'VSS_CM59':
      PIN_NUMBER='(0,0,0,0,0,0,0,0,0,0,0,0,0,0,0,0,0,0,0,0,0,0,0,0,0,0,0,0,0,0,0~
,0,0,0,0,0,0,CM59,0,0)';
      PINUSE='POWER';
      NO_LOAD_CHECK='Both';
      NO_IO_CHECK='Both';
      NO_ASSERT_CHECK='TRUE';
      NO_DIR_CHECK='TRUE';
      ALLOW_CONNECT='TRUE';
    'VSS_CM68':
      PIN_NUMBER='(0,0,0,0,0,0,0,0,0,0,0,0,0,0,0,0,0,0,0,0,0,0,0,0,0,0,0,0,0,0,0~
,0,0,0,0,0,0,CM68,0,0)';
      PINUSE='POWER';
      NO_LOAD_CHECK='Both';
      NO_IO_CHECK='Both';
      NO_ASSERT_CHECK='TRUE';
      NO_DIR_CHECK='TRUE';
      ALLOW_CONNECT='TRUE';
    'VSS_CM71':
      PIN_NUMBER='(0,0,0,0,0,0,0,0,0,0,0,0,0,0,0,0,0,0,0,0,0,0,0,0,0,0,0,0,0,0,0~
,0,0,0,0,0,0,CM71,0,0)';
      PINUSE='POWER';
      NO_LOAD_CHECK='Both';
      NO_IO_CHECK='Both';
      NO_ASSERT_CHECK='TRUE';
      NO_DIR_CHECK='TRUE';
      ALLOW_CONNECT='TRUE';
    'VSS_CM73':
      PIN_NUMBER='(0,0,0,0,0,0,0,0,0,0,0,0,0,0,0,0,0,0,0,0,0,0,0,0,0,0,0,0,0,0,0~
,0,0,0,0,0,0,CM73,0,0)';
      PINUSE='POWER';
      NO_LOAD_CHECK='Both';
      NO_IO_CHECK='Both';
      NO_ASSERT_CHECK='TRUE';
      NO_DIR_CHECK='TRUE';
      ALLOW_CONNECT='TRUE';
    'VSS_CN1':
      PIN_NUMBER='(0,0,0,0,0,0,0,0,0,0,0,0,0,0,0,0,0,0,0,0,0,0,0,0,0,0,0,0,0,0,0~
,0,0,0,0,0,0,CN1,0,0)';
      PINUSE='POWER';
      NO_LOAD_CHECK='Both';
      NO_IO_CHECK='Both';
      NO_ASSERT_CHECK='TRUE';
      NO_DIR_CHECK='TRUE';
      ALLOW_CONNECT='TRUE';
    'VSS_CN6':
      PIN_NUMBER='(0,0,0,0,0,0,0,0,0,0,0,0,0,0,0,0,0,0,0,0,0,0,0,0,0,0,0,0,0,0,0~
,0,0,0,0,0,0,CN6,0,0)';
      PINUSE='POWER';
      NO_LOAD_CHECK='Both';
      NO_IO_CHECK='Both';
      NO_ASSERT_CHECK='TRUE';
      NO_DIR_CHECK='TRUE';
      ALLOW_CONNECT='TRUE';
    'VSS_CN8':
      PIN_NUMBER='(0,0,0,0,0,0,0,0,0,0,0,0,0,0,0,0,0,0,0,0,0,0,0,0,0,0,0,0,0,0,0~
,0,0,0,0,0,0,CN8,0,0)';
      PINUSE='POWER';
      NO_LOAD_CHECK='Both';
      NO_IO_CHECK='Both';
      NO_ASSERT_CHECK='TRUE';
      NO_DIR_CHECK='TRUE';
      ALLOW_CONNECT='TRUE';
    'VSS_CN13':
      PIN_NUMBER='(0,0,0,0,0,0,0,0,0,0,0,0,0,0,0,0,0,0,0,0,0,0,0,0,0,0,0,0,0,0,0~
,0,0,0,0,0,0,CN13,0,0)';
      PINUSE='POWER';
      NO_LOAD_CHECK='Both';
      NO_IO_CHECK='Both';
      NO_ASSERT_CHECK='TRUE';
      NO_DIR_CHECK='TRUE';
      ALLOW_CONNECT='TRUE';
    'VSS_CN15':
      PIN_NUMBER='(0,0,0,0,0,0,0,0,0,0,0,0,0,0,0,0,0,0,0,0,0,0,0,0,0,0,0,0,0,0,0~
,0,0,0,0,0,0,CN15,0,0)';
      PINUSE='POWER';
      NO_LOAD_CHECK='Both';
      NO_IO_CHECK='Both';
      NO_ASSERT_CHECK='TRUE';
      NO_DIR_CHECK='TRUE';
      ALLOW_CONNECT='TRUE';
    'VSS_CN25':
      PIN_NUMBER='(0,0,0,0,0,0,0,0,0,0,0,0,0,0,0,0,0,0,0,0,0,0,0,0,0,0,0,0,0,0,0~
,0,0,0,0,0,0,CN25,0,0)';
      PINUSE='POWER';
      NO_LOAD_CHECK='Both';
      NO_IO_CHECK='Both';
      NO_ASSERT_CHECK='TRUE';
      NO_DIR_CHECK='TRUE';
      ALLOW_CONNECT='TRUE';
    'VSS_CN28':
      PIN_NUMBER='(0,0,0,0,0,0,0,0,0,0,0,0,0,0,0,0,0,0,0,0,0,0,0,0,0,0,0,0,0,0,0~
,0,0,0,0,0,0,CN28,0,0)';
      PINUSE='POWER';
      NO_LOAD_CHECK='Both';
      NO_IO_CHECK='Both';
      NO_ASSERT_CHECK='TRUE';
      NO_DIR_CHECK='TRUE';
      ALLOW_CONNECT='TRUE';
    'VSS_CN31':
      PIN_NUMBER='(0,0,0,0,0,0,0,0,0,0,0,0,0,0,0,0,0,0,0,0,0,0,0,0,0,0,0,0,0,0,0~
,0,0,0,0,0,0,CN31,0,0)';
      PINUSE='POWER';
      NO_LOAD_CHECK='Both';
      NO_IO_CHECK='Both';
      NO_ASSERT_CHECK='TRUE';
      NO_DIR_CHECK='TRUE';
      ALLOW_CONNECT='TRUE';
    'VSS_CN34':
      PIN_NUMBER='(0,0,0,0,0,0,0,0,0,0,0,0,0,0,0,0,0,0,0,0,0,0,0,0,0,0,0,0,0,0,0~
,0,0,0,0,0,0,CN34,0,0)';
      PINUSE='POWER';
      NO_LOAD_CHECK='Both';
      NO_IO_CHECK='Both';
      NO_ASSERT_CHECK='TRUE';
      NO_DIR_CHECK='TRUE';
      ALLOW_CONNECT='TRUE';
    'VSS_CN42':
      PIN_NUMBER='(0,0,0,0,0,0,0,0,0,0,0,0,0,0,0,0,0,0,0,0,0,0,0,0,0,0,0,0,0,0,0~
,0,0,0,0,0,0,CN42,0,0)';
      PINUSE='POWER';
      NO_LOAD_CHECK='Both';
      NO_IO_CHECK='Both';
      NO_ASSERT_CHECK='TRUE';
      NO_DIR_CHECK='TRUE';
      ALLOW_CONNECT='TRUE';
    'VSS_CN45':
      PIN_NUMBER='(0,0,0,0,0,0,0,0,0,0,0,0,0,0,0,0,0,0,0,0,0,0,0,0,0,0,0,0,0,0,0~
,0,0,0,0,0,0,CN45,0,0)';
      PINUSE='POWER';
      NO_LOAD_CHECK='Both';
      NO_IO_CHECK='Both';
      NO_ASSERT_CHECK='TRUE';
      NO_DIR_CHECK='TRUE';
      ALLOW_CONNECT='TRUE';
    'VSS_CN48':
      PIN_NUMBER='(0,0,0,0,0,0,0,0,0,0,0,0,0,0,0,0,0,0,0,0,0,0,0,0,0,0,0,0,0,0,0~
,0,0,0,0,0,0,CN48,0,0)';
      PINUSE='POWER';
      NO_LOAD_CHECK='Both';
      NO_IO_CHECK='Both';
      NO_ASSERT_CHECK='TRUE';
      NO_DIR_CHECK='TRUE';
      ALLOW_CONNECT='TRUE';
    'VSS_CN51':
      PIN_NUMBER='(0,0,0,0,0,0,0,0,0,0,0,0,0,0,0,0,0,0,0,0,0,0,0,0,0,0,0,0,0,0,0~
,0,0,0,0,0,0,CN51,0,0)';
      PINUSE='POWER';
      NO_LOAD_CHECK='Both';
      NO_IO_CHECK='Both';
      NO_ASSERT_CHECK='TRUE';
      NO_DIR_CHECK='TRUE';
      ALLOW_CONNECT='TRUE';
    'VSS_CN61':
      PIN_NUMBER='(0,0,0,0,0,0,0,0,0,0,0,0,0,0,0,0,0,0,0,0,0,0,0,0,0,0,0,0,0,0,0~
,0,0,0,0,0,0,CN61,0,0)';
      PINUSE='POWER';
      NO_LOAD_CHECK='Both';
      NO_IO_CHECK='Both';
      NO_ASSERT_CHECK='TRUE';
      NO_DIR_CHECK='TRUE';
      ALLOW_CONNECT='TRUE';
    'VSS_CN63':
      PIN_NUMBER='(0,0,0,0,0,0,0,0,0,0,0,0,0,0,0,0,0,0,0,0,0,0,0,0,0,0,0,0,0,0,0~
,0,0,0,0,0,0,CN63,0,0)';
      PINUSE='POWER';
      NO_LOAD_CHECK='Both';
      NO_IO_CHECK='Both';
      NO_ASSERT_CHECK='TRUE';
      NO_DIR_CHECK='TRUE';
      ALLOW_CONNECT='TRUE';
    'VSS_CN68':
      PIN_NUMBER='(0,0,0,0,0,0,0,0,0,0,0,0,0,0,0,0,0,0,0,0,0,0,0,0,0,0,0,0,0,0,0~
,0,0,0,0,0,0,CN68,0,0)';
      PINUSE='POWER';
      NO_LOAD_CHECK='Both';
      NO_IO_CHECK='Both';
      NO_ASSERT_CHECK='TRUE';
      NO_DIR_CHECK='TRUE';
      ALLOW_CONNECT='TRUE';
    'VSS_CN70':
      PIN_NUMBER='(0,0,0,0,0,0,0,0,0,0,0,0,0,0,0,0,0,0,0,0,0,0,0,0,0,0,0,0,0,0,0~
,0,0,0,0,0,0,CN70,0,0)';
      PINUSE='POWER';
      NO_LOAD_CHECK='Both';
      NO_IO_CHECK='Both';
      NO_ASSERT_CHECK='TRUE';
      NO_DIR_CHECK='TRUE';
      ALLOW_CONNECT='TRUE';
    'VSS_CN75':
      PIN_NUMBER='(0,0,0,0,0,0,0,0,0,0,0,0,0,0,0,0,0,0,0,0,0,0,0,0,0,0,0,0,0,0,0~
,0,0,0,0,0,0,CN75,0,0)';
      PINUSE='POWER';
      NO_LOAD_CHECK='Both';
      NO_IO_CHECK='Both';
      NO_ASSERT_CHECK='TRUE';
      NO_DIR_CHECK='TRUE';
      ALLOW_CONNECT='TRUE';
    'VSS_CP3':
      PIN_NUMBER='(0,0,0,0,0,0,0,0,0,0,0,0,0,0,0,0,0,0,0,0,0,0,0,0,0,0,0,0,0,0,0~
,0,0,0,0,0,0,CP3,0,0)';
      PINUSE='POWER';
      NO_LOAD_CHECK='Both';
      NO_IO_CHECK='Both';
      NO_ASSERT_CHECK='TRUE';
      NO_DIR_CHECK='TRUE';
      ALLOW_CONNECT='TRUE';
    'VSS_CP5':
      PIN_NUMBER='(0,0,0,0,0,0,0,0,0,0,0,0,0,0,0,0,0,0,0,0,0,0,0,0,0,0,0,0,0,0,0~
,0,0,0,0,0,0,CP5,0,0)';
      PINUSE='POWER';
      NO_LOAD_CHECK='Both';
      NO_IO_CHECK='Both';
      NO_ASSERT_CHECK='TRUE';
      NO_DIR_CHECK='TRUE';
      ALLOW_CONNECT='TRUE';
    'VSS_CP8':
      PIN_NUMBER='(0,0,0,0,0,0,0,0,0,0,0,0,0,0,0,0,0,0,0,0,0,0,0,0,0,0,0,0,0,0,0~
,0,0,0,0,0,0,CP8,0,0)';
      PINUSE='POWER';
      NO_LOAD_CHECK='Both';
      NO_IO_CHECK='Both';
      NO_ASSERT_CHECK='TRUE';
      NO_DIR_CHECK='TRUE';
      ALLOW_CONNECT='TRUE';
    'VSS_CP10':
      PIN_NUMBER='(0,0,0,0,0,0,0,0,0,0,0,0,0,0,0,0,0,0,0,0,0,0,0,0,0,0,0,0,0,0,0~
,0,0,0,0,0,0,CP10,0,0)';
      PINUSE='POWER';
      NO_LOAD_CHECK='Both';
      NO_IO_CHECK='Both';
      NO_ASSERT_CHECK='TRUE';
      NO_DIR_CHECK='TRUE';
      ALLOW_CONNECT='TRUE';
    'VSS_CP12':
      PIN_NUMBER='(0,0,0,0,0,0,0,0,0,0,0,0,0,0,0,0,0,0,0,0,0,0,0,0,0,0,0,0,0,0,0~
,0,0,0,0,0,0,CP12,0,0)';
      PINUSE='POWER';
      NO_LOAD_CHECK='Both';
      NO_IO_CHECK='Both';
      NO_ASSERT_CHECK='TRUE';
      NO_DIR_CHECK='TRUE';
      ALLOW_CONNECT='TRUE';
    'VSS_CP15':
      PIN_NUMBER='(0,0,0,0,0,0,0,0,0,0,0,0,0,0,0,0,0,0,0,0,0,0,0,0,0,0,0,0,0,0,0~
,0,0,0,0,0,0,CP15,0,0)';
      PINUSE='POWER';
      NO_LOAD_CHECK='Both';
      NO_IO_CHECK='Both';
      NO_ASSERT_CHECK='TRUE';
      NO_DIR_CHECK='TRUE';
      ALLOW_CONNECT='TRUE';
    'VSS_CP17':
      PIN_NUMBER='(0,0,0,0,0,0,0,0,0,0,0,0,0,0,0,0,0,0,0,0,0,0,0,0,0,0,0,0,0,0,0~
,0,0,0,0,0,0,CP17,0,0)';
      PINUSE='POWER';
      NO_LOAD_CHECK='Both';
      NO_IO_CHECK='Both';
      NO_ASSERT_CHECK='TRUE';
      NO_DIR_CHECK='TRUE';
      ALLOW_CONNECT='TRUE';
    'VSS_CP19':
      PIN_NUMBER='(0,0,0,0,0,0,0,0,0,0,0,0,0,0,0,0,0,0,0,0,0,0,0,0,0,0,0,0,0,0,0~
,0,0,0,0,0,0,CP19,0,0)';
      PINUSE='POWER';
      NO_LOAD_CHECK='Both';
      NO_IO_CHECK='Both';
      NO_ASSERT_CHECK='TRUE';
      NO_DIR_CHECK='TRUE';
      ALLOW_CONNECT='TRUE';
    'VSS_CP22':
      PIN_NUMBER='(0,0,0,0,0,0,0,0,0,0,0,0,0,0,0,0,0,0,0,0,0,0,0,0,0,0,0,0,0,0,0~
,0,0,0,0,0,0,0,CP22,0)';
      PINUSE='POWER';
      NO_LOAD_CHECK='Both';
      NO_IO_CHECK='Both';
      NO_ASSERT_CHECK='TRUE';
      NO_DIR_CHECK='TRUE';
      ALLOW_CONNECT='TRUE';
    'VSS_CP42':
      PIN_NUMBER='(0,0,0,0,0,0,0,0,0,0,0,0,0,0,0,0,0,0,0,0,0,0,0,0,0,0,0,0,0,0,0~
,0,0,0,0,0,0,0,CP42,0)';
      PINUSE='POWER';
      NO_LOAD_CHECK='Both';
      NO_IO_CHECK='Both';
      NO_ASSERT_CHECK='TRUE';
      NO_DIR_CHECK='TRUE';
      ALLOW_CONNECT='TRUE';
    'VSS_CP45':
      PIN_NUMBER='(0,0,0,0,0,0,0,0,0,0,0,0,0,0,0,0,0,0,0,0,0,0,0,0,0,0,0,0,0,0,0~
,0,0,0,0,0,0,0,CP45,0)';
      PINUSE='POWER';
      NO_LOAD_CHECK='Both';
      NO_IO_CHECK='Both';
      NO_ASSERT_CHECK='TRUE';
      NO_DIR_CHECK='TRUE';
      ALLOW_CONNECT='TRUE';
    'VSS_CP48':
      PIN_NUMBER='(0,0,0,0,0,0,0,0,0,0,0,0,0,0,0,0,0,0,0,0,0,0,0,0,0,0,0,0,0,0,0~
,0,0,0,0,0,0,0,CP48,0)';
      PINUSE='POWER';
      NO_LOAD_CHECK='Both';
      NO_IO_CHECK='Both';
      NO_ASSERT_CHECK='TRUE';
      NO_DIR_CHECK='TRUE';
      ALLOW_CONNECT='TRUE';
    'VSS_CP51':
      PIN_NUMBER='(0,0,0,0,0,0,0,0,0,0,0,0,0,0,0,0,0,0,0,0,0,0,0,0,0,0,0,0,0,0,0~
,0,0,0,0,0,0,0,CP51,0)';
      PINUSE='POWER';
      NO_LOAD_CHECK='Both';
      NO_IO_CHECK='Both';
      NO_ASSERT_CHECK='TRUE';
      NO_DIR_CHECK='TRUE';
      ALLOW_CONNECT='TRUE';
    'VSS_CP54':
      PIN_NUMBER='(0,0,0,0,0,0,0,0,0,0,0,0,0,0,0,0,0,0,0,0,0,0,0,0,0,0,0,0,0,0,0~
,0,0,0,0,0,0,0,CP54,0)';
      PINUSE='POWER';
      NO_LOAD_CHECK='Both';
      NO_IO_CHECK='Both';
      NO_ASSERT_CHECK='TRUE';
      NO_DIR_CHECK='TRUE';
      ALLOW_CONNECT='TRUE';
    'VSS_CP71':
      PIN_NUMBER='(0,0,0,0,0,0,0,0,0,0,0,0,0,0,0,0,0,0,0,0,0,0,0,0,0,0,0,0,0,0,0~
,0,0,0,0,0,0,0,CP71,0)';
      PINUSE='POWER';
      NO_LOAD_CHECK='Both';
      NO_IO_CHECK='Both';
      NO_ASSERT_CHECK='TRUE';
      NO_DIR_CHECK='TRUE';
      ALLOW_CONNECT='TRUE';
    'VSS_CP73':
      PIN_NUMBER='(0,0,0,0,0,0,0,0,0,0,0,0,0,0,0,0,0,0,0,0,0,0,0,0,0,0,0,0,0,0,0~
,0,0,0,0,0,0,0,CP73,0)';
      PINUSE='POWER';
      NO_LOAD_CHECK='Both';
      NO_IO_CHECK='Both';
      NO_ASSERT_CHECK='TRUE';
      NO_DIR_CHECK='TRUE';
      ALLOW_CONNECT='TRUE';
    'VSS_CR1':
      PIN_NUMBER='(0,0,0,0,0,0,0,0,0,0,0,0,0,0,0,0,0,0,0,0,0,0,0,0,0,0,0,0,0,0,0~
,0,0,0,0,0,0,0,CR1,0)';
      PINUSE='POWER';
      NO_LOAD_CHECK='Both';
      NO_IO_CHECK='Both';
      NO_ASSERT_CHECK='TRUE';
      NO_DIR_CHECK='TRUE';
      ALLOW_CONNECT='TRUE';
    'VSS_CR4':
      PIN_NUMBER='(0,0,0,0,0,0,0,0,0,0,0,0,0,0,0,0,0,0,0,0,0,0,0,0,0,0,0,0,0,0,0~
,0,0,0,0,0,0,0,CR4,0)';
      PINUSE='POWER';
      NO_LOAD_CHECK='Both';
      NO_IO_CHECK='Both';
      NO_ASSERT_CHECK='TRUE';
      NO_DIR_CHECK='TRUE';
      ALLOW_CONNECT='TRUE';
    'VSS_CR6':
      PIN_NUMBER='(0,0,0,0,0,0,0,0,0,0,0,0,0,0,0,0,0,0,0,0,0,0,0,0,0,0,0,0,0,0,0~
,0,0,0,0,0,0,0,CR6,0)';
      PINUSE='POWER';
      NO_LOAD_CHECK='Both';
      NO_IO_CHECK='Both';
      NO_ASSERT_CHECK='TRUE';
      NO_DIR_CHECK='TRUE';
      ALLOW_CONNECT='TRUE';
    'VSS_CR22':
      PIN_NUMBER='(0,0,0,0,0,0,0,0,0,0,0,0,0,0,0,0,0,0,0,0,0,0,0,0,0,0,0,0,0,0,0~
,0,0,0,0,0,0,0,CR22,0)';
      PINUSE='POWER';
      NO_LOAD_CHECK='Both';
      NO_IO_CHECK='Both';
      NO_ASSERT_CHECK='TRUE';
      NO_DIR_CHECK='TRUE';
      ALLOW_CONNECT='TRUE';
    'VSS_CR25':
      PIN_NUMBER='(0,0,0,0,0,0,0,0,0,0,0,0,0,0,0,0,0,0,0,0,0,0,0,0,0,0,0,0,0,0,0~
,0,0,0,0,0,0,0,CR25,0)';
      PINUSE='POWER';
      NO_LOAD_CHECK='Both';
      NO_IO_CHECK='Both';
      NO_ASSERT_CHECK='TRUE';
      NO_DIR_CHECK='TRUE';
      ALLOW_CONNECT='TRUE';
    'VSS_CR28':
      PIN_NUMBER='(0,0,0,0,0,0,0,0,0,0,0,0,0,0,0,0,0,0,0,0,0,0,0,0,0,0,0,0,0,0,0~
,0,0,0,0,0,0,0,CR28,0)';
      PINUSE='POWER';
      NO_LOAD_CHECK='Both';
      NO_IO_CHECK='Both';
      NO_ASSERT_CHECK='TRUE';
      NO_DIR_CHECK='TRUE';
      ALLOW_CONNECT='TRUE';
    'VSS_CR31':
      PIN_NUMBER='(0,0,0,0,0,0,0,0,0,0,0,0,0,0,0,0,0,0,0,0,0,0,0,0,0,0,0,0,0,0,0~
,0,0,0,0,0,0,0,CR31,0)';
      PINUSE='POWER';
      NO_LOAD_CHECK='Both';
      NO_IO_CHECK='Both';
      NO_ASSERT_CHECK='TRUE';
      NO_DIR_CHECK='TRUE';
      ALLOW_CONNECT='TRUE';
    'VSS_CR34':
      PIN_NUMBER='(0,0,0,0,0,0,0,0,0,0,0,0,0,0,0,0,0,0,0,0,0,0,0,0,0,0,0,0,0,0,0~
,0,0,0,0,0,0,0,CR34,0)';
      PINUSE='POWER';
      NO_LOAD_CHECK='Both';
      NO_IO_CHECK='Both';
      NO_ASSERT_CHECK='TRUE';
      NO_DIR_CHECK='TRUE';
      ALLOW_CONNECT='TRUE';
    'VSS_CR48':
      PIN_NUMBER='(0,0,0,0,0,0,0,0,0,0,0,0,0,0,0,0,0,0,0,0,0,0,0,0,0,0,0,0,0,0,0~
,0,0,0,0,0,0,0,CR48,0)';
      PINUSE='POWER';
      NO_LOAD_CHECK='Both';
      NO_IO_CHECK='Both';
      NO_ASSERT_CHECK='TRUE';
      NO_DIR_CHECK='TRUE';
      ALLOW_CONNECT='TRUE';
    'VSS_CR51':
      PIN_NUMBER='(0,0,0,0,0,0,0,0,0,0,0,0,0,0,0,0,0,0,0,0,0,0,0,0,0,0,0,0,0,0,0~
,0,0,0,0,0,0,0,CR51,0)';
      PINUSE='POWER';
      NO_LOAD_CHECK='Both';
      NO_IO_CHECK='Both';
      NO_ASSERT_CHECK='TRUE';
      NO_DIR_CHECK='TRUE';
      ALLOW_CONNECT='TRUE';
    'VSS_CR54':
      PIN_NUMBER='(0,0,0,0,0,0,0,0,0,0,0,0,0,0,0,0,0,0,0,0,0,0,0,0,0,0,0,0,0,0,0~
,0,0,0,0,0,0,0,CR54,0)';
      PINUSE='POWER';
      NO_LOAD_CHECK='Both';
      NO_IO_CHECK='Both';
      NO_ASSERT_CHECK='TRUE';
      NO_DIR_CHECK='TRUE';
      ALLOW_CONNECT='TRUE';
    'VSS_CR56':
      PIN_NUMBER='(0,0,0,0,0,0,0,0,0,0,0,0,0,0,0,0,0,0,0,0,0,0,0,0,0,0,0,0,0,0,0~
,0,0,0,0,0,0,0,CR56,0)';
      PINUSE='POWER';
      NO_LOAD_CHECK='Both';
      NO_IO_CHECK='Both';
      NO_ASSERT_CHECK='TRUE';
      NO_DIR_CHECK='TRUE';
      ALLOW_CONNECT='TRUE';
    'VSS_CR58':
      PIN_NUMBER='(0,0,0,0,0,0,0,0,0,0,0,0,0,0,0,0,0,0,0,0,0,0,0,0,0,0,0,0,0,0,0~
,0,0,0,0,0,0,0,CR58,0)';
      PINUSE='POWER';
      NO_LOAD_CHECK='Both';
      NO_IO_CHECK='Both';
      NO_ASSERT_CHECK='TRUE';
      NO_DIR_CHECK='TRUE';
      ALLOW_CONNECT='TRUE';
    'VSS_CR75':
      PIN_NUMBER='(0,0,0,0,0,0,0,0,0,0,0,0,0,0,0,0,0,0,0,0,0,0,0,0,0,0,0,0,0,0,0~
,0,0,0,0,0,0,0,CR75,0)';
      PINUSE='POWER';
      NO_LOAD_CHECK='Both';
      NO_IO_CHECK='Both';
      NO_ASSERT_CHECK='TRUE';
      NO_DIR_CHECK='TRUE';
      ALLOW_CONNECT='TRUE';
    'VSS_CT3':
      PIN_NUMBER='(0,0,0,0,0,0,0,0,0,0,0,0,0,0,0,0,0,0,0,0,0,0,0,0,0,0,0,0,0,0,0~
,0,0,0,0,0,0,0,CT3,0)';
      PINUSE='POWER';
      NO_LOAD_CHECK='Both';
      NO_IO_CHECK='Both';
      NO_ASSERT_CHECK='TRUE';
      NO_DIR_CHECK='TRUE';
      ALLOW_CONNECT='TRUE';
    'VSS_CT8':
      PIN_NUMBER='(0,0,0,0,0,0,0,0,0,0,0,0,0,0,0,0,0,0,0,0,0,0,0,0,0,0,0,0,0,0,0~
,0,0,0,0,0,0,0,CT8,0)';
      PINUSE='POWER';
      NO_LOAD_CHECK='Both';
      NO_IO_CHECK='Both';
      NO_ASSERT_CHECK='TRUE';
      NO_DIR_CHECK='TRUE';
      ALLOW_CONNECT='TRUE';
    'VSS_CT10':
      PIN_NUMBER='(0,0,0,0,0,0,0,0,0,0,0,0,0,0,0,0,0,0,0,0,0,0,0,0,0,0,0,0,0,0,0~
,0,0,0,0,0,0,0,CT10,0)';
      PINUSE='POWER';
      NO_LOAD_CHECK='Both';
      NO_IO_CHECK='Both';
      NO_ASSERT_CHECK='TRUE';
      NO_DIR_CHECK='TRUE';
      ALLOW_CONNECT='TRUE';
    'VSS_CT15':
      PIN_NUMBER='(0,0,0,0,0,0,0,0,0,0,0,0,0,0,0,0,0,0,0,0,0,0,0,0,0,0,0,0,0,0,0~
,0,0,0,0,0,0,0,CT15,0)';
      PINUSE='POWER';
      NO_LOAD_CHECK='Both';
      NO_IO_CHECK='Both';
      NO_ASSERT_CHECK='TRUE';
      NO_DIR_CHECK='TRUE';
      ALLOW_CONNECT='TRUE';
    'VSS_CT48':
      PIN_NUMBER='(0,0,0,0,0,0,0,0,0,0,0,0,0,0,0,0,0,0,0,0,0,0,0,0,0,0,0,0,0,0,0~
,0,0,0,0,0,0,0,CT48,0)';
      PINUSE='POWER';
      NO_LOAD_CHECK='Both';
      NO_IO_CHECK='Both';
      NO_ASSERT_CHECK='TRUE';
      NO_DIR_CHECK='TRUE';
      ALLOW_CONNECT='TRUE';
    'VSS_CT73':
      PIN_NUMBER='(0,0,0,0,0,0,0,0,0,0,0,0,0,0,0,0,0,0,0,0,0,0,0,0,0,0,0,0,0,0,0~
,0,0,0,0,0,0,0,CT73,0)';
      PINUSE='POWER';
      NO_LOAD_CHECK='Both';
      NO_IO_CHECK='Both';
      NO_ASSERT_CHECK='TRUE';
      NO_DIR_CHECK='TRUE';
      ALLOW_CONNECT='TRUE';
    'VSS_CU1':
      PIN_NUMBER='(0,0,0,0,0,0,0,0,0,0,0,0,0,0,0,0,0,0,0,0,0,0,0,0,0,0,0,0,0,0,0~
,0,0,0,0,0,0,0,CU1,0)';
      PINUSE='POWER';
      NO_LOAD_CHECK='Both';
      NO_IO_CHECK='Both';
      NO_ASSERT_CHECK='TRUE';
      NO_DIR_CHECK='TRUE';
      ALLOW_CONNECT='TRUE';
    'VSS_CU22':
      PIN_NUMBER='(0,0,0,0,0,0,0,0,0,0,0,0,0,0,0,0,0,0,0,0,0,0,0,0,0,0,0,0,0,0,0~
,0,0,0,0,0,0,0,CU22,0)';
      PINUSE='POWER';
      NO_LOAD_CHECK='Both';
      NO_IO_CHECK='Both';
      NO_ASSERT_CHECK='TRUE';
      NO_DIR_CHECK='TRUE';
      ALLOW_CONNECT='TRUE';
    'VSS_CU25':
      PIN_NUMBER='(0,0,0,0,0,0,0,0,0,0,0,0,0,0,0,0,0,0,0,0,0,0,0,0,0,0,0,0,0,0,0~
,0,0,0,0,0,0,0,CU25,0)';
      PINUSE='POWER';
      NO_LOAD_CHECK='Both';
      NO_IO_CHECK='Both';
      NO_ASSERT_CHECK='TRUE';
      NO_DIR_CHECK='TRUE';
      ALLOW_CONNECT='TRUE';
    'VSS_CU28':
      PIN_NUMBER='(0,0,0,0,0,0,0,0,0,0,0,0,0,0,0,0,0,0,0,0,0,0,0,0,0,0,0,0,0,0,0~
,0,0,0,0,0,0,0,CU28,0)';
      PINUSE='POWER';
      NO_LOAD_CHECK='Both';
      NO_IO_CHECK='Both';
      NO_ASSERT_CHECK='TRUE';
      NO_DIR_CHECK='TRUE';
      ALLOW_CONNECT='TRUE';
    'VSS_CU56':
      PIN_NUMBER='(0,0,0,0,0,0,0,0,0,0,0,0,0,0,0,0,0,0,0,0,0,0,0,0,0,0,0,0,0,0,0~
,0,0,0,0,0,0,0,CU56,0)';
      PINUSE='POWER';
      NO_LOAD_CHECK='Both';
      NO_IO_CHECK='Both';
      NO_ASSERT_CHECK='TRUE';
      NO_DIR_CHECK='TRUE';
      ALLOW_CONNECT='TRUE';
    'VSS_CU61':
      PIN_NUMBER='(0,0,0,0,0,0,0,0,0,0,0,0,0,0,0,0,0,0,0,0,0,0,0,0,0,0,0,0,0,0,0~
,0,0,0,0,0,0,0,CU61,0)';
      PINUSE='POWER';
      NO_LOAD_CHECK='Both';
      NO_IO_CHECK='Both';
      NO_ASSERT_CHECK='TRUE';
      NO_DIR_CHECK='TRUE';
      ALLOW_CONNECT='TRUE';
    'VSS_CU63':
      PIN_NUMBER='(0,0,0,0,0,0,0,0,0,0,0,0,0,0,0,0,0,0,0,0,0,0,0,0,0,0,0,0,0,0,0~
,0,0,0,0,0,0,0,CU63,0)';
      PINUSE='POWER';
      NO_LOAD_CHECK='Both';
      NO_IO_CHECK='Both';
      NO_ASSERT_CHECK='TRUE';
      NO_DIR_CHECK='TRUE';
      ALLOW_CONNECT='TRUE';
    'VSS_CV5':
      PIN_NUMBER='(0,0,0,0,0,0,0,0,0,0,0,0,0,0,0,0,0,0,0,0,0,0,0,0,0,0,0,0,0,0,0~
,0,0,0,0,0,0,0,CV5,0)';
      PINUSE='POWER';
      NO_LOAD_CHECK='Both';
      NO_IO_CHECK='Both';
      NO_ASSERT_CHECK='TRUE';
      NO_DIR_CHECK='TRUE';
      ALLOW_CONNECT='TRUE';
    'VSS_CV8':
      PIN_NUMBER='(0,0,0,0,0,0,0,0,0,0,0,0,0,0,0,0,0,0,0,0,0,0,0,0,0,0,0,0,0,0,0~
,0,0,0,0,0,0,0,CV8,0)';
      PINUSE='POWER';
      NO_LOAD_CHECK='Both';
      NO_IO_CHECK='Both';
      NO_ASSERT_CHECK='TRUE';
      NO_DIR_CHECK='TRUE';
      ALLOW_CONNECT='TRUE';
    'VSS_CV10':
      PIN_NUMBER='(0,0,0,0,0,0,0,0,0,0,0,0,0,0,0,0,0,0,0,0,0,0,0,0,0,0,0,0,0,0,0~
,0,0,0,0,0,0,0,CV10,0)';
      PINUSE='POWER';
      NO_LOAD_CHECK='Both';
      NO_IO_CHECK='Both';
      NO_ASSERT_CHECK='TRUE';
      NO_DIR_CHECK='TRUE';
      ALLOW_CONNECT='TRUE';
    'VSS_CV12':
      PIN_NUMBER='(0,0,0,0,0,0,0,0,0,0,0,0,0,0,0,0,0,0,0,0,0,0,0,0,0,0,0,0,0,0,0~
,0,0,0,0,0,0,0,CV12,0)';
      PINUSE='POWER';
      NO_LOAD_CHECK='Both';
      NO_IO_CHECK='Both';
      NO_ASSERT_CHECK='TRUE';
      NO_DIR_CHECK='TRUE';
      ALLOW_CONNECT='TRUE';
    'VSS_CV15':
      PIN_NUMBER='(0,0,0,0,0,0,0,0,0,0,0,0,0,0,0,0,0,0,0,0,0,0,0,0,0,0,0,0,0,0,0~
,0,0,0,0,0,0,0,CV15,0)';
      PINUSE='POWER';
      NO_LOAD_CHECK='Both';
      NO_IO_CHECK='Both';
      NO_ASSERT_CHECK='TRUE';
      NO_DIR_CHECK='TRUE';
      ALLOW_CONNECT='TRUE';
    'VSS_CV34':
      PIN_NUMBER='(0,0,0,0,0,0,0,0,0,0,0,0,0,0,0,0,0,0,0,0,0,0,0,0,0,0,0,0,0,0,0~
,0,0,0,0,0,0,0,CV34,0)';
      PINUSE='POWER';
      NO_LOAD_CHECK='Both';
      NO_IO_CHECK='Both';
      NO_ASSERT_CHECK='TRUE';
      NO_DIR_CHECK='TRUE';
      ALLOW_CONNECT='TRUE';
    'VSS_CV37':
      PIN_NUMBER='(0,0,0,0,0,0,0,0,0,0,0,0,0,0,0,0,0,0,0,0,0,0,0,0,0,0,0,0,0,0,0~
,0,0,0,0,0,0,0,CV37,0)';
      PINUSE='POWER';
      NO_LOAD_CHECK='Both';
      NO_IO_CHECK='Both';
      NO_ASSERT_CHECK='TRUE';
      NO_DIR_CHECK='TRUE';
      ALLOW_CONNECT='TRUE';
    'VSS_CV39':
      PIN_NUMBER='(0,0,0,0,0,0,0,0,0,0,0,0,0,0,0,0,0,0,0,0,0,0,0,0,0,0,0,0,0,0,0~
,0,0,0,0,0,0,0,CV39,0)';
      PINUSE='POWER';
      NO_LOAD_CHECK='Both';
      NO_IO_CHECK='Both';
      NO_ASSERT_CHECK='TRUE';
      NO_DIR_CHECK='TRUE';
      ALLOW_CONNECT='TRUE';
    'VSS_CV42':
      PIN_NUMBER='(0,0,0,0,0,0,0,0,0,0,0,0,0,0,0,0,0,0,0,0,0,0,0,0,0,0,0,0,0,0,0~
,0,0,0,0,0,0,0,CV42,0)';
      PINUSE='POWER';
      NO_LOAD_CHECK='Both';
      NO_IO_CHECK='Both';
      NO_ASSERT_CHECK='TRUE';
      NO_DIR_CHECK='TRUE';
      ALLOW_CONNECT='TRUE';
    'VSS_CV45':
      PIN_NUMBER='(0,0,0,0,0,0,0,0,0,0,0,0,0,0,0,0,0,0,0,0,0,0,0,0,0,0,0,0,0,0,0~
,0,0,0,0,0,0,0,CV45,0)';
      PINUSE='POWER';
      NO_LOAD_CHECK='Both';
      NO_IO_CHECK='Both';
      NO_ASSERT_CHECK='TRUE';
      NO_DIR_CHECK='TRUE';
      ALLOW_CONNECT='TRUE';
    'VSS_CV64':
      PIN_NUMBER='(0,0,0,0,0,0,0,0,0,0,0,0,0,0,0,0,0,0,0,0,0,0,0,0,0,0,0,0,0,0,0~
,0,0,0,0,0,0,0,CV64,0)';
      PINUSE='POWER';
      NO_LOAD_CHECK='Both';
      NO_IO_CHECK='Both';
      NO_ASSERT_CHECK='TRUE';
      NO_DIR_CHECK='TRUE';
      ALLOW_CONNECT='TRUE';
    'VSS_CV66':
      PIN_NUMBER='(0,0,0,0,0,0,0,0,0,0,0,0,0,0,0,0,0,0,0,0,0,0,0,0,0,0,0,0,0,0,0~
,0,0,0,0,0,0,0,CV66,0)';
      PINUSE='POWER';
      NO_LOAD_CHECK='Both';
      NO_IO_CHECK='Both';
      NO_ASSERT_CHECK='TRUE';
      NO_DIR_CHECK='TRUE';
      ALLOW_CONNECT='TRUE';
    'VSS_CV68':
      PIN_NUMBER='(0,0,0,0,0,0,0,0,0,0,0,0,0,0,0,0,0,0,0,0,0,0,0,0,0,0,0,0,0,0,0~
,0,0,0,0,0,0,0,CV68,0)';
      PINUSE='POWER';
      NO_LOAD_CHECK='Both';
      NO_IO_CHECK='Both';
      NO_ASSERT_CHECK='TRUE';
      NO_DIR_CHECK='TRUE';
      ALLOW_CONNECT='TRUE';
    'VSS_CV71':
      PIN_NUMBER='(0,0,0,0,0,0,0,0,0,0,0,0,0,0,0,0,0,0,0,0,0,0,0,0,0,0,0,0,0,0,0~
,0,0,0,0,0,0,0,CV71,0)';
      PINUSE='POWER';
      NO_LOAD_CHECK='Both';
      NO_IO_CHECK='Both';
      NO_ASSERT_CHECK='TRUE';
      NO_DIR_CHECK='TRUE';
      ALLOW_CONNECT='TRUE';
    'VSS_CV73':
      PIN_NUMBER='(0,0,0,0,0,0,0,0,0,0,0,0,0,0,0,0,0,0,0,0,0,0,0,0,0,0,0,0,0,0,0~
,0,0,0,0,0,0,0,CV73,0)';
      PINUSE='POWER';
      NO_LOAD_CHECK='Both';
      NO_IO_CHECK='Both';
      NO_ASSERT_CHECK='TRUE';
      NO_DIR_CHECK='TRUE';
      ALLOW_CONNECT='TRUE';
    'VSS_CW22':
      PIN_NUMBER='(0,0,0,0,0,0,0,0,0,0,0,0,0,0,0,0,0,0,0,0,0,0,0,0,0,0,0,0,0,0,0~
,0,0,0,0,0,0,0,CW22,0)';
      PINUSE='POWER';
      NO_LOAD_CHECK='Both';
      NO_IO_CHECK='Both';
      NO_ASSERT_CHECK='TRUE';
      NO_DIR_CHECK='TRUE';
      ALLOW_CONNECT='TRUE';
    'VSS_CW25':
      PIN_NUMBER='(0,0,0,0,0,0,0,0,0,0,0,0,0,0,0,0,0,0,0,0,0,0,0,0,0,0,0,0,0,0,0~
,0,0,0,0,0,0,0,CW25,0)';
      PINUSE='POWER';
      NO_LOAD_CHECK='Both';
      NO_IO_CHECK='Both';
      NO_ASSERT_CHECK='TRUE';
      NO_DIR_CHECK='TRUE';
      ALLOW_CONNECT='TRUE';
    'VSS_CW28':
      PIN_NUMBER='(0,0,0,0,0,0,0,0,0,0,0,0,0,0,0,0,0,0,0,0,0,0,0,0,0,0,0,0,0,0,0~
,0,0,0,0,0,0,0,CW28,0)';
      PINUSE='POWER';
      NO_LOAD_CHECK='Both';
      NO_IO_CHECK='Both';
      NO_ASSERT_CHECK='TRUE';
      NO_DIR_CHECK='TRUE';
      ALLOW_CONNECT='TRUE';
    'VSS_CW31':
      PIN_NUMBER='(0,0,0,0,0,0,0,0,0,0,0,0,0,0,0,0,0,0,0,0,0,0,0,0,0,0,0,0,0,0,0~
,0,0,0,0,0,0,0,CW31,0)';
      PINUSE='POWER';
      NO_LOAD_CHECK='Both';
      NO_IO_CHECK='Both';
      NO_ASSERT_CHECK='TRUE';
      NO_DIR_CHECK='TRUE';
      ALLOW_CONNECT='TRUE';
    'VSS_CW34':
      PIN_NUMBER='(0,0,0,0,0,0,0,0,0,0,0,0,0,0,0,0,0,0,0,0,0,0,0,0,0,0,0,0,0,0,0~
,0,0,0,0,0,0,0,CW34,0)';
      PINUSE='POWER';
      NO_LOAD_CHECK='Both';
      NO_IO_CHECK='Both';
      NO_ASSERT_CHECK='TRUE';
      NO_DIR_CHECK='TRUE';
      ALLOW_CONNECT='TRUE';
    'VSS_CY32':
      PIN_NUMBER='(0,0,0,0,0,0,0,0,0,0,0,0,0,0,0,0,0,0,0,0,0,0,0,0,0,0,0,0,0,0,0~
,0,0,0,0,0,0,0,CY32,0)';
      PINUSE='POWER';
      NO_LOAD_CHECK='Both';
      NO_IO_CHECK='Both';
      NO_ASSERT_CHECK='TRUE';
      NO_DIR_CHECK='TRUE';
      ALLOW_CONNECT='TRUE';
    'VSS_CY47':
      PIN_NUMBER='(0,0,0,0,0,0,0,0,0,0,0,0,0,0,0,0,0,0,0,0,0,0,0,0,0,0,0,0,0,0,0~
,0,0,0,0,0,0,0,CY47,0)';
      PINUSE='POWER';
      NO_LOAD_CHECK='Both';
      NO_IO_CHECK='Both';
      NO_ASSERT_CHECK='TRUE';
      NO_DIR_CHECK='TRUE';
      ALLOW_CONNECT='TRUE';
    'VSS_CY48':
      PIN_NUMBER='(0,0,0,0,0,0,0,0,0,0,0,0,0,0,0,0,0,0,0,0,0,0,0,0,0,0,0,0,0,0,0~
,0,0,0,0,0,0,0,CY48,0)';
      PINUSE='POWER';
      NO_LOAD_CHECK='Both';
      NO_IO_CHECK='Both';
      NO_ASSERT_CHECK='TRUE';
      NO_DIR_CHECK='TRUE';
      ALLOW_CONNECT='TRUE';
    'VSS_CY64':
      PIN_NUMBER='(0,0,0,0,0,0,0,0,0,0,0,0,0,0,0,0,0,0,0,0,0,0,0,0,0,0,0,0,0,0,0~
,0,0,0,0,0,0,0,CY64,0)';
      PINUSE='POWER';
      NO_LOAD_CHECK='Both';
      NO_IO_CHECK='Both';
      NO_ASSERT_CHECK='TRUE';
      NO_DIR_CHECK='TRUE';
      ALLOW_CONNECT='TRUE';
    'VSS_CY66':
      PIN_NUMBER='(0,0,0,0,0,0,0,0,0,0,0,0,0,0,0,0,0,0,0,0,0,0,0,0,0,0,0,0,0,0,0~
,0,0,0,0,0,0,0,CY66,0)';
      PINUSE='POWER';
      NO_LOAD_CHECK='Both';
      NO_IO_CHECK='Both';
      NO_ASSERT_CHECK='TRUE';
      NO_DIR_CHECK='TRUE';
      ALLOW_CONNECT='TRUE';
    'VSS_CY68':
      PIN_NUMBER='(0,0,0,0,0,0,0,0,0,0,0,0,0,0,0,0,0,0,0,0,0,0,0,0,0,0,0,0,0,0,0~
,0,0,0,0,0,0,0,CY68,0)';
      PINUSE='POWER';
      NO_LOAD_CHECK='Both';
      NO_IO_CHECK='Both';
      NO_ASSERT_CHECK='TRUE';
      NO_DIR_CHECK='TRUE';
      ALLOW_CONNECT='TRUE';
    'VSS_DA13':
      PIN_NUMBER='(0,0,0,0,0,0,0,0,0,0,0,0,0,0,0,0,0,0,0,0,0,0,0,0,0,0,0,0,0,0,0~
,0,0,0,0,0,0,0,DA13,0)';
      PINUSE='POWER';
      NO_LOAD_CHECK='Both';
      NO_IO_CHECK='Both';
      NO_ASSERT_CHECK='TRUE';
      NO_DIR_CHECK='TRUE';
      ALLOW_CONNECT='TRUE';
    'VSS_DA15':
      PIN_NUMBER='(0,0,0,0,0,0,0,0,0,0,0,0,0,0,0,0,0,0,0,0,0,0,0,0,0,0,0,0,0,0,0~
,0,0,0,0,0,0,0,DA15,0)';
      PINUSE='POWER';
      NO_LOAD_CHECK='Both';
      NO_IO_CHECK='Both';
      NO_ASSERT_CHECK='TRUE';
      NO_DIR_CHECK='TRUE';
      ALLOW_CONNECT='TRUE';
    'VSS_DA18':
      PIN_NUMBER='(0,0,0,0,0,0,0,0,0,0,0,0,0,0,0,0,0,0,0,0,0,0,0,0,0,0,0,0,0,0,0~
,0,0,0,0,0,0,0,DA18,0)';
      PINUSE='POWER';
      NO_LOAD_CHECK='Both';
      NO_IO_CHECK='Both';
      NO_ASSERT_CHECK='TRUE';
      NO_DIR_CHECK='TRUE';
      ALLOW_CONNECT='TRUE';
    'VSS_DA20':
      PIN_NUMBER='(0,0,0,0,0,0,0,0,0,0,0,0,0,0,0,0,0,0,0,0,0,0,0,0,0,0,0,0,0,0,0~
,0,0,0,0,0,0,0,DA20,0)';
      PINUSE='POWER';
      NO_LOAD_CHECK='Both';
      NO_IO_CHECK='Both';
      NO_ASSERT_CHECK='TRUE';
      NO_DIR_CHECK='TRUE';
      ALLOW_CONNECT='TRUE';
    'VSS_DA45':
      PIN_NUMBER='(0,0,0,0,0,0,0,0,0,0,0,0,0,0,0,0,0,0,0,0,0,0,0,0,0,0,0,0,0,0,0~
,0,0,0,0,0,0,0,DA45,0)';
      PINUSE='POWER';
      NO_LOAD_CHECK='Both';
      NO_IO_CHECK='Both';
      NO_ASSERT_CHECK='TRUE';
      NO_DIR_CHECK='TRUE';
      ALLOW_CONNECT='TRUE';
    'VSS_DA48':
      PIN_NUMBER='(0,0,0,0,0,0,0,0,0,0,0,0,0,0,0,0,0,0,0,0,0,0,0,0,0,0,0,0,0,0,0~
,0,0,0,0,0,0,0,DA48,0)';
      PINUSE='POWER';
      NO_LOAD_CHECK='Both';
      NO_IO_CHECK='Both';
      NO_ASSERT_CHECK='TRUE';
      NO_DIR_CHECK='TRUE';
      ALLOW_CONNECT='TRUE';
    'VSS_DA51':
      PIN_NUMBER='(0,0,0,0,0,0,0,0,0,0,0,0,0,0,0,0,0,0,0,0,0,0,0,0,0,0,0,0,0,0,0~
,0,0,0,0,0,0,0,DA51,0)';
      PINUSE='POWER';
      NO_LOAD_CHECK='Both';
      NO_IO_CHECK='Both';
      NO_ASSERT_CHECK='TRUE';
      NO_DIR_CHECK='TRUE';
      ALLOW_CONNECT='TRUE';
    'VSS_DA54':
      PIN_NUMBER='(0,0,0,0,0,0,0,0,0,0,0,0,0,0,0,0,0,0,0,0,0,0,0,0,0,0,0,0,0,0,0~
,0,0,0,0,0,0,0,DA54,0)';
      PINUSE='POWER';
      NO_LOAD_CHECK='Both';
      NO_IO_CHECK='Both';
      NO_ASSERT_CHECK='TRUE';
      NO_DIR_CHECK='TRUE';
      ALLOW_CONNECT='TRUE';
    'VSS_CP25':
      PIN_NUMBER='(0,0,0,0,0,0,0,0,0,0,0,0,0,0,0,0,0,0,0,0,0,0,0,0,0,0,0,0,0,0,0~
,0,0,0,0,0,0,0,CP25,0)';
      PINUSE='POWER';
      NO_LOAD_CHECK='Both';
      NO_IO_CHECK='Both';
      NO_ASSERT_CHECK='TRUE';
      NO_DIR_CHECK='TRUE';
      ALLOW_CONNECT='TRUE';
    'VSS_CP28':
      PIN_NUMBER='(0,0,0,0,0,0,0,0,0,0,0,0,0,0,0,0,0,0,0,0,0,0,0,0,0,0,0,0,0,0,0~
,0,0,0,0,0,0,0,CP28,0)';
      PINUSE='POWER';
      NO_LOAD_CHECK='Both';
      NO_IO_CHECK='Both';
      NO_ASSERT_CHECK='TRUE';
      NO_DIR_CHECK='TRUE';
      ALLOW_CONNECT='TRUE';
    'VSS_CP31':
      PIN_NUMBER='(0,0,0,0,0,0,0,0,0,0,0,0,0,0,0,0,0,0,0,0,0,0,0,0,0,0,0,0,0,0,0~
,0,0,0,0,0,0,0,CP31,0)';
      PINUSE='POWER';
      NO_LOAD_CHECK='Both';
      NO_IO_CHECK='Both';
      NO_ASSERT_CHECK='TRUE';
      NO_DIR_CHECK='TRUE';
      ALLOW_CONNECT='TRUE';
    'VSS_CP34':
      PIN_NUMBER='(0,0,0,0,0,0,0,0,0,0,0,0,0,0,0,0,0,0,0,0,0,0,0,0,0,0,0,0,0,0,0~
,0,0,0,0,0,0,0,CP34,0)';
      PINUSE='POWER';
      NO_LOAD_CHECK='Both';
      NO_IO_CHECK='Both';
      NO_ASSERT_CHECK='TRUE';
      NO_DIR_CHECK='TRUE';
      ALLOW_CONNECT='TRUE';
    'VSS_CP37':
      PIN_NUMBER='(0,0,0,0,0,0,0,0,0,0,0,0,0,0,0,0,0,0,0,0,0,0,0,0,0,0,0,0,0,0,0~
,0,0,0,0,0,0,0,CP37,0)';
      PINUSE='POWER';
      NO_LOAD_CHECK='Both';
      NO_IO_CHECK='Both';
      NO_ASSERT_CHECK='TRUE';
      NO_DIR_CHECK='TRUE';
      ALLOW_CONNECT='TRUE';
    'VSS_CP39':
      PIN_NUMBER='(0,0,0,0,0,0,0,0,0,0,0,0,0,0,0,0,0,0,0,0,0,0,0,0,0,0,0,0,0,0,0~
,0,0,0,0,0,0,0,CP39,0)';
      PINUSE='POWER';
      NO_LOAD_CHECK='Both';
      NO_IO_CHECK='Both';
      NO_ASSERT_CHECK='TRUE';
      NO_DIR_CHECK='TRUE';
      ALLOW_CONNECT='TRUE';
    'VSS_CP57':
      PIN_NUMBER='(0,0,0,0,0,0,0,0,0,0,0,0,0,0,0,0,0,0,0,0,0,0,0,0,0,0,0,0,0,0,0~
,0,0,0,0,0,0,0,CP57,0)';
      PINUSE='POWER';
      NO_LOAD_CHECK='Both';
      NO_IO_CHECK='Both';
      NO_ASSERT_CHECK='TRUE';
      NO_DIR_CHECK='TRUE';
      ALLOW_CONNECT='TRUE';
    'VSS_CP59':
      PIN_NUMBER='(0,0,0,0,0,0,0,0,0,0,0,0,0,0,0,0,0,0,0,0,0,0,0,0,0,0,0,0,0,0,0~
,0,0,0,0,0,0,0,CP59,0)';
      PINUSE='POWER';
      NO_LOAD_CHECK='Both';
      NO_IO_CHECK='Both';
      NO_ASSERT_CHECK='TRUE';
      NO_DIR_CHECK='TRUE';
      ALLOW_CONNECT='TRUE';
    'VSS_CP61':
      PIN_NUMBER='(0,0,0,0,0,0,0,0,0,0,0,0,0,0,0,0,0,0,0,0,0,0,0,0,0,0,0,0,0,0,0~
,0,0,0,0,0,0,0,CP61,0)';
      PINUSE='POWER';
      NO_LOAD_CHECK='Both';
      NO_IO_CHECK='Both';
      NO_ASSERT_CHECK='TRUE';
      NO_DIR_CHECK='TRUE';
      ALLOW_CONNECT='TRUE';
    'VSS_CP64':
      PIN_NUMBER='(0,0,0,0,0,0,0,0,0,0,0,0,0,0,0,0,0,0,0,0,0,0,0,0,0,0,0,0,0,0,0~
,0,0,0,0,0,0,0,CP64,0)';
      PINUSE='POWER';
      NO_LOAD_CHECK='Both';
      NO_IO_CHECK='Both';
      NO_ASSERT_CHECK='TRUE';
      NO_DIR_CHECK='TRUE';
      ALLOW_CONNECT='TRUE';
    'VSS_CP66':
      PIN_NUMBER='(0,0,0,0,0,0,0,0,0,0,0,0,0,0,0,0,0,0,0,0,0,0,0,0,0,0,0,0,0,0,0~
,0,0,0,0,0,0,0,CP66,0)';
      PINUSE='POWER';
      NO_LOAD_CHECK='Both';
      NO_IO_CHECK='Both';
      NO_ASSERT_CHECK='TRUE';
      NO_DIR_CHECK='TRUE';
      ALLOW_CONNECT='TRUE';
    'VSS_CP68':
      PIN_NUMBER='(0,0,0,0,0,0,0,0,0,0,0,0,0,0,0,0,0,0,0,0,0,0,0,0,0,0,0,0,0,0,0~
,0,0,0,0,0,0,0,CP68,0)';
      PINUSE='POWER';
      NO_LOAD_CHECK='Both';
      NO_IO_CHECK='Both';
      NO_ASSERT_CHECK='TRUE';
      NO_DIR_CHECK='TRUE';
      ALLOW_CONNECT='TRUE';
    'VSS_CR8':
      PIN_NUMBER='(0,0,0,0,0,0,0,0,0,0,0,0,0,0,0,0,0,0,0,0,0,0,0,0,0,0,0,0,0,0,0~
,0,0,0,0,0,0,0,CR8,0)';
      PINUSE='POWER';
      NO_LOAD_CHECK='Both';
      NO_IO_CHECK='Both';
      NO_ASSERT_CHECK='TRUE';
      NO_DIR_CHECK='TRUE';
      ALLOW_CONNECT='TRUE';
    'VSS_CR11':
      PIN_NUMBER='(0,0,0,0,0,0,0,0,0,0,0,0,0,0,0,0,0,0,0,0,0,0,0,0,0,0,0,0,0,0,0~
,0,0,0,0,0,0,0,CR11,0)';
      PINUSE='POWER';
      NO_LOAD_CHECK='Both';
      NO_IO_CHECK='Both';
      NO_ASSERT_CHECK='TRUE';
      NO_DIR_CHECK='TRUE';
      ALLOW_CONNECT='TRUE';
    'VSS_CR13':
      PIN_NUMBER='(0,0,0,0,0,0,0,0,0,0,0,0,0,0,0,0,0,0,0,0,0,0,0,0,0,0,0,0,0,0,0~
,0,0,0,0,0,0,0,CR13,0)';
      PINUSE='POWER';
      NO_LOAD_CHECK='Both';
      NO_IO_CHECK='Both';
      NO_ASSERT_CHECK='TRUE';
      NO_DIR_CHECK='TRUE';
      ALLOW_CONNECT='TRUE';
    'VSS_CR15':
      PIN_NUMBER='(0,0,0,0,0,0,0,0,0,0,0,0,0,0,0,0,0,0,0,0,0,0,0,0,0,0,0,0,0,0,0~
,0,0,0,0,0,0,0,CR15,0)';
      PINUSE='POWER';
      NO_LOAD_CHECK='Both';
      NO_IO_CHECK='Both';
      NO_ASSERT_CHECK='TRUE';
      NO_DIR_CHECK='TRUE';
      ALLOW_CONNECT='TRUE';
    'VSS_CR18':
      PIN_NUMBER='(0,0,0,0,0,0,0,0,0,0,0,0,0,0,0,0,0,0,0,0,0,0,0,0,0,0,0,0,0,0,0~
,0,0,0,0,0,0,0,CR18,0)';
      PINUSE='POWER';
      NO_LOAD_CHECK='Both';
      NO_IO_CHECK='Both';
      NO_ASSERT_CHECK='TRUE';
      NO_DIR_CHECK='TRUE';
      ALLOW_CONNECT='TRUE';
    'VSS_CR20':
      PIN_NUMBER='(0,0,0,0,0,0,0,0,0,0,0,0,0,0,0,0,0,0,0,0,0,0,0,0,0,0,0,0,0,0,0~
,0,0,0,0,0,0,0,CR20,0)';
      PINUSE='POWER';
      NO_LOAD_CHECK='Both';
      NO_IO_CHECK='Both';
      NO_ASSERT_CHECK='TRUE';
      NO_DIR_CHECK='TRUE';
      ALLOW_CONNECT='TRUE';
    'VSS_CR35':
      PIN_NUMBER='(0,0,0,0,0,0,0,0,0,0,0,0,0,0,0,0,0,0,0,0,0,0,0,0,0,0,0,0,0,0,0~
,0,0,0,0,0,0,0,CR35,0)';
      PINUSE='POWER';
      NO_LOAD_CHECK='Both';
      NO_IO_CHECK='Both';
      NO_ASSERT_CHECK='TRUE';
      NO_DIR_CHECK='TRUE';
      ALLOW_CONNECT='TRUE';
    'VSS_CR36':
      PIN_NUMBER='(0,0,0,0,0,0,0,0,0,0,0,0,0,0,0,0,0,0,0,0,0,0,0,0,0,0,0,0,0,0,0~
,0,0,0,0,0,0,0,CR36,0)';
      PINUSE='POWER';
      NO_LOAD_CHECK='Both';
      NO_IO_CHECK='Both';
      NO_ASSERT_CHECK='TRUE';
      NO_DIR_CHECK='TRUE';
      ALLOW_CONNECT='TRUE';
    'VSS_CR40':
      PIN_NUMBER='(0,0,0,0,0,0,0,0,0,0,0,0,0,0,0,0,0,0,0,0,0,0,0,0,0,0,0,0,0,0,0~
,0,0,0,0,0,0,0,CR40,0)';
      PINUSE='POWER';
      NO_LOAD_CHECK='Both';
      NO_IO_CHECK='Both';
      NO_ASSERT_CHECK='TRUE';
      NO_DIR_CHECK='TRUE';
      ALLOW_CONNECT='TRUE';
    'VSS_CR41':
      PIN_NUMBER='(0,0,0,0,0,0,0,0,0,0,0,0,0,0,0,0,0,0,0,0,0,0,0,0,0,0,0,0,0,0,0~
,0,0,0,0,0,0,0,CR41,0)';
      PINUSE='POWER';
      NO_LOAD_CHECK='Both';
      NO_IO_CHECK='Both';
      NO_ASSERT_CHECK='TRUE';
      NO_DIR_CHECK='TRUE';
      ALLOW_CONNECT='TRUE';
    'VSS_CR42':
      PIN_NUMBER='(0,0,0,0,0,0,0,0,0,0,0,0,0,0,0,0,0,0,0,0,0,0,0,0,0,0,0,0,0,0,0~
,0,0,0,0,0,0,0,CR42,0)';
      PINUSE='POWER';
      NO_LOAD_CHECK='Both';
      NO_IO_CHECK='Both';
      NO_ASSERT_CHECK='TRUE';
      NO_DIR_CHECK='TRUE';
      ALLOW_CONNECT='TRUE';
    'VSS_CR45':
      PIN_NUMBER='(0,0,0,0,0,0,0,0,0,0,0,0,0,0,0,0,0,0,0,0,0,0,0,0,0,0,0,0,0,0,0~
,0,0,0,0,0,0,0,CR45,0)';
      PINUSE='POWER';
      NO_LOAD_CHECK='Both';
      NO_IO_CHECK='Both';
      NO_ASSERT_CHECK='TRUE';
      NO_DIR_CHECK='TRUE';
      ALLOW_CONNECT='TRUE';
    'VSS_CR61':
      PIN_NUMBER='(0,0,0,0,0,0,0,0,0,0,0,0,0,0,0,0,0,0,0,0,0,0,0,0,0,0,0,0,0,0,0~
,0,0,0,0,0,0,0,CR61,0)';
      PINUSE='POWER';
      NO_LOAD_CHECK='Both';
      NO_IO_CHECK='Both';
      NO_ASSERT_CHECK='TRUE';
      NO_DIR_CHECK='TRUE';
      ALLOW_CONNECT='TRUE';
    'VSS_CR63':
      PIN_NUMBER='(0,0,0,0,0,0,0,0,0,0,0,0,0,0,0,0,0,0,0,0,0,0,0,0,0,0,0,0,0,0,0~
,0,0,0,0,0,0,0,CR63,0)';
      PINUSE='POWER';
      NO_LOAD_CHECK='Both';
      NO_IO_CHECK='Both';
      NO_ASSERT_CHECK='TRUE';
      NO_DIR_CHECK='TRUE';
      ALLOW_CONNECT='TRUE';
    'VSS_CR65':
      PIN_NUMBER='(0,0,0,0,0,0,0,0,0,0,0,0,0,0,0,0,0,0,0,0,0,0,0,0,0,0,0,0,0,0,0~
,0,0,0,0,0,0,0,CR65,0)';
      PINUSE='POWER';
      NO_LOAD_CHECK='Both';
      NO_IO_CHECK='Both';
      NO_ASSERT_CHECK='TRUE';
      NO_DIR_CHECK='TRUE';
      ALLOW_CONNECT='TRUE';
    'VSS_CR68':
      PIN_NUMBER='(0,0,0,0,0,0,0,0,0,0,0,0,0,0,0,0,0,0,0,0,0,0,0,0,0,0,0,0,0,0,0~
,0,0,0,0,0,0,0,CR68,0)';
      PINUSE='POWER';
      NO_LOAD_CHECK='Both';
      NO_IO_CHECK='Both';
      NO_ASSERT_CHECK='TRUE';
      NO_DIR_CHECK='TRUE';
      ALLOW_CONNECT='TRUE';
    'VSS_CR70':
      PIN_NUMBER='(0,0,0,0,0,0,0,0,0,0,0,0,0,0,0,0,0,0,0,0,0,0,0,0,0,0,0,0,0,0,0~
,0,0,0,0,0,0,0,CR70,0)';
      PINUSE='POWER';
      NO_LOAD_CHECK='Both';
      NO_IO_CHECK='Both';
      NO_ASSERT_CHECK='TRUE';
      NO_DIR_CHECK='TRUE';
      ALLOW_CONNECT='TRUE';
    'VSS_CR72':
      PIN_NUMBER='(0,0,0,0,0,0,0,0,0,0,0,0,0,0,0,0,0,0,0,0,0,0,0,0,0,0,0,0,0,0,0~
,0,0,0,0,0,0,0,CR72,0)';
      PINUSE='POWER';
      NO_LOAD_CHECK='Both';
      NO_IO_CHECK='Both';
      NO_ASSERT_CHECK='TRUE';
      NO_DIR_CHECK='TRUE';
      ALLOW_CONNECT='TRUE';
    'VSS_CT17':
      PIN_NUMBER='(0,0,0,0,0,0,0,0,0,0,0,0,0,0,0,0,0,0,0,0,0,0,0,0,0,0,0,0,0,0,0~
,0,0,0,0,0,0,0,CT17,0)';
      PINUSE='POWER';
      NO_LOAD_CHECK='Both';
      NO_IO_CHECK='Both';
      NO_ASSERT_CHECK='TRUE';
      NO_DIR_CHECK='TRUE';
      ALLOW_CONNECT='TRUE';
    'VSS_CT23':
      PIN_NUMBER='(0,0,0,0,0,0,0,0,0,0,0,0,0,0,0,0,0,0,0,0,0,0,0,0,0,0,0,0,0,0,0~
,0,0,0,0,0,0,0,CT23,0)';
      PINUSE='POWER';
      NO_LOAD_CHECK='Both';
      NO_IO_CHECK='Both';
      NO_ASSERT_CHECK='TRUE';
      NO_DIR_CHECK='TRUE';
      ALLOW_CONNECT='TRUE';
    'VSS_CT24':
      PIN_NUMBER='(0,0,0,0,0,0,0,0,0,0,0,0,0,0,0,0,0,0,0,0,0,0,0,0,0,0,0,0,0,0,0~
,0,0,0,0,0,0,0,CT24,0)';
      PINUSE='POWER';
      NO_LOAD_CHECK='Both';
      NO_IO_CHECK='Both';
      NO_ASSERT_CHECK='TRUE';
      NO_DIR_CHECK='TRUE';
      ALLOW_CONNECT='TRUE';
    'VSS_CT25':
      PIN_NUMBER='(0,0,0,0,0,0,0,0,0,0,0,0,0,0,0,0,0,0,0,0,0,0,0,0,0,0,0,0,0,0,0~
,0,0,0,0,0,0,0,CT25,0)';
      PINUSE='POWER';
      NO_LOAD_CHECK='Both';
      NO_IO_CHECK='Both';
      NO_ASSERT_CHECK='TRUE';
      NO_DIR_CHECK='TRUE';
      ALLOW_CONNECT='TRUE';
    'VSS_CT26':
      PIN_NUMBER='(0,0,0,0,0,0,0,0,0,0,0,0,0,0,0,0,0,0,0,0,0,0,0,0,0,0,0,0,0,0,0~
,0,0,0,0,0,0,0,CT26,0)';
      PINUSE='POWER';
      NO_LOAD_CHECK='Both';
      NO_IO_CHECK='Both';
      NO_ASSERT_CHECK='TRUE';
      NO_DIR_CHECK='TRUE';
      ALLOW_CONNECT='TRUE';
    'VSS_CT27':
      PIN_NUMBER='(0,0,0,0,0,0,0,0,0,0,0,0,0,0,0,0,0,0,0,0,0,0,0,0,0,0,0,0,0,0,0~
,0,0,0,0,0,0,0,CT27,0)';
      PINUSE='POWER';
      NO_LOAD_CHECK='Both';
      NO_IO_CHECK='Both';
      NO_ASSERT_CHECK='TRUE';
      NO_DIR_CHECK='TRUE';
      ALLOW_CONNECT='TRUE';
    'VSS_CT28':
      PIN_NUMBER='(0,0,0,0,0,0,0,0,0,0,0,0,0,0,0,0,0,0,0,0,0,0,0,0,0,0,0,0,0,0,0~
,0,0,0,0,0,0,0,CT28,0)';
      PINUSE='POWER';
      NO_LOAD_CHECK='Both';
      NO_IO_CHECK='Both';
      NO_ASSERT_CHECK='TRUE';
      NO_DIR_CHECK='TRUE';
      ALLOW_CONNECT='TRUE';
    'VSS_CT29':
      PIN_NUMBER='(0,0,0,0,0,0,0,0,0,0,0,0,0,0,0,0,0,0,0,0,0,0,0,0,0,0,0,0,0,0,0~
,0,0,0,0,0,0,0,CT29,0)';
      PINUSE='POWER';
      NO_LOAD_CHECK='Both';
      NO_IO_CHECK='Both';
      NO_ASSERT_CHECK='TRUE';
      NO_DIR_CHECK='TRUE';
      ALLOW_CONNECT='TRUE';
    'VSS_CT30':
      PIN_NUMBER='(0,0,0,0,0,0,0,0,0,0,0,0,0,0,0,0,0,0,0,0,0,0,0,0,0,0,0,0,0,0,0~
,0,0,0,0,0,0,0,CT30,0)';
      PINUSE='POWER';
      NO_LOAD_CHECK='Both';
      NO_IO_CHECK='Both';
      NO_ASSERT_CHECK='TRUE';
      NO_DIR_CHECK='TRUE';
      ALLOW_CONNECT='TRUE';
    'VSS_CT31':
      PIN_NUMBER='(0,0,0,0,0,0,0,0,0,0,0,0,0,0,0,0,0,0,0,0,0,0,0,0,0,0,0,0,0,0,0~
,0,0,0,0,0,0,0,CT31,0)';
      PINUSE='POWER';
      NO_LOAD_CHECK='Both';
      NO_IO_CHECK='Both';
      NO_ASSERT_CHECK='TRUE';
      NO_DIR_CHECK='TRUE';
      ALLOW_CONNECT='TRUE';
    'VSS_CT32':
      PIN_NUMBER='(0,0,0,0,0,0,0,0,0,0,0,0,0,0,0,0,0,0,0,0,0,0,0,0,0,0,0,0,0,0,0~
,0,0,0,0,0,0,0,CT32,0)';
      PINUSE='POWER';
      NO_LOAD_CHECK='Both';
      NO_IO_CHECK='Both';
      NO_ASSERT_CHECK='TRUE';
      NO_DIR_CHECK='TRUE';
      ALLOW_CONNECT='TRUE';
    'VSS_CT33':
      PIN_NUMBER='(0,0,0,0,0,0,0,0,0,0,0,0,0,0,0,0,0,0,0,0,0,0,0,0,0,0,0,0,0,0,0~
,0,0,0,0,0,0,0,CT33,0)';
      PINUSE='POWER';
      NO_LOAD_CHECK='Both';
      NO_IO_CHECK='Both';
      NO_ASSERT_CHECK='TRUE';
      NO_DIR_CHECK='TRUE';
      ALLOW_CONNECT='TRUE';
    'VSS_CT34':
      PIN_NUMBER='(0,0,0,0,0,0,0,0,0,0,0,0,0,0,0,0,0,0,0,0,0,0,0,0,0,0,0,0,0,0,0~
,0,0,0,0,0,0,0,CT34,0)';
      PINUSE='POWER';
      NO_LOAD_CHECK='Both';
      NO_IO_CHECK='Both';
      NO_ASSERT_CHECK='TRUE';
      NO_DIR_CHECK='TRUE';
      ALLOW_CONNECT='TRUE';
    'VSS_CT37':
      PIN_NUMBER='(0,0,0,0,0,0,0,0,0,0,0,0,0,0,0,0,0,0,0,0,0,0,0,0,0,0,0,0,0,0,0~
,0,0,0,0,0,0,0,CT37,0)';
      PINUSE='POWER';
      NO_LOAD_CHECK='Both';
      NO_IO_CHECK='Both';
      NO_ASSERT_CHECK='TRUE';
      NO_DIR_CHECK='TRUE';
      ALLOW_CONNECT='TRUE';
    'VSS_CT39':
      PIN_NUMBER='(0,0,0,0,0,0,0,0,0,0,0,0,0,0,0,0,0,0,0,0,0,0,0,0,0,0,0,0,0,0,0~
,0,0,0,0,0,0,0,CT39,0)';
      PINUSE='POWER';
      NO_LOAD_CHECK='Both';
      NO_IO_CHECK='Both';
      NO_ASSERT_CHECK='TRUE';
      NO_DIR_CHECK='TRUE';
      ALLOW_CONNECT='TRUE';
    'VSS_CT42':
      PIN_NUMBER='(0,0,0,0,0,0,0,0,0,0,0,0,0,0,0,0,0,0,0,0,0,0,0,0,0,0,0,0,0,0,0~
,0,0,0,0,0,0,0,CT42,0)';
      PINUSE='POWER';
      NO_LOAD_CHECK='Both';
      NO_IO_CHECK='Both';
      NO_ASSERT_CHECK='TRUE';
      NO_DIR_CHECK='TRUE';
      ALLOW_CONNECT='TRUE';
    'VSS_CT43':
      PIN_NUMBER='(0,0,0,0,0,0,0,0,0,0,0,0,0,0,0,0,0,0,0,0,0,0,0,0,0,0,0,0,0,0,0~
,0,0,0,0,0,0,0,CT43,0)';
      PINUSE='POWER';
      NO_LOAD_CHECK='Both';
      NO_IO_CHECK='Both';
      NO_ASSERT_CHECK='TRUE';
      NO_DIR_CHECK='TRUE';
      ALLOW_CONNECT='TRUE';
    'VSS_CT44':
      PIN_NUMBER='(0,0,0,0,0,0,0,0,0,0,0,0,0,0,0,0,0,0,0,0,0,0,0,0,0,0,0,0,0,0,0~
,0,0,0,0,0,0,0,CT44,0)';
      PINUSE='POWER';
      NO_LOAD_CHECK='Both';
      NO_IO_CHECK='Both';
      NO_ASSERT_CHECK='TRUE';
      NO_DIR_CHECK='TRUE';
      ALLOW_CONNECT='TRUE';
    'VSS_CT45':
      PIN_NUMBER='(0,0,0,0,0,0,0,0,0,0,0,0,0,0,0,0,0,0,0,0,0,0,0,0,0,0,0,0,0,0,0~
,0,0,0,0,0,0,0,CT45,0)';
      PINUSE='POWER';
      NO_LOAD_CHECK='Both';
      NO_IO_CHECK='Both';
      NO_ASSERT_CHECK='TRUE';
      NO_DIR_CHECK='TRUE';
      ALLOW_CONNECT='TRUE';
    'VSS_CT46':
      PIN_NUMBER='(0,0,0,0,0,0,0,0,0,0,0,0,0,0,0,0,0,0,0,0,0,0,0,0,0,0,0,0,0,0,0~
,0,0,0,0,0,0,0,CT46,0)';
      PINUSE='POWER';
      NO_LOAD_CHECK='Both';
      NO_IO_CHECK='Both';
      NO_ASSERT_CHECK='TRUE';
      NO_DIR_CHECK='TRUE';
      ALLOW_CONNECT='TRUE';
    'VSS_CT47':
      PIN_NUMBER='(0,0,0,0,0,0,0,0,0,0,0,0,0,0,0,0,0,0,0,0,0,0,0,0,0,0,0,0,0,0,0~
,0,0,0,0,0,0,0,CT47,0)';
      PINUSE='POWER';
      NO_LOAD_CHECK='Both';
      NO_IO_CHECK='Both';
      NO_ASSERT_CHECK='TRUE';
      NO_DIR_CHECK='TRUE';
      ALLOW_CONNECT='TRUE';
    'VSS_CT49':
      PIN_NUMBER='(0,0,0,0,0,0,0,0,0,0,0,0,0,0,0,0,0,0,0,0,0,0,0,0,0,0,0,0,0,0,0~
,0,0,0,0,0,0,0,CT49,0)';
      PINUSE='POWER';
      NO_LOAD_CHECK='Both';
      NO_IO_CHECK='Both';
      NO_ASSERT_CHECK='TRUE';
      NO_DIR_CHECK='TRUE';
      ALLOW_CONNECT='TRUE';
    'VSS_CT50':
      PIN_NUMBER='(0,0,0,0,0,0,0,0,0,0,0,0,0,0,0,0,0,0,0,0,0,0,0,0,0,0,0,0,0,0,0~
,0,0,0,0,0,0,0,CT50,0)';
      PINUSE='POWER';
      NO_LOAD_CHECK='Both';
      NO_IO_CHECK='Both';
      NO_ASSERT_CHECK='TRUE';
      NO_DIR_CHECK='TRUE';
      ALLOW_CONNECT='TRUE';
    'VSS_CT51':
      PIN_NUMBER='(0,0,0,0,0,0,0,0,0,0,0,0,0,0,0,0,0,0,0,0,0,0,0,0,0,0,0,0,0,0,0~
,0,0,0,0,0,0,0,CT51,0)';
      PINUSE='POWER';
      NO_LOAD_CHECK='Both';
      NO_IO_CHECK='Both';
      NO_ASSERT_CHECK='TRUE';
      NO_DIR_CHECK='TRUE';
      ALLOW_CONNECT='TRUE';
    'VSS_CT53':
      PIN_NUMBER='(0,0,0,0,0,0,0,0,0,0,0,0,0,0,0,0,0,0,0,0,0,0,0,0,0,0,0,0,0,0,0~
,0,0,0,0,0,0,0,CT53,0)';
      PINUSE='POWER';
      NO_LOAD_CHECK='Both';
      NO_IO_CHECK='Both';
      NO_ASSERT_CHECK='TRUE';
      NO_DIR_CHECK='TRUE';
      ALLOW_CONNECT='TRUE';
    'VSS_CT59':
      PIN_NUMBER='(0,0,0,0,0,0,0,0,0,0,0,0,0,0,0,0,0,0,0,0,0,0,0,0,0,0,0,0,0,0,0~
,0,0,0,0,0,0,0,CT59,0)';
      PINUSE='POWER';
      NO_LOAD_CHECK='Both';
      NO_IO_CHECK='Both';
      NO_ASSERT_CHECK='TRUE';
      NO_DIR_CHECK='TRUE';
      ALLOW_CONNECT='TRUE';
    'VSS_CT61':
      PIN_NUMBER='(0,0,0,0,0,0,0,0,0,0,0,0,0,0,0,0,0,0,0,0,0,0,0,0,0,0,0,0,0,0,0~
,0,0,0,0,0,0,0,CT61,0)';
      PINUSE='POWER';
      NO_LOAD_CHECK='Both';
      NO_IO_CHECK='Both';
      NO_ASSERT_CHECK='TRUE';
      NO_DIR_CHECK='TRUE';
      ALLOW_CONNECT='TRUE';
    'VSS_CT66':
      PIN_NUMBER='(0,0,0,0,0,0,0,0,0,0,0,0,0,0,0,0,0,0,0,0,0,0,0,0,0,0,0,0,0,0,0~
,0,0,0,0,0,0,0,CT66,0)';
      PINUSE='POWER';
      NO_LOAD_CHECK='Both';
      NO_IO_CHECK='Both';
      NO_ASSERT_CHECK='TRUE';
      NO_DIR_CHECK='TRUE';
      ALLOW_CONNECT='TRUE';
    'VSS_CT68':
      PIN_NUMBER='(0,0,0,0,0,0,0,0,0,0,0,0,0,0,0,0,0,0,0,0,0,0,0,0,0,0,0,0,0,0,0~
,0,0,0,0,0,0,0,CT68,0)';
      PINUSE='POWER';
      NO_LOAD_CHECK='Both';
      NO_IO_CHECK='Both';
      NO_ASSERT_CHECK='TRUE';
      NO_DIR_CHECK='TRUE';
      ALLOW_CONNECT='TRUE';
    'VSS_CU4':
      PIN_NUMBER='(0,0,0,0,0,0,0,0,0,0,0,0,0,0,0,0,0,0,0,0,0,0,0,0,0,0,0,0,0,0,0~
,0,0,0,0,0,0,0,CU4,0)';
      PINUSE='POWER';
      NO_LOAD_CHECK='Both';
      NO_IO_CHECK='Both';
      NO_ASSERT_CHECK='TRUE';
      NO_DIR_CHECK='TRUE';
      ALLOW_CONNECT='TRUE';
    'VSS_CU6':
      PIN_NUMBER='(0,0,0,0,0,0,0,0,0,0,0,0,0,0,0,0,0,0,0,0,0,0,0,0,0,0,0,0,0,0,0~
,0,0,0,0,0,0,0,CU6,0)';
      PINUSE='POWER';
      NO_LOAD_CHECK='Both';
      NO_IO_CHECK='Both';
      NO_ASSERT_CHECK='TRUE';
      NO_DIR_CHECK='TRUE';
      ALLOW_CONNECT='TRUE';
    'VSS_CU8':
      PIN_NUMBER='(0,0,0,0,0,0,0,0,0,0,0,0,0,0,0,0,0,0,0,0,0,0,0,0,0,0,0,0,0,0,0~
,0,0,0,0,0,0,0,CU8,0)';
      PINUSE='POWER';
      NO_LOAD_CHECK='Both';
      NO_IO_CHECK='Both';
      NO_ASSERT_CHECK='TRUE';
      NO_DIR_CHECK='TRUE';
      ALLOW_CONNECT='TRUE';
    'VSS_CU11':
      PIN_NUMBER='(0,0,0,0,0,0,0,0,0,0,0,0,0,0,0,0,0,0,0,0,0,0,0,0,0,0,0,0,0,0,0~
,0,0,0,0,0,0,0,CU11,0)';
      PINUSE='POWER';
      NO_LOAD_CHECK='Both';
      NO_IO_CHECK='Both';
      NO_ASSERT_CHECK='TRUE';
      NO_DIR_CHECK='TRUE';
      ALLOW_CONNECT='TRUE';
    'VSS_CU13':
      PIN_NUMBER='(0,0,0,0,0,0,0,0,0,0,0,0,0,0,0,0,0,0,0,0,0,0,0,0,0,0,0,0,0,0,0~
,0,0,0,0,0,0,0,CU13,0)';
      PINUSE='POWER';
      NO_LOAD_CHECK='Both';
      NO_IO_CHECK='Both';
      NO_ASSERT_CHECK='TRUE';
      NO_DIR_CHECK='TRUE';
      ALLOW_CONNECT='TRUE';
    'VSS_CU15':
      PIN_NUMBER='(0,0,0,0,0,0,0,0,0,0,0,0,0,0,0,0,0,0,0,0,0,0,0,0,0,0,0,0,0,0,0~
,0,0,0,0,0,0,0,CU15,0)';
      PINUSE='POWER';
      NO_LOAD_CHECK='Both';
      NO_IO_CHECK='Both';
      NO_ASSERT_CHECK='TRUE';
      NO_DIR_CHECK='TRUE';
      ALLOW_CONNECT='TRUE';
    'VSS_CU18':
      PIN_NUMBER='(0,0,0,0,0,0,0,0,0,0,0,0,0,0,0,0,0,0,0,0,0,0,0,0,0,0,0,0,0,0,0~
,0,0,0,0,0,0,0,CU18,0)';
      PINUSE='POWER';
      NO_LOAD_CHECK='Both';
      NO_IO_CHECK='Both';
      NO_ASSERT_CHECK='TRUE';
      NO_DIR_CHECK='TRUE';
      ALLOW_CONNECT='TRUE';
    'VSS_CU20':
      PIN_NUMBER='(0,0,0,0,0,0,0,0,0,0,0,0,0,0,0,0,0,0,0,0,0,0,0,0,0,0,0,0,0,0,0~
,0,0,0,0,0,0,0,CU20,0)';
      PINUSE='POWER';
      NO_LOAD_CHECK='Both';
      NO_IO_CHECK='Both';
      NO_ASSERT_CHECK='TRUE';
      NO_DIR_CHECK='TRUE';
      ALLOW_CONNECT='TRUE';
    'VSS_CU31':
      PIN_NUMBER='(0,0,0,0,0,0,0,0,0,0,0,0,0,0,0,0,0,0,0,0,0,0,0,0,0,0,0,0,0,0,0~
,0,0,0,0,0,0,0,CU31,0)';
      PINUSE='POWER';
      NO_LOAD_CHECK='Both';
      NO_IO_CHECK='Both';
      NO_ASSERT_CHECK='TRUE';
      NO_DIR_CHECK='TRUE';
      ALLOW_CONNECT='TRUE';
    'VSS_CU34':
      PIN_NUMBER='(0,0,0,0,0,0,0,0,0,0,0,0,0,0,0,0,0,0,0,0,0,0,0,0,0,0,0,0,0,0,0~
,0,0,0,0,0,0,0,CU34,0)';
      PINUSE='POWER';
      NO_LOAD_CHECK='Both';
      NO_IO_CHECK='Both';
      NO_ASSERT_CHECK='TRUE';
      NO_DIR_CHECK='TRUE';
      ALLOW_CONNECT='TRUE';
    'VSS_CU42':
      PIN_NUMBER='(0,0,0,0,0,0,0,0,0,0,0,0,0,0,0,0,0,0,0,0,0,0,0,0,0,0,0,0,0,0,0~
,0,0,0,0,0,0,0,CU42,0)';
      PINUSE='POWER';
      NO_LOAD_CHECK='Both';
      NO_IO_CHECK='Both';
      NO_ASSERT_CHECK='TRUE';
      NO_DIR_CHECK='TRUE';
      ALLOW_CONNECT='TRUE';
    'VSS_CU45':
      PIN_NUMBER='(0,0,0,0,0,0,0,0,0,0,0,0,0,0,0,0,0,0,0,0,0,0,0,0,0,0,0,0,0,0,0~
,0,0,0,0,0,0,0,CU45,0)';
      PINUSE='POWER';
      NO_LOAD_CHECK='Both';
      NO_IO_CHECK='Both';
      NO_ASSERT_CHECK='TRUE';
      NO_DIR_CHECK='TRUE';
      ALLOW_CONNECT='TRUE';
    'VSS_CU48':
      PIN_NUMBER='(0,0,0,0,0,0,0,0,0,0,0,0,0,0,0,0,0,0,0,0,0,0,0,0,0,0,0,0,0,0,0~
,0,0,0,0,0,0,0,CU48,0)';
      PINUSE='POWER';
      NO_LOAD_CHECK='Both';
      NO_IO_CHECK='Both';
      NO_ASSERT_CHECK='TRUE';
      NO_DIR_CHECK='TRUE';
      ALLOW_CONNECT='TRUE';
    'VSS_CU51':
      PIN_NUMBER='(0,0,0,0,0,0,0,0,0,0,0,0,0,0,0,0,0,0,0,0,0,0,0,0,0,0,0,0,0,0,0~
,0,0,0,0,0,0,0,CU51,0)';
      PINUSE='POWER';
      NO_LOAD_CHECK='Both';
      NO_IO_CHECK='Both';
      NO_ASSERT_CHECK='TRUE';
      NO_DIR_CHECK='TRUE';
      ALLOW_CONNECT='TRUE';
    'VSS_CU54':
      PIN_NUMBER='(0,0,0,0,0,0,0,0,0,0,0,0,0,0,0,0,0,0,0,0,0,0,0,0,0,0,0,0,0,0,0~
,0,0,0,0,0,0,0,CU54,0)';
      PINUSE='POWER';
      NO_LOAD_CHECK='Both';
      NO_IO_CHECK='Both';
      NO_ASSERT_CHECK='TRUE';
      NO_DIR_CHECK='TRUE';
      ALLOW_CONNECT='TRUE';
    'VSS_CU65':
      PIN_NUMBER='(0,0,0,0,0,0,0,0,0,0,0,0,0,0,0,0,0,0,0,0,0,0,0,0,0,0,0,0,0,0,0~
,0,0,0,0,0,0,0,CU65,0)';
      PINUSE='POWER';
      NO_LOAD_CHECK='Both';
      NO_IO_CHECK='Both';
      NO_ASSERT_CHECK='TRUE';
      NO_DIR_CHECK='TRUE';
      ALLOW_CONNECT='TRUE';
    'VSS_CU68':
      PIN_NUMBER='(0,0,0,0,0,0,0,0,0,0,0,0,0,0,0,0,0,0,0,0,0,0,0,0,0,0,0,0,0,0,0~
,0,0,0,0,0,0,0,CU68,0)';
      PINUSE='POWER';
      NO_LOAD_CHECK='Both';
      NO_IO_CHECK='Both';
      NO_ASSERT_CHECK='TRUE';
      NO_DIR_CHECK='TRUE';
      ALLOW_CONNECT='TRUE';
    'VSS_CU70':
      PIN_NUMBER='(0,0,0,0,0,0,0,0,0,0,0,0,0,0,0,0,0,0,0,0,0,0,0,0,0,0,0,0,0,0,0~
,0,0,0,0,0,0,0,CU70,0)';
      PINUSE='POWER';
      NO_LOAD_CHECK='Both';
      NO_IO_CHECK='Both';
      NO_ASSERT_CHECK='TRUE';
      NO_DIR_CHECK='TRUE';
      ALLOW_CONNECT='TRUE';
    'VSS_CU72':
      PIN_NUMBER='(0,0,0,0,0,0,0,0,0,0,0,0,0,0,0,0,0,0,0,0,0,0,0,0,0,0,0,0,0,0,0~
,0,0,0,0,0,0,0,CU72,0)';
      PINUSE='POWER';
      NO_LOAD_CHECK='Both';
      NO_IO_CHECK='Both';
      NO_ASSERT_CHECK='TRUE';
      NO_DIR_CHECK='TRUE';
      ALLOW_CONNECT='TRUE';
    'VSS_CU75':
      PIN_NUMBER='(0,0,0,0,0,0,0,0,0,0,0,0,0,0,0,0,0,0,0,0,0,0,0,0,0,0,0,0,0,0,0~
,0,0,0,0,0,0,0,CU75,0)';
      PINUSE='POWER';
      NO_LOAD_CHECK='Both';
      NO_IO_CHECK='Both';
      NO_ASSERT_CHECK='TRUE';
      NO_DIR_CHECK='TRUE';
      ALLOW_CONNECT='TRUE';
    'VSS_CV3':
      PIN_NUMBER='(0,0,0,0,0,0,0,0,0,0,0,0,0,0,0,0,0,0,0,0,0,0,0,0,0,0,0,0,0,0,0~
,0,0,0,0,0,0,0,CV3,0)';
      PINUSE='POWER';
      NO_LOAD_CHECK='Both';
      NO_IO_CHECK='Both';
      NO_ASSERT_CHECK='TRUE';
      NO_DIR_CHECK='TRUE';
      ALLOW_CONNECT='TRUE';
    'VSS_CV17':
      PIN_NUMBER='(0,0,0,0,0,0,0,0,0,0,0,0,0,0,0,0,0,0,0,0,0,0,0,0,0,0,0,0,0,0,0~
,0,0,0,0,0,0,0,CV17,0)';
      PINUSE='POWER';
      NO_LOAD_CHECK='Both';
      NO_IO_CHECK='Both';
      NO_ASSERT_CHECK='TRUE';
      NO_DIR_CHECK='TRUE';
      ALLOW_CONNECT='TRUE';
    'VSS_CV19':
      PIN_NUMBER='(0,0,0,0,0,0,0,0,0,0,0,0,0,0,0,0,0,0,0,0,0,0,0,0,0,0,0,0,0,0,0~
,0,0,0,0,0,0,0,CV19,0)';
      PINUSE='POWER';
      NO_LOAD_CHECK='Both';
      NO_IO_CHECK='Both';
      NO_ASSERT_CHECK='TRUE';
      NO_DIR_CHECK='TRUE';
      ALLOW_CONNECT='TRUE';
    'VSS_CV22':
      PIN_NUMBER='(0,0,0,0,0,0,0,0,0,0,0,0,0,0,0,0,0,0,0,0,0,0,0,0,0,0,0,0,0,0,0~
,0,0,0,0,0,0,0,CV22,0)';
      PINUSE='POWER';
      NO_LOAD_CHECK='Both';
      NO_IO_CHECK='Both';
      NO_ASSERT_CHECK='TRUE';
      NO_DIR_CHECK='TRUE';
      ALLOW_CONNECT='TRUE';
    'VSS_CV25':
      PIN_NUMBER='(0,0,0,0,0,0,0,0,0,0,0,0,0,0,0,0,0,0,0,0,0,0,0,0,0,0,0,0,0,0,0~
,0,0,0,0,0,0,0,CV25,0)';
      PINUSE='POWER';
      NO_LOAD_CHECK='Both';
      NO_IO_CHECK='Both';
      NO_ASSERT_CHECK='TRUE';
      NO_DIR_CHECK='TRUE';
      ALLOW_CONNECT='TRUE';
    'VSS_CV28':
      PIN_NUMBER='(0,0,0,0,0,0,0,0,0,0,0,0,0,0,0,0,0,0,0,0,0,0,0,0,0,0,0,0,0,0,0~
,0,0,0,0,0,0,0,CV28,0)';
      PINUSE='POWER';
      NO_LOAD_CHECK='Both';
      NO_IO_CHECK='Both';
      NO_ASSERT_CHECK='TRUE';
      NO_DIR_CHECK='TRUE';
      ALLOW_CONNECT='TRUE';
    'VSS_CV31':
      PIN_NUMBER='(0,0,0,0,0,0,0,0,0,0,0,0,0,0,0,0,0,0,0,0,0,0,0,0,0,0,0,0,0,0,0~
,0,0,0,0,0,0,0,CV31,0)';
      PINUSE='POWER';
      NO_LOAD_CHECK='Both';
      NO_IO_CHECK='Both';
      NO_ASSERT_CHECK='TRUE';
      NO_DIR_CHECK='TRUE';
      ALLOW_CONNECT='TRUE';
    'VSS_CV48':
      PIN_NUMBER='(0,0,0,0,0,0,0,0,0,0,0,0,0,0,0,0,0,0,0,0,0,0,0,0,0,0,0,0,0,0,0~
,0,0,0,0,0,0,0,CV48,0)';
      PINUSE='POWER';
      NO_LOAD_CHECK='Both';
      NO_IO_CHECK='Both';
      NO_ASSERT_CHECK='TRUE';
      NO_DIR_CHECK='TRUE';
      ALLOW_CONNECT='TRUE';
    'VSS_CV51':
      PIN_NUMBER='(0,0,0,0,0,0,0,0,0,0,0,0,0,0,0,0,0,0,0,0,0,0,0,0,0,0,0,0,0,0,0~
,0,0,0,0,0,0,0,CV51,0)';
      PINUSE='POWER';
      NO_LOAD_CHECK='Both';
      NO_IO_CHECK='Both';
      NO_ASSERT_CHECK='TRUE';
      NO_DIR_CHECK='TRUE';
      ALLOW_CONNECT='TRUE';
    'VSS_CV54':
      PIN_NUMBER='(0,0,0,0,0,0,0,0,0,0,0,0,0,0,0,0,0,0,0,0,0,0,0,0,0,0,0,0,0,0,0~
,0,0,0,0,0,0,0,CV54,0)';
      PINUSE='POWER';
      NO_LOAD_CHECK='Both';
      NO_IO_CHECK='Both';
      NO_ASSERT_CHECK='TRUE';
      NO_DIR_CHECK='TRUE';
      ALLOW_CONNECT='TRUE';
    'VSS_CV57':
      PIN_NUMBER='(0,0,0,0,0,0,0,0,0,0,0,0,0,0,0,0,0,0,0,0,0,0,0,0,0,0,0,0,0,0,0~
,0,0,0,0,0,0,0,CV57,0)';
      PINUSE='POWER';
      NO_LOAD_CHECK='Both';
      NO_IO_CHECK='Both';
      NO_ASSERT_CHECK='TRUE';
      NO_DIR_CHECK='TRUE';
      ALLOW_CONNECT='TRUE';
    'VSS_CV59':
      PIN_NUMBER='(0,0,0,0,0,0,0,0,0,0,0,0,0,0,0,0,0,0,0,0,0,0,0,0,0,0,0,0,0,0,0~
,0,0,0,0,0,0,0,CV59,0)';
      PINUSE='POWER';
      NO_LOAD_CHECK='Both';
      NO_IO_CHECK='Both';
      NO_ASSERT_CHECK='TRUE';
      NO_DIR_CHECK='TRUE';
      ALLOW_CONNECT='TRUE';
    'VSS_CV61':
      PIN_NUMBER='(0,0,0,0,0,0,0,0,0,0,0,0,0,0,0,0,0,0,0,0,0,0,0,0,0,0,0,0,0,0,0~
,0,0,0,0,0,0,0,CV61,0)';
      PINUSE='POWER';
      NO_LOAD_CHECK='Both';
      NO_IO_CHECK='Both';
      NO_ASSERT_CHECK='TRUE';
      NO_DIR_CHECK='TRUE';
      ALLOW_CONNECT='TRUE';
    'VSS_CW1':
      PIN_NUMBER='(0,0,0,0,0,0,0,0,0,0,0,0,0,0,0,0,0,0,0,0,0,0,0,0,0,0,0,0,0,0,0~
,0,0,0,0,0,0,0,CW1,0)';
      PINUSE='POWER';
      NO_LOAD_CHECK='Both';
      NO_IO_CHECK='Both';
      NO_ASSERT_CHECK='TRUE';
      NO_DIR_CHECK='TRUE';
      ALLOW_CONNECT='TRUE';
    'VSS_CW6':
      PIN_NUMBER='(0,0,0,0,0,0,0,0,0,0,0,0,0,0,0,0,0,0,0,0,0,0,0,0,0,0,0,0,0,0,0~
,0,0,0,0,0,0,0,CW6,0)';
      PINUSE='POWER';
      NO_LOAD_CHECK='Both';
      NO_IO_CHECK='Both';
      NO_ASSERT_CHECK='TRUE';
      NO_DIR_CHECK='TRUE';
      ALLOW_CONNECT='TRUE';
    'VSS_CW8':
      PIN_NUMBER='(0,0,0,0,0,0,0,0,0,0,0,0,0,0,0,0,0,0,0,0,0,0,0,0,0,0,0,0,0,0,0~
,0,0,0,0,0,0,0,CW8,0)';
      PINUSE='POWER';
      NO_LOAD_CHECK='Both';
      NO_IO_CHECK='Both';
      NO_ASSERT_CHECK='TRUE';
      NO_DIR_CHECK='TRUE';
      ALLOW_CONNECT='TRUE';
    'VSS_CW13':
      PIN_NUMBER='(0,0,0,0,0,0,0,0,0,0,0,0,0,0,0,0,0,0,0,0,0,0,0,0,0,0,0,0,0,0,0~
,0,0,0,0,0,0,0,CW13,0)';
      PINUSE='POWER';
      NO_LOAD_CHECK='Both';
      NO_IO_CHECK='Both';
      NO_ASSERT_CHECK='TRUE';
      NO_DIR_CHECK='TRUE';
      ALLOW_CONNECT='TRUE';
    'VSS_CW15':
      PIN_NUMBER='(0,0,0,0,0,0,0,0,0,0,0,0,0,0,0,0,0,0,0,0,0,0,0,0,0,0,0,0,0,0,0~
,0,0,0,0,0,0,0,CW15,0)';
      PINUSE='POWER';
      NO_LOAD_CHECK='Both';
      NO_IO_CHECK='Both';
      NO_ASSERT_CHECK='TRUE';
      NO_DIR_CHECK='TRUE';
      ALLOW_CONNECT='TRUE';
    'VSS_CW20':
      PIN_NUMBER='(0,0,0,0,0,0,0,0,0,0,0,0,0,0,0,0,0,0,0,0,0,0,0,0,0,0,0,0,0,0,0~
,0,0,0,0,0,0,0,CW20,0)';
      PINUSE='POWER';
      NO_LOAD_CHECK='Both';
      NO_IO_CHECK='Both';
      NO_ASSERT_CHECK='TRUE';
      NO_DIR_CHECK='TRUE';
      ALLOW_CONNECT='TRUE';
    'VSS_CW35':
      PIN_NUMBER='(0,0,0,0,0,0,0,0,0,0,0,0,0,0,0,0,0,0,0,0,0,0,0,0,0,0,0,0,0,0,0~
,0,0,0,0,0,0,0,CW35,0)';
      PINUSE='POWER';
      NO_LOAD_CHECK='Both';
      NO_IO_CHECK='Both';
      NO_ASSERT_CHECK='TRUE';
      NO_DIR_CHECK='TRUE';
      ALLOW_CONNECT='TRUE';
    'VSS_CW36':
      PIN_NUMBER='(0,0,0,0,0,0,0,0,0,0,0,0,0,0,0,0,0,0,0,0,0,0,0,0,0,0,0,0,0,0,0~
,0,0,0,0,0,0,0,CW36,0)';
      PINUSE='POWER';
      NO_LOAD_CHECK='Both';
      NO_IO_CHECK='Both';
      NO_ASSERT_CHECK='TRUE';
      NO_DIR_CHECK='TRUE';
      ALLOW_CONNECT='TRUE';
    'VSS_CW40':
      PIN_NUMBER='(0,0,0,0,0,0,0,0,0,0,0,0,0,0,0,0,0,0,0,0,0,0,0,0,0,0,0,0,0,0,0~
,0,0,0,0,0,0,0,CW40,0)';
      PINUSE='POWER';
      NO_LOAD_CHECK='Both';
      NO_IO_CHECK='Both';
      NO_ASSERT_CHECK='TRUE';
      NO_DIR_CHECK='TRUE';
      ALLOW_CONNECT='TRUE';
    'VSS_CW41':
      PIN_NUMBER='(0,0,0,0,0,0,0,0,0,0,0,0,0,0,0,0,0,0,0,0,0,0,0,0,0,0,0,0,0,0,0~
,0,0,0,0,0,0,0,CW41,0)';
      PINUSE='POWER';
      NO_LOAD_CHECK='Both';
      NO_IO_CHECK='Both';
      NO_ASSERT_CHECK='TRUE';
      NO_DIR_CHECK='TRUE';
      ALLOW_CONNECT='TRUE';
    'VSS_CW42':
      PIN_NUMBER='(0,0,0,0,0,0,0,0,0,0,0,0,0,0,0,0,0,0,0,0,0,0,0,0,0,0,0,0,0,0,0~
,0,0,0,0,0,0,0,CW42,0)';
      PINUSE='POWER';
      NO_LOAD_CHECK='Both';
      NO_IO_CHECK='Both';
      NO_ASSERT_CHECK='TRUE';
      NO_DIR_CHECK='TRUE';
      ALLOW_CONNECT='TRUE';
    'VSS_CW45':
      PIN_NUMBER='(0,0,0,0,0,0,0,0,0,0,0,0,0,0,0,0,0,0,0,0,0,0,0,0,0,0,0,0,0,0,0~
,0,0,0,0,0,0,0,CW45,0)';
      PINUSE='POWER';
      NO_LOAD_CHECK='Both';
      NO_IO_CHECK='Both';
      NO_ASSERT_CHECK='TRUE';
      NO_DIR_CHECK='TRUE';
      ALLOW_CONNECT='TRUE';
    'VSS_CW48':
      PIN_NUMBER='(0,0,0,0,0,0,0,0,0,0,0,0,0,0,0,0,0,0,0,0,0,0,0,0,0,0,0,0,0,0,0~
,0,0,0,0,0,0,0,CW48,0)';
      PINUSE='POWER';
      NO_LOAD_CHECK='Both';
      NO_IO_CHECK='Both';
      NO_ASSERT_CHECK='TRUE';
      NO_DIR_CHECK='TRUE';
      ALLOW_CONNECT='TRUE';
    'VSS_CW51':
      PIN_NUMBER='(0,0,0,0,0,0,0,0,0,0,0,0,0,0,0,0,0,0,0,0,0,0,0,0,0,0,0,0,0,0,0~
,0,0,0,0,0,0,0,CW51,0)';
      PINUSE='POWER';
      NO_LOAD_CHECK='Both';
      NO_IO_CHECK='Both';
      NO_ASSERT_CHECK='TRUE';
      NO_DIR_CHECK='TRUE';
      ALLOW_CONNECT='TRUE';
    'VSS_CW54':
      PIN_NUMBER='(0,0,0,0,0,0,0,0,0,0,0,0,0,0,0,0,0,0,0,0,0,0,0,0,0,0,0,0,0,0,0~
,0,0,0,0,0,0,0,CW54,0)';
      PINUSE='POWER';
      NO_LOAD_CHECK='Both';
      NO_IO_CHECK='Both';
      NO_ASSERT_CHECK='TRUE';
      NO_DIR_CHECK='TRUE';
      ALLOW_CONNECT='TRUE';
    'VSS_CW56':
      PIN_NUMBER='(0,0,0,0,0,0,0,0,0,0,0,0,0,0,0,0,0,0,0,0,0,0,0,0,0,0,0,0,0,0,0~
,0,0,0,0,0,0,0,CW56,0)';
      PINUSE='POWER';
      NO_LOAD_CHECK='Both';
      NO_IO_CHECK='Both';
      NO_ASSERT_CHECK='TRUE';
      NO_DIR_CHECK='TRUE';
      ALLOW_CONNECT='TRUE';
    'VSS_CW61':
      PIN_NUMBER='(0,0,0,0,0,0,0,0,0,0,0,0,0,0,0,0,0,0,0,0,0,0,0,0,0,0,0,0,0,0,0~
,0,0,0,0,0,0,0,CW61,0)';
      PINUSE='POWER';
      NO_LOAD_CHECK='Both';
      NO_IO_CHECK='Both';
      NO_ASSERT_CHECK='TRUE';
      NO_DIR_CHECK='TRUE';
      ALLOW_CONNECT='TRUE';
    'VSS_CW63':
      PIN_NUMBER='(0,0,0,0,0,0,0,0,0,0,0,0,0,0,0,0,0,0,0,0,0,0,0,0,0,0,0,0,0,0,0~
,0,0,0,0,0,0,0,CW63,0)';
      PINUSE='POWER';
      NO_LOAD_CHECK='Both';
      NO_IO_CHECK='Both';
      NO_ASSERT_CHECK='TRUE';
      NO_DIR_CHECK='TRUE';
      ALLOW_CONNECT='TRUE';
    'VSS_CW68':
      PIN_NUMBER='(0,0,0,0,0,0,0,0,0,0,0,0,0,0,0,0,0,0,0,0,0,0,0,0,0,0,0,0,0,0,0~
,0,0,0,0,0,0,0,CW68,0)';
      PINUSE='POWER';
      NO_LOAD_CHECK='Both';
      NO_IO_CHECK='Both';
      NO_ASSERT_CHECK='TRUE';
      NO_DIR_CHECK='TRUE';
      ALLOW_CONNECT='TRUE';
    'VSS_CW70':
      PIN_NUMBER='(0,0,0,0,0,0,0,0,0,0,0,0,0,0,0,0,0,0,0,0,0,0,0,0,0,0,0,0,0,0,0~
,0,0,0,0,0,0,0,CW70,0)';
      PINUSE='POWER';
      NO_LOAD_CHECK='Both';
      NO_IO_CHECK='Both';
      NO_ASSERT_CHECK='TRUE';
      NO_DIR_CHECK='TRUE';
      ALLOW_CONNECT='TRUE';
    'VSS_CW75':
      PIN_NUMBER='(0,0,0,0,0,0,0,0,0,0,0,0,0,0,0,0,0,0,0,0,0,0,0,0,0,0,0,0,0,0,0~
,0,0,0,0,0,0,0,CW75,0)';
      PINUSE='POWER';
      NO_LOAD_CHECK='Both';
      NO_IO_CHECK='Both';
      NO_ASSERT_CHECK='TRUE';
      NO_DIR_CHECK='TRUE';
      ALLOW_CONNECT='TRUE';
    'VSS_CY3':
      PIN_NUMBER='(0,0,0,0,0,0,0,0,0,0,0,0,0,0,0,0,0,0,0,0,0,0,0,0,0,0,0,0,0,0,0~
,0,0,0,0,0,0,0,CY3,0)';
      PINUSE='POWER';
      NO_LOAD_CHECK='Both';
      NO_IO_CHECK='Both';
      NO_ASSERT_CHECK='TRUE';
      NO_DIR_CHECK='TRUE';
      ALLOW_CONNECT='TRUE';
    'VSS_CY5':
      PIN_NUMBER='(0,0,0,0,0,0,0,0,0,0,0,0,0,0,0,0,0,0,0,0,0,0,0,0,0,0,0,0,0,0,0~
,0,0,0,0,0,0,0,CY5,0)';
      PINUSE='POWER';
      NO_LOAD_CHECK='Both';
      NO_IO_CHECK='Both';
      NO_ASSERT_CHECK='TRUE';
      NO_DIR_CHECK='TRUE';
      ALLOW_CONNECT='TRUE';
    'VSS_CY8':
      PIN_NUMBER='(0,0,0,0,0,0,0,0,0,0,0,0,0,0,0,0,0,0,0,0,0,0,0,0,0,0,0,0,0,0,0~
,0,0,0,0,0,0,0,CY8,0)';
      PINUSE='POWER';
      NO_LOAD_CHECK='Both';
      NO_IO_CHECK='Both';
      NO_ASSERT_CHECK='TRUE';
      NO_DIR_CHECK='TRUE';
      ALLOW_CONNECT='TRUE';
    'VSS_CY10':
      PIN_NUMBER='(0,0,0,0,0,0,0,0,0,0,0,0,0,0,0,0,0,0,0,0,0,0,0,0,0,0,0,0,0,0,0~
,0,0,0,0,0,0,0,CY10,0)';
      PINUSE='POWER';
      NO_LOAD_CHECK='Both';
      NO_IO_CHECK='Both';
      NO_ASSERT_CHECK='TRUE';
      NO_DIR_CHECK='TRUE';
      ALLOW_CONNECT='TRUE';
    'VSS_CY12':
      PIN_NUMBER='(0,0,0,0,0,0,0,0,0,0,0,0,0,0,0,0,0,0,0,0,0,0,0,0,0,0,0,0,0,0,0~
,0,0,0,0,0,0,0,CY12,0)';
      PINUSE='POWER';
      NO_LOAD_CHECK='Both';
      NO_IO_CHECK='Both';
      NO_ASSERT_CHECK='TRUE';
      NO_DIR_CHECK='TRUE';
      ALLOW_CONNECT='TRUE';
    'VSS_CY15':
      PIN_NUMBER='(0,0,0,0,0,0,0,0,0,0,0,0,0,0,0,0,0,0,0,0,0,0,0,0,0,0,0,0,0,0,0~
,0,0,0,0,0,0,0,CY15,0)';
      PINUSE='POWER';
      NO_LOAD_CHECK='Both';
      NO_IO_CHECK='Both';
      NO_ASSERT_CHECK='TRUE';
      NO_DIR_CHECK='TRUE';
      ALLOW_CONNECT='TRUE';
    'VSS_CY17':
      PIN_NUMBER='(0,0,0,0,0,0,0,0,0,0,0,0,0,0,0,0,0,0,0,0,0,0,0,0,0,0,0,0,0,0,0~
,0,0,0,0,0,0,0,CY17,0)';
      PINUSE='POWER';
      NO_LOAD_CHECK='Both';
      NO_IO_CHECK='Both';
      NO_ASSERT_CHECK='TRUE';
      NO_DIR_CHECK='TRUE';
      ALLOW_CONNECT='TRUE';
    'VSS_CY19':
      PIN_NUMBER='(0,0,0,0,0,0,0,0,0,0,0,0,0,0,0,0,0,0,0,0,0,0,0,0,0,0,0,0,0,0,0~
,0,0,0,0,0,0,0,CY19,0)';
      PINUSE='POWER';
      NO_LOAD_CHECK='Both';
      NO_IO_CHECK='Both';
      NO_ASSERT_CHECK='TRUE';
      NO_DIR_CHECK='TRUE';
      ALLOW_CONNECT='TRUE';
    'VSS_CY23':
      PIN_NUMBER='(0,0,0,0,0,0,0,0,0,0,0,0,0,0,0,0,0,0,0,0,0,0,0,0,0,0,0,0,0,0,0~
,0,0,0,0,0,0,0,CY23,0)';
      PINUSE='POWER';
      NO_LOAD_CHECK='Both';
      NO_IO_CHECK='Both';
      NO_ASSERT_CHECK='TRUE';
      NO_DIR_CHECK='TRUE';
      ALLOW_CONNECT='TRUE';
    'VSS_CY24':
      PIN_NUMBER='(0,0,0,0,0,0,0,0,0,0,0,0,0,0,0,0,0,0,0,0,0,0,0,0,0,0,0,0,0,0,0~
,0,0,0,0,0,0,0,CY24,0)';
      PINUSE='POWER';
      NO_LOAD_CHECK='Both';
      NO_IO_CHECK='Both';
      NO_ASSERT_CHECK='TRUE';
      NO_DIR_CHECK='TRUE';
      ALLOW_CONNECT='TRUE';
    'VSS_CY25':
      PIN_NUMBER='(0,0,0,0,0,0,0,0,0,0,0,0,0,0,0,0,0,0,0,0,0,0,0,0,0,0,0,0,0,0,0~
,0,0,0,0,0,0,0,CY25,0)';
      PINUSE='POWER';
      NO_LOAD_CHECK='Both';
      NO_IO_CHECK='Both';
      NO_ASSERT_CHECK='TRUE';
      NO_DIR_CHECK='TRUE';
      ALLOW_CONNECT='TRUE';
    'VSS_CY26':
      PIN_NUMBER='(0,0,0,0,0,0,0,0,0,0,0,0,0,0,0,0,0,0,0,0,0,0,0,0,0,0,0,0,0,0,0~
,0,0,0,0,0,0,0,CY26,0)';
      PINUSE='POWER';
      NO_LOAD_CHECK='Both';
      NO_IO_CHECK='Both';
      NO_ASSERT_CHECK='TRUE';
      NO_DIR_CHECK='TRUE';
      ALLOW_CONNECT='TRUE';
    'VSS_CY27':
      PIN_NUMBER='(0,0,0,0,0,0,0,0,0,0,0,0,0,0,0,0,0,0,0,0,0,0,0,0,0,0,0,0,0,0,0~
,0,0,0,0,0,0,0,CY27,0)';
      PINUSE='POWER';
      NO_LOAD_CHECK='Both';
      NO_IO_CHECK='Both';
      NO_ASSERT_CHECK='TRUE';
      NO_DIR_CHECK='TRUE';
      ALLOW_CONNECT='TRUE';
    'VSS_CY28':
      PIN_NUMBER='(0,0,0,0,0,0,0,0,0,0,0,0,0,0,0,0,0,0,0,0,0,0,0,0,0,0,0,0,0,0,0~
,0,0,0,0,0,0,0,CY28,0)';
      PINUSE='POWER';
      NO_LOAD_CHECK='Both';
      NO_IO_CHECK='Both';
      NO_ASSERT_CHECK='TRUE';
      NO_DIR_CHECK='TRUE';
      ALLOW_CONNECT='TRUE';
    'VSS_CY29':
      PIN_NUMBER='(0,0,0,0,0,0,0,0,0,0,0,0,0,0,0,0,0,0,0,0,0,0,0,0,0,0,0,0,0,0,0~
,0,0,0,0,0,0,0,CY29,0)';
      PINUSE='POWER';
      NO_LOAD_CHECK='Both';
      NO_IO_CHECK='Both';
      NO_ASSERT_CHECK='TRUE';
      NO_DIR_CHECK='TRUE';
      ALLOW_CONNECT='TRUE';
    'VSS_CY30':
      PIN_NUMBER='(0,0,0,0,0,0,0,0,0,0,0,0,0,0,0,0,0,0,0,0,0,0,0,0,0,0,0,0,0,0,0~
,0,0,0,0,0,0,0,CY30,0)';
      PINUSE='POWER';
      NO_LOAD_CHECK='Both';
      NO_IO_CHECK='Both';
      NO_ASSERT_CHECK='TRUE';
      NO_DIR_CHECK='TRUE';
      ALLOW_CONNECT='TRUE';
    'VSS_CY31':
      PIN_NUMBER='(0,0,0,0,0,0,0,0,0,0,0,0,0,0,0,0,0,0,0,0,0,0,0,0,0,0,0,0,0,0,0~
,0,0,0,0,0,0,0,CY31,0)';
      PINUSE='POWER';
      NO_LOAD_CHECK='Both';
      NO_IO_CHECK='Both';
      NO_ASSERT_CHECK='TRUE';
      NO_DIR_CHECK='TRUE';
      ALLOW_CONNECT='TRUE';
    'VSS_CY33':
      PIN_NUMBER='(0,0,0,0,0,0,0,0,0,0,0,0,0,0,0,0,0,0,0,0,0,0,0,0,0,0,0,0,0,0,0~
,0,0,0,0,0,0,0,CY33,0)';
      PINUSE='POWER';
      NO_LOAD_CHECK='Both';
      NO_IO_CHECK='Both';
      NO_ASSERT_CHECK='TRUE';
      NO_DIR_CHECK='TRUE';
      ALLOW_CONNECT='TRUE';
    'VSS_CY34':
      PIN_NUMBER='(0,0,0,0,0,0,0,0,0,0,0,0,0,0,0,0,0,0,0,0,0,0,0,0,0,0,0,0,0,0,0~
,0,0,0,0,0,0,0,CY34,0)';
      PINUSE='POWER';
      NO_LOAD_CHECK='Both';
      NO_IO_CHECK='Both';
      NO_ASSERT_CHECK='TRUE';
      NO_DIR_CHECK='TRUE';
      ALLOW_CONNECT='TRUE';
    'VSS_CY37':
      PIN_NUMBER='(0,0,0,0,0,0,0,0,0,0,0,0,0,0,0,0,0,0,0,0,0,0,0,0,0,0,0,0,0,0,0~
,0,0,0,0,0,0,0,CY37,0)';
      PINUSE='POWER';
      NO_LOAD_CHECK='Both';
      NO_IO_CHECK='Both';
      NO_ASSERT_CHECK='TRUE';
      NO_DIR_CHECK='TRUE';
      ALLOW_CONNECT='TRUE';
    'VSS_CY39':
      PIN_NUMBER='(0,0,0,0,0,0,0,0,0,0,0,0,0,0,0,0,0,0,0,0,0,0,0,0,0,0,0,0,0,0,0~
,0,0,0,0,0,0,0,CY39,0)';
      PINUSE='POWER';
      NO_LOAD_CHECK='Both';
      NO_IO_CHECK='Both';
      NO_ASSERT_CHECK='TRUE';
      NO_DIR_CHECK='TRUE';
      ALLOW_CONNECT='TRUE';
    'VSS_CY42':
      PIN_NUMBER='(0,0,0,0,0,0,0,0,0,0,0,0,0,0,0,0,0,0,0,0,0,0,0,0,0,0,0,0,0,0,0~
,0,0,0,0,0,0,0,CY42,0)';
      PINUSE='POWER';
      NO_LOAD_CHECK='Both';
      NO_IO_CHECK='Both';
      NO_ASSERT_CHECK='TRUE';
      NO_DIR_CHECK='TRUE';
      ALLOW_CONNECT='TRUE';
    'VSS_CY43':
      PIN_NUMBER='(0,0,0,0,0,0,0,0,0,0,0,0,0,0,0,0,0,0,0,0,0,0,0,0,0,0,0,0,0,0,0~
,0,0,0,0,0,0,0,CY43,0)';
      PINUSE='POWER';
      NO_LOAD_CHECK='Both';
      NO_IO_CHECK='Both';
      NO_ASSERT_CHECK='TRUE';
      NO_DIR_CHECK='TRUE';
      ALLOW_CONNECT='TRUE';
    'VSS_CY44':
      PIN_NUMBER='(0,0,0,0,0,0,0,0,0,0,0,0,0,0,0,0,0,0,0,0,0,0,0,0,0,0,0,0,0,0,0~
,0,0,0,0,0,0,0,CY44,0)';
      PINUSE='POWER';
      NO_LOAD_CHECK='Both';
      NO_IO_CHECK='Both';
      NO_ASSERT_CHECK='TRUE';
      NO_DIR_CHECK='TRUE';
      ALLOW_CONNECT='TRUE';
    'VSS_CY45':
      PIN_NUMBER='(0,0,0,0,0,0,0,0,0,0,0,0,0,0,0,0,0,0,0,0,0,0,0,0,0,0,0,0,0,0,0~
,0,0,0,0,0,0,0,CY45,0)';
      PINUSE='POWER';
      NO_LOAD_CHECK='Both';
      NO_IO_CHECK='Both';
      NO_ASSERT_CHECK='TRUE';
      NO_DIR_CHECK='TRUE';
      ALLOW_CONNECT='TRUE';
    'VSS_CY46':
      PIN_NUMBER='(0,0,0,0,0,0,0,0,0,0,0,0,0,0,0,0,0,0,0,0,0,0,0,0,0,0,0,0,0,0,0~
,0,0,0,0,0,0,0,CY46,0)';
      PINUSE='POWER';
      NO_LOAD_CHECK='Both';
      NO_IO_CHECK='Both';
      NO_ASSERT_CHECK='TRUE';
      NO_DIR_CHECK='TRUE';
      ALLOW_CONNECT='TRUE';
    'VSS_CY49':
      PIN_NUMBER='(0,0,0,0,0,0,0,0,0,0,0,0,0,0,0,0,0,0,0,0,0,0,0,0,0,0,0,0,0,0,0~
,0,0,0,0,0,0,0,CY49,0)';
      PINUSE='POWER';
      NO_LOAD_CHECK='Both';
      NO_IO_CHECK='Both';
      NO_ASSERT_CHECK='TRUE';
      NO_DIR_CHECK='TRUE';
      ALLOW_CONNECT='TRUE';
    'VSS_CY50':
      PIN_NUMBER='(0,0,0,0,0,0,0,0,0,0,0,0,0,0,0,0,0,0,0,0,0,0,0,0,0,0,0,0,0,0,0~
,0,0,0,0,0,0,0,CY50,0)';
      PINUSE='POWER';
      NO_LOAD_CHECK='Both';
      NO_IO_CHECK='Both';
      NO_ASSERT_CHECK='TRUE';
      NO_DIR_CHECK='TRUE';
      ALLOW_CONNECT='TRUE';
    'VSS_CY51':
      PIN_NUMBER='(0,0,0,0,0,0,0,0,0,0,0,0,0,0,0,0,0,0,0,0,0,0,0,0,0,0,0,0,0,0,0~
,0,0,0,0,0,0,0,CY51,0)';
      PINUSE='POWER';
      NO_LOAD_CHECK='Both';
      NO_IO_CHECK='Both';
      NO_ASSERT_CHECK='TRUE';
      NO_DIR_CHECK='TRUE';
      ALLOW_CONNECT='TRUE';
    'VSS_CY52':
      PIN_NUMBER='(0,0,0,0,0,0,0,0,0,0,0,0,0,0,0,0,0,0,0,0,0,0,0,0,0,0,0,0,0,0,0~
,0,0,0,0,0,0,0,CY52,0)';
      PINUSE='POWER';
      NO_LOAD_CHECK='Both';
      NO_IO_CHECK='Both';
      NO_ASSERT_CHECK='TRUE';
      NO_DIR_CHECK='TRUE';
      ALLOW_CONNECT='TRUE';
    'VSS_CY53':
      PIN_NUMBER='(0,0,0,0,0,0,0,0,0,0,0,0,0,0,0,0,0,0,0,0,0,0,0,0,0,0,0,0,0,0,0~
,0,0,0,0,0,0,0,CY53,0)';
      PINUSE='POWER';
      NO_LOAD_CHECK='Both';
      NO_IO_CHECK='Both';
      NO_ASSERT_CHECK='TRUE';
      NO_DIR_CHECK='TRUE';
      ALLOW_CONNECT='TRUE';
    'VSS_CY59':
      PIN_NUMBER='(0,0,0,0,0,0,0,0,0,0,0,0,0,0,0,0,0,0,0,0,0,0,0,0,0,0,0,0,0,0,0~
,0,0,0,0,0,0,0,CY59,0)';
      PINUSE='POWER';
      NO_LOAD_CHECK='Both';
      NO_IO_CHECK='Both';
      NO_ASSERT_CHECK='TRUE';
      NO_DIR_CHECK='TRUE';
      ALLOW_CONNECT='TRUE';
    'VSS_CY61':
      PIN_NUMBER='(0,0,0,0,0,0,0,0,0,0,0,0,0,0,0,0,0,0,0,0,0,0,0,0,0,0,0,0,0,0,0~
,0,0,0,0,0,0,0,CY61,0)';
      PINUSE='POWER';
      NO_LOAD_CHECK='Both';
      NO_IO_CHECK='Both';
      NO_ASSERT_CHECK='TRUE';
      NO_DIR_CHECK='TRUE';
      ALLOW_CONNECT='TRUE';
    'VSS_CY71':
      PIN_NUMBER='(0,0,0,0,0,0,0,0,0,0,0,0,0,0,0,0,0,0,0,0,0,0,0,0,0,0,0,0,0,0,0~
,0,0,0,0,0,0,0,CY71,0)';
      PINUSE='POWER';
      NO_LOAD_CHECK='Both';
      NO_IO_CHECK='Both';
      NO_ASSERT_CHECK='TRUE';
      NO_DIR_CHECK='TRUE';
      ALLOW_CONNECT='TRUE';
    'VSS_CY73':
      PIN_NUMBER='(0,0,0,0,0,0,0,0,0,0,0,0,0,0,0,0,0,0,0,0,0,0,0,0,0,0,0,0,0,0,0~
,0,0,0,0,0,0,0,CY73,0)';
      PINUSE='POWER';
      NO_LOAD_CHECK='Both';
      NO_IO_CHECK='Both';
      NO_ASSERT_CHECK='TRUE';
      NO_DIR_CHECK='TRUE';
      ALLOW_CONNECT='TRUE';
    'VSS_DA1':
      PIN_NUMBER='(0,0,0,0,0,0,0,0,0,0,0,0,0,0,0,0,0,0,0,0,0,0,0,0,0,0,0,0,0,0,0~
,0,0,0,0,0,0,0,DA1,0)';
      PINUSE='POWER';
      NO_LOAD_CHECK='Both';
      NO_IO_CHECK='Both';
      NO_ASSERT_CHECK='TRUE';
      NO_DIR_CHECK='TRUE';
      ALLOW_CONNECT='TRUE';
    'VSS_DA4':
      PIN_NUMBER='(0,0,0,0,0,0,0,0,0,0,0,0,0,0,0,0,0,0,0,0,0,0,0,0,0,0,0,0,0,0,0~
,0,0,0,0,0,0,0,DA4,0)';
      PINUSE='POWER';
      NO_LOAD_CHECK='Both';
      NO_IO_CHECK='Both';
      NO_ASSERT_CHECK='TRUE';
      NO_DIR_CHECK='TRUE';
      ALLOW_CONNECT='TRUE';
    'VSS_DA6':
      PIN_NUMBER='(0,0,0,0,0,0,0,0,0,0,0,0,0,0,0,0,0,0,0,0,0,0,0,0,0,0,0,0,0,0,0~
,0,0,0,0,0,0,0,DA6,0)';
      PINUSE='POWER';
      NO_LOAD_CHECK='Both';
      NO_IO_CHECK='Both';
      NO_ASSERT_CHECK='TRUE';
      NO_DIR_CHECK='TRUE';
      ALLOW_CONNECT='TRUE';
    'VSS_DA8':
      PIN_NUMBER='(0,0,0,0,0,0,0,0,0,0,0,0,0,0,0,0,0,0,0,0,0,0,0,0,0,0,0,0,0,0,0~
,0,0,0,0,0,0,0,DA8,0)';
      PINUSE='POWER';
      NO_LOAD_CHECK='Both';
      NO_IO_CHECK='Both';
      NO_ASSERT_CHECK='TRUE';
      NO_DIR_CHECK='TRUE';
      ALLOW_CONNECT='TRUE';
    'VSS_DA11':
      PIN_NUMBER='(0,0,0,0,0,0,0,0,0,0,0,0,0,0,0,0,0,0,0,0,0,0,0,0,0,0,0,0,0,0,0~
,0,0,0,0,0,0,0,DA11,0)';
      PINUSE='POWER';
      NO_LOAD_CHECK='Both';
      NO_IO_CHECK='Both';
      NO_ASSERT_CHECK='TRUE';
      NO_DIR_CHECK='TRUE';
      ALLOW_CONNECT='TRUE';
    'VSS_DA22':
      PIN_NUMBER='(0,0,0,0,0,0,0,0,0,0,0,0,0,0,0,0,0,0,0,0,0,0,0,0,0,0,0,0,0,0,0~
,0,0,0,0,0,0,0,DA22,0)';
      PINUSE='POWER';
      NO_LOAD_CHECK='Both';
      NO_IO_CHECK='Both';
      NO_ASSERT_CHECK='TRUE';
      NO_DIR_CHECK='TRUE';
      ALLOW_CONNECT='TRUE';
    'VSS_DA25':
      PIN_NUMBER='(0,0,0,0,0,0,0,0,0,0,0,0,0,0,0,0,0,0,0,0,0,0,0,0,0,0,0,0,0,0,0~
,0,0,0,0,0,0,0,DA25,0)';
      PINUSE='POWER';
      NO_LOAD_CHECK='Both';
      NO_IO_CHECK='Both';
      NO_ASSERT_CHECK='TRUE';
      NO_DIR_CHECK='TRUE';
      ALLOW_CONNECT='TRUE';
    'VSS_DA28':
      PIN_NUMBER='(0,0,0,0,0,0,0,0,0,0,0,0,0,0,0,0,0,0,0,0,0,0,0,0,0,0,0,0,0,0,0~
,0,0,0,0,0,0,0,DA28,0)';
      PINUSE='POWER';
      NO_LOAD_CHECK='Both';
      NO_IO_CHECK='Both';
      NO_ASSERT_CHECK='TRUE';
      NO_DIR_CHECK='TRUE';
      ALLOW_CONNECT='TRUE';
    'VSS_DA31':
      PIN_NUMBER='(0,0,0,0,0,0,0,0,0,0,0,0,0,0,0,0,0,0,0,0,0,0,0,0,0,0,0,0,0,0,0~
,0,0,0,0,0,0,0,DA31,0)';
      PINUSE='POWER';
      NO_LOAD_CHECK='Both';
      NO_IO_CHECK='Both';
      NO_ASSERT_CHECK='TRUE';
      NO_DIR_CHECK='TRUE';
      ALLOW_CONNECT='TRUE';
    'VSS_DA34':
      PIN_NUMBER='(0,0,0,0,0,0,0,0,0,0,0,0,0,0,0,0,0,0,0,0,0,0,0,0,0,0,0,0,0,0,0~
,0,0,0,0,0,0,0,DA34,0)';
      PINUSE='POWER';
      NO_LOAD_CHECK='Both';
      NO_IO_CHECK='Both';
      NO_ASSERT_CHECK='TRUE';
      NO_DIR_CHECK='TRUE';
      ALLOW_CONNECT='TRUE';
    'VSS_DA42':
      PIN_NUMBER='(0,0,0,0,0,0,0,0,0,0,0,0,0,0,0,0,0,0,0,0,0,0,0,0,0,0,0,0,0,0,0~
,0,0,0,0,0,0,0,DA42,0)';
      PINUSE='POWER';
      NO_LOAD_CHECK='Both';
      NO_IO_CHECK='Both';
      NO_ASSERT_CHECK='TRUE';
      NO_DIR_CHECK='TRUE';
      ALLOW_CONNECT='TRUE';
    'VSS_DA58':
      PIN_NUMBER='(0,0,0,0,0,0,0,0,0,0,0,0,0,0,0,0,0,0,0,0,0,0,0,0,0,0,0,0,0,0,0~
,0,0,0,0,0,0,0,DA58,0)';
      PINUSE='POWER';
      NO_LOAD_CHECK='Both';
      NO_IO_CHECK='Both';
      NO_ASSERT_CHECK='TRUE';
      NO_DIR_CHECK='TRUE';
      ALLOW_CONNECT='TRUE';
    'VSS_DA61':
      PIN_NUMBER='(0,0,0,0,0,0,0,0,0,0,0,0,0,0,0,0,0,0,0,0,0,0,0,0,0,0,0,0,0,0,0~
,0,0,0,0,0,0,0,DA61,0)';
      PINUSE='POWER';
      NO_LOAD_CHECK='Both';
      NO_IO_CHECK='Both';
      NO_ASSERT_CHECK='TRUE';
      NO_DIR_CHECK='TRUE';
      ALLOW_CONNECT='TRUE';
    'VSS_DA63':
      PIN_NUMBER='(0,0,0,0,0,0,0,0,0,0,0,0,0,0,0,0,0,0,0,0,0,0,0,0,0,0,0,0,0,0,0~
,0,0,0,0,0,0,0,DA63,0)';
      PINUSE='POWER';
      NO_LOAD_CHECK='Both';
      NO_IO_CHECK='Both';
      NO_ASSERT_CHECK='TRUE';
      NO_DIR_CHECK='TRUE';
      ALLOW_CONNECT='TRUE';
    'VSS_DA65':
      PIN_NUMBER='(0,0,0,0,0,0,0,0,0,0,0,0,0,0,0,0,0,0,0,0,0,0,0,0,0,0,0,0,0,0,0~
,0,0,0,0,0,0,0,DA65,0)';
      PINUSE='POWER';
      NO_LOAD_CHECK='Both';
      NO_IO_CHECK='Both';
      NO_ASSERT_CHECK='TRUE';
      NO_DIR_CHECK='TRUE';
      ALLOW_CONNECT='TRUE';
    'VSS_DA68':
      PIN_NUMBER='(0,0,0,0,0,0,0,0,0,0,0,0,0,0,0,0,0,0,0,0,0,0,0,0,0,0,0,0,0,0,0~
,0,0,0,0,0,0,0,DA68,0)';
      PINUSE='POWER';
      NO_LOAD_CHECK='Both';
      NO_IO_CHECK='Both';
      NO_ASSERT_CHECK='TRUE';
      NO_DIR_CHECK='TRUE';
      ALLOW_CONNECT='TRUE';
    'VSS_DA70':
      PIN_NUMBER='(0,0,0,0,0,0,0,0,0,0,0,0,0,0,0,0,0,0,0,0,0,0,0,0,0,0,0,0,0,0,0~
,0,0,0,0,0,0,0,DA70,0)';
      PINUSE='POWER';
      NO_LOAD_CHECK='Both';
      NO_IO_CHECK='Both';
      NO_ASSERT_CHECK='TRUE';
      NO_DIR_CHECK='TRUE';
      ALLOW_CONNECT='TRUE';
    'VSS_DB15':
      PIN_NUMBER='(0,0,0,0,0,0,0,0,0,0,0,0,0,0,0,0,0,0,0,0,0,0,0,0,0,0,0,0,0,0,0~
,0,0,0,0,0,0,0,0,DB15)';
      PINUSE='POWER';
      NO_LOAD_CHECK='Both';
      NO_IO_CHECK='Both';
      NO_ASSERT_CHECK='TRUE';
      NO_DIR_CHECK='TRUE';
      ALLOW_CONNECT='TRUE';
    'VSS_DB17':
      PIN_NUMBER='(0,0,0,0,0,0,0,0,0,0,0,0,0,0,0,0,0,0,0,0,0,0,0,0,0,0,0,0,0,0,0~
,0,0,0,0,0,0,0,0,DB17)';
      PINUSE='POWER';
      NO_LOAD_CHECK='Both';
      NO_IO_CHECK='Both';
      NO_ASSERT_CHECK='TRUE';
      NO_DIR_CHECK='TRUE';
      ALLOW_CONNECT='TRUE';
    'VSS_DB22':
      PIN_NUMBER='(0,0,0,0,0,0,0,0,0,0,0,0,0,0,0,0,0,0,0,0,0,0,0,0,0,0,0,0,0,0,0~
,0,0,0,0,0,0,0,0,DB22)';
      PINUSE='POWER';
      NO_LOAD_CHECK='Both';
      NO_IO_CHECK='Both';
      NO_ASSERT_CHECK='TRUE';
      NO_DIR_CHECK='TRUE';
      ALLOW_CONNECT='TRUE';
    'VSS_DB25':
      PIN_NUMBER='(0,0,0,0,0,0,0,0,0,0,0,0,0,0,0,0,0,0,0,0,0,0,0,0,0,0,0,0,0,0,0~
,0,0,0,0,0,0,0,0,DB25)';
      PINUSE='POWER';
      NO_LOAD_CHECK='Both';
      NO_IO_CHECK='Both';
      NO_ASSERT_CHECK='TRUE';
      NO_DIR_CHECK='TRUE';
      ALLOW_CONNECT='TRUE';
    'VSS_DB48':
      PIN_NUMBER='(0,0,0,0,0,0,0,0,0,0,0,0,0,0,0,0,0,0,0,0,0,0,0,0,0,0,0,0,0,0,0~
,0,0,0,0,0,0,0,0,DB48)';
      PINUSE='POWER';
      NO_LOAD_CHECK='Both';
      NO_IO_CHECK='Both';
      NO_ASSERT_CHECK='TRUE';
      NO_DIR_CHECK='TRUE';
      ALLOW_CONNECT='TRUE';
    'VSS_DB51':
      PIN_NUMBER='(0,0,0,0,0,0,0,0,0,0,0,0,0,0,0,0,0,0,0,0,0,0,0,0,0,0,0,0,0,0,0~
,0,0,0,0,0,0,0,0,DB51)';
      PINUSE='POWER';
      NO_LOAD_CHECK='Both';
      NO_IO_CHECK='Both';
      NO_ASSERT_CHECK='TRUE';
      NO_DIR_CHECK='TRUE';
      ALLOW_CONNECT='TRUE';
    'VSS_DB54':
      PIN_NUMBER='(0,0,0,0,0,0,0,0,0,0,0,0,0,0,0,0,0,0,0,0,0,0,0,0,0,0,0,0,0,0,0~
,0,0,0,0,0,0,0,0,DB54)';
      PINUSE='POWER';
      NO_LOAD_CHECK='Both';
      NO_IO_CHECK='Both';
      NO_ASSERT_CHECK='TRUE';
      NO_DIR_CHECK='TRUE';
      ALLOW_CONNECT='TRUE';
    'VSS_DB59':
      PIN_NUMBER='(0,0,0,0,0,0,0,0,0,0,0,0,0,0,0,0,0,0,0,0,0,0,0,0,0,0,0,0,0,0,0~
,0,0,0,0,0,0,0,0,DB59)';
      PINUSE='POWER';
      NO_LOAD_CHECK='Both';
      NO_IO_CHECK='Both';
      NO_ASSERT_CHECK='TRUE';
      NO_DIR_CHECK='TRUE';
      ALLOW_CONNECT='TRUE';
    'VSS_DC13':
      PIN_NUMBER='(0,0,0,0,0,0,0,0,0,0,0,0,0,0,0,0,0,0,0,0,0,0,0,0,0,0,0,0,0,0,0~
,0,0,0,0,0,0,0,0,DC13)';
      PINUSE='POWER';
      NO_LOAD_CHECK='Both';
      NO_IO_CHECK='Both';
      NO_ASSERT_CHECK='TRUE';
      NO_DIR_CHECK='TRUE';
      ALLOW_CONNECT='TRUE';
    'VSS_DC15':
      PIN_NUMBER='(0,0,0,0,0,0,0,0,0,0,0,0,0,0,0,0,0,0,0,0,0,0,0,0,0,0,0,0,0,0,0~
,0,0,0,0,0,0,0,0,DC15)';
      PINUSE='POWER';
      NO_LOAD_CHECK='Both';
      NO_IO_CHECK='Both';
      NO_ASSERT_CHECK='TRUE';
      NO_DIR_CHECK='TRUE';
      ALLOW_CONNECT='TRUE';
    'VSS_DC45':
      PIN_NUMBER='(0,0,0,0,0,0,0,0,0,0,0,0,0,0,0,0,0,0,0,0,0,0,0,0,0,0,0,0,0,0,0~
,0,0,0,0,0,0,0,0,DC45)';
      PINUSE='POWER';
      NO_LOAD_CHECK='Both';
      NO_IO_CHECK='Both';
      NO_ASSERT_CHECK='TRUE';
      NO_DIR_CHECK='TRUE';
      ALLOW_CONNECT='TRUE';
    'VSS_DC48':
      PIN_NUMBER='(0,0,0,0,0,0,0,0,0,0,0,0,0,0,0,0,0,0,0,0,0,0,0,0,0,0,0,0,0,0,0~
,0,0,0,0,0,0,0,0,DC48)';
      PINUSE='POWER';
      NO_LOAD_CHECK='Both';
      NO_IO_CHECK='Both';
      NO_ASSERT_CHECK='TRUE';
      NO_DIR_CHECK='TRUE';
      ALLOW_CONNECT='TRUE';
    'VSS_DC51':
      PIN_NUMBER='(0,0,0,0,0,0,0,0,0,0,0,0,0,0,0,0,0,0,0,0,0,0,0,0,0,0,0,0,0,0,0~
,0,0,0,0,0,0,0,0,DC51)';
      PINUSE='POWER';
      NO_LOAD_CHECK='Both';
      NO_IO_CHECK='Both';
      NO_ASSERT_CHECK='TRUE';
      NO_DIR_CHECK='TRUE';
      ALLOW_CONNECT='TRUE';
    'VSS_DC70':
      PIN_NUMBER='(0,0,0,0,0,0,0,0,0,0,0,0,0,0,0,0,0,0,0,0,0,0,0,0,0,0,0,0,0,0,0~
,0,0,0,0,0,0,0,0,DC70)';
      PINUSE='POWER';
      NO_LOAD_CHECK='Both';
      NO_IO_CHECK='Both';
      NO_ASSERT_CHECK='TRUE';
      NO_DIR_CHECK='TRUE';
      ALLOW_CONNECT='TRUE';
    'VSS_DC72':
      PIN_NUMBER='(0,0,0,0,0,0,0,0,0,0,0,0,0,0,0,0,0,0,0,0,0,0,0,0,0,0,0,0,0,0,0~
,0,0,0,0,0,0,0,0,DC72)';
      PINUSE='POWER';
      NO_LOAD_CHECK='Both';
      NO_IO_CHECK='Both';
      NO_ASSERT_CHECK='TRUE';
      NO_DIR_CHECK='TRUE';
      ALLOW_CONNECT='TRUE';
    'VSS_DC75':
      PIN_NUMBER='(0,0,0,0,0,0,0,0,0,0,0,0,0,0,0,0,0,0,0,0,0,0,0,0,0,0,0,0,0,0,0~
,0,0,0,0,0,0,0,0,DC75)';
      PINUSE='POWER';
      NO_LOAD_CHECK='Both';
      NO_IO_CHECK='Both';
      NO_ASSERT_CHECK='TRUE';
      NO_DIR_CHECK='TRUE';
      ALLOW_CONNECT='TRUE';
    'VSS_DD3':
      PIN_NUMBER='(0,0,0,0,0,0,0,0,0,0,0,0,0,0,0,0,0,0,0,0,0,0,0,0,0,0,0,0,0,0,0~
,0,0,0,0,0,0,0,0,DD3)';
      PINUSE='POWER';
      NO_LOAD_CHECK='Both';
      NO_IO_CHECK='Both';
      NO_ASSERT_CHECK='TRUE';
      NO_DIR_CHECK='TRUE';
      ALLOW_CONNECT='TRUE';
    'VSS_DD23':
      PIN_NUMBER='(0,0,0,0,0,0,0,0,0,0,0,0,0,0,0,0,0,0,0,0,0,0,0,0,0,0,0,0,0,0,0~
,0,0,0,0,0,0,0,0,DD23)';
      PINUSE='POWER';
      NO_LOAD_CHECK='Both';
      NO_IO_CHECK='Both';
      NO_ASSERT_CHECK='TRUE';
      NO_DIR_CHECK='TRUE';
      ALLOW_CONNECT='TRUE';
    'VSS_DD24':
      PIN_NUMBER='(0,0,0,0,0,0,0,0,0,0,0,0,0,0,0,0,0,0,0,0,0,0,0,0,0,0,0,0,0,0,0~
,0,0,0,0,0,0,0,0,DD24)';
      PINUSE='POWER';
      NO_LOAD_CHECK='Both';
      NO_IO_CHECK='Both';
      NO_ASSERT_CHECK='TRUE';
      NO_DIR_CHECK='TRUE';
      ALLOW_CONNECT='TRUE';
    'VSS_DD26':
      PIN_NUMBER='(0,0,0,0,0,0,0,0,0,0,0,0,0,0,0,0,0,0,0,0,0,0,0,0,0,0,0,0,0,0,0~
,0,0,0,0,0,0,0,0,DD26)';
      PINUSE='POWER';
      NO_LOAD_CHECK='Both';
      NO_IO_CHECK='Both';
      NO_ASSERT_CHECK='TRUE';
      NO_DIR_CHECK='TRUE';
      ALLOW_CONNECT='TRUE';
    'VSS_DD27':
      PIN_NUMBER='(0,0,0,0,0,0,0,0,0,0,0,0,0,0,0,0,0,0,0,0,0,0,0,0,0,0,0,0,0,0,0~
,0,0,0,0,0,0,0,0,DD27)';
      PINUSE='POWER';
      NO_LOAD_CHECK='Both';
      NO_IO_CHECK='Both';
      NO_ASSERT_CHECK='TRUE';
      NO_DIR_CHECK='TRUE';
      ALLOW_CONNECT='TRUE';
    'VSS_DD39':
      PIN_NUMBER='(0,0,0,0,0,0,0,0,0,0,0,0,0,0,0,0,0,0,0,0,0,0,0,0,0,0,0,0,0,0,0~
,0,0,0,0,0,0,0,0,DD39)';
      PINUSE='POWER';
      NO_LOAD_CHECK='Both';
      NO_IO_CHECK='Both';
      NO_ASSERT_CHECK='TRUE';
      NO_DIR_CHECK='TRUE';
      ALLOW_CONNECT='TRUE';
    'VSS_DD40':
      PIN_NUMBER='(0,0,0,0,0,0,0,0,0,0,0,0,0,0,0,0,0,0,0,0,0,0,0,0,0,0,0,0,0,0,0~
,0,0,0,0,0,0,0,0,DD40)';
      PINUSE='POWER';
      NO_LOAD_CHECK='Both';
      NO_IO_CHECK='Both';
      NO_ASSERT_CHECK='TRUE';
      NO_DIR_CHECK='TRUE';
      ALLOW_CONNECT='TRUE';
    'VSS_DD41':
      PIN_NUMBER='(0,0,0,0,0,0,0,0,0,0,0,0,0,0,0,0,0,0,0,0,0,0,0,0,0,0,0,0,0,0,0~
,0,0,0,0,0,0,0,0,DD41)';
      PINUSE='POWER';
      NO_LOAD_CHECK='Both';
      NO_IO_CHECK='Both';
      NO_ASSERT_CHECK='TRUE';
      NO_DIR_CHECK='TRUE';
      ALLOW_CONNECT='TRUE';
    'VSS_DD43':
      PIN_NUMBER='(0,0,0,0,0,0,0,0,0,0,0,0,0,0,0,0,0,0,0,0,0,0,0,0,0,0,0,0,0,0,0~
,0,0,0,0,0,0,0,0,DD43)';
      PINUSE='POWER';
      NO_LOAD_CHECK='Both';
      NO_IO_CHECK='Both';
      NO_ASSERT_CHECK='TRUE';
      NO_DIR_CHECK='TRUE';
      ALLOW_CONNECT='TRUE';
    'VSS_DD57':
      PIN_NUMBER='(0,0,0,0,0,0,0,0,0,0,0,0,0,0,0,0,0,0,0,0,0,0,0,0,0,0,0,0,0,0,0~
,0,0,0,0,0,0,0,0,DD57)';
      PINUSE='POWER';
      NO_LOAD_CHECK='Both';
      NO_IO_CHECK='Both';
      NO_ASSERT_CHECK='TRUE';
      NO_DIR_CHECK='TRUE';
      ALLOW_CONNECT='TRUE';
    'VSS_DD59':
      PIN_NUMBER='(0,0,0,0,0,0,0,0,0,0,0,0,0,0,0,0,0,0,0,0,0,0,0,0,0,0,0,0,0,0,0~
,0,0,0,0,0,0,0,0,DD59)';
      PINUSE='POWER';
      NO_LOAD_CHECK='Both';
      NO_IO_CHECK='Both';
      NO_ASSERT_CHECK='TRUE';
      NO_DIR_CHECK='TRUE';
      ALLOW_CONNECT='TRUE';
    'VSS_DD61':
      PIN_NUMBER='(0,0,0,0,0,0,0,0,0,0,0,0,0,0,0,0,0,0,0,0,0,0,0,0,0,0,0,0,0,0,0~
,0,0,0,0,0,0,0,0,DD61)';
      PINUSE='POWER';
      NO_LOAD_CHECK='Both';
      NO_IO_CHECK='Both';
      NO_ASSERT_CHECK='TRUE';
      NO_DIR_CHECK='TRUE';
      ALLOW_CONNECT='TRUE';
    'VSS_DD64':
      PIN_NUMBER='(0,0,0,0,0,0,0,0,0,0,0,0,0,0,0,0,0,0,0,0,0,0,0,0,0,0,0,0,0,0,0~
,0,0,0,0,0,0,0,0,DD64)';
      PINUSE='POWER';
      NO_LOAD_CHECK='Both';
      NO_IO_CHECK='Both';
      NO_ASSERT_CHECK='TRUE';
      NO_DIR_CHECK='TRUE';
      ALLOW_CONNECT='TRUE';
    'VSS_DE13':
      PIN_NUMBER='(0,0,0,0,0,0,0,0,0,0,0,0,0,0,0,0,0,0,0,0,0,0,0,0,0,0,0,0,0,0,0~
,0,0,0,0,0,0,0,0,DE13)';
      PINUSE='POWER';
      NO_LOAD_CHECK='Both';
      NO_IO_CHECK='Both';
      NO_ASSERT_CHECK='TRUE';
      NO_DIR_CHECK='TRUE';
      ALLOW_CONNECT='TRUE';
    'VSS_DE15':
      PIN_NUMBER='(0,0,0,0,0,0,0,0,0,0,0,0,0,0,0,0,0,0,0,0,0,0,0,0,0,0,0,0,0,0,0~
,0,0,0,0,0,0,0,0,DE15)';
      PINUSE='POWER';
      NO_LOAD_CHECK='Both';
      NO_IO_CHECK='Both';
      NO_ASSERT_CHECK='TRUE';
      NO_DIR_CHECK='TRUE';
      ALLOW_CONNECT='TRUE';
    'VSS_DE20':
      PIN_NUMBER='(0,0,0,0,0,0,0,0,0,0,0,0,0,0,0,0,0,0,0,0,0,0,0,0,0,0,0,0,0,0,0~
,0,0,0,0,0,0,0,0,DE20)';
      PINUSE='POWER';
      NO_LOAD_CHECK='Both';
      NO_IO_CHECK='Both';
      NO_ASSERT_CHECK='TRUE';
      NO_DIR_CHECK='TRUE';
      ALLOW_CONNECT='TRUE';
    'VSS_DE23':
      PIN_NUMBER='(0,0,0,0,0,0,0,0,0,0,0,0,0,0,0,0,0,0,0,0,0,0,0,0,0,0,0,0,0,0,0~
,0,0,0,0,0,0,0,0,DE23)';
      PINUSE='POWER';
      NO_LOAD_CHECK='Both';
      NO_IO_CHECK='Both';
      NO_ASSERT_CHECK='TRUE';
      NO_DIR_CHECK='TRUE';
      ALLOW_CONNECT='TRUE';
    'VSS_DE70':
      PIN_NUMBER='(0,0,0,0,0,0,0,0,0,0,0,0,0,0,0,0,0,0,0,0,0,0,0,0,0,0,0,0,0,0,0~
,0,0,0,0,0,0,0,0,DE70)';
      PINUSE='POWER';
      NO_LOAD_CHECK='Both';
      NO_IO_CHECK='Both';
      NO_ASSERT_CHECK='TRUE';
      NO_DIR_CHECK='TRUE';
      ALLOW_CONNECT='TRUE';
    'VSS_DE75':
      PIN_NUMBER='(0,0,0,0,0,0,0,0,0,0,0,0,0,0,0,0,0,0,0,0,0,0,0,0,0,0,0,0,0,0,0~
,0,0,0,0,0,0,0,0,DE75)';
      PINUSE='POWER';
      NO_LOAD_CHECK='Both';
      NO_IO_CHECK='Both';
      NO_ASSERT_CHECK='TRUE';
      NO_DIR_CHECK='TRUE';
      ALLOW_CONNECT='TRUE';
    'VSS_DF3':
      PIN_NUMBER='(0,0,0,0,0,0,0,0,0,0,0,0,0,0,0,0,0,0,0,0,0,0,0,0,0,0,0,0,0,0,0~
,0,0,0,0,0,0,0,0,DF3)';
      PINUSE='POWER';
      NO_LOAD_CHECK='Both';
      NO_IO_CHECK='Both';
      NO_ASSERT_CHECK='TRUE';
      NO_DIR_CHECK='TRUE';
      ALLOW_CONNECT='TRUE';
    'VSS_DF4':
      PIN_NUMBER='(0,0,0,0,0,0,0,0,0,0,0,0,0,0,0,0,0,0,0,0,0,0,0,0,0,0,0,0,0,0,0~
,0,0,0,0,0,0,0,0,DF4)';
      PINUSE='POWER';
      NO_LOAD_CHECK='Both';
      NO_IO_CHECK='Both';
      NO_ASSERT_CHECK='TRUE';
      NO_DIR_CHECK='TRUE';
      ALLOW_CONNECT='TRUE';
    'VSS_DF15':
      PIN_NUMBER='(0,0,0,0,0,0,0,0,0,0,0,0,0,0,0,0,0,0,0,0,0,0,0,0,0,0,0,0,0,0,0~
,0,0,0,0,0,0,0,0,DF15)';
      PINUSE='POWER';
      NO_LOAD_CHECK='Both';
      NO_IO_CHECK='Both';
      NO_ASSERT_CHECK='TRUE';
      NO_DIR_CHECK='TRUE';
      ALLOW_CONNECT='TRUE';
    'VSS_DF17':
      PIN_NUMBER='(0,0,0,0,0,0,0,0,0,0,0,0,0,0,0,0,0,0,0,0,0,0,0,0,0,0,0,0,0,0,0~
,0,0,0,0,0,0,0,0,DF17)';
      PINUSE='POWER';
      NO_LOAD_CHECK='Both';
      NO_IO_CHECK='Both';
      NO_ASSERT_CHECK='TRUE';
      NO_DIR_CHECK='TRUE';
      ALLOW_CONNECT='TRUE';
    'VSS_DF18':
      PIN_NUMBER='(0,0,0,0,0,0,0,0,0,0,0,0,0,0,0,0,0,0,0,0,0,0,0,0,0,0,0,0,0,0,0~
,0,0,0,0,0,0,0,0,DF18)';
      PINUSE='POWER';
      NO_LOAD_CHECK='Both';
      NO_IO_CHECK='Both';
      NO_ASSERT_CHECK='TRUE';
      NO_DIR_CHECK='TRUE';
      ALLOW_CONNECT='TRUE';
    'VSS_DF19':
      PIN_NUMBER='(0,0,0,0,0,0,0,0,0,0,0,0,0,0,0,0,0,0,0,0,0,0,0,0,0,0,0,0,0,0,0~
,0,0,0,0,0,0,0,0,DF19)';
      PINUSE='POWER';
      NO_LOAD_CHECK='Both';
      NO_IO_CHECK='Both';
      NO_ASSERT_CHECK='TRUE';
      NO_DIR_CHECK='TRUE';
      ALLOW_CONNECT='TRUE';
    'VSS_DF43':
      PIN_NUMBER='(0,0,0,0,0,0,0,0,0,0,0,0,0,0,0,0,0,0,0,0,0,0,0,0,0,0,0,0,0,0,0~
,0,0,0,0,0,0,0,0,DF43)';
      PINUSE='POWER';
      NO_LOAD_CHECK='Both';
      NO_IO_CHECK='Both';
      NO_ASSERT_CHECK='TRUE';
      NO_DIR_CHECK='TRUE';
      ALLOW_CONNECT='TRUE';
    'VSS_DF53':
      PIN_NUMBER='(0,0,0,0,0,0,0,0,0,0,0,0,0,0,0,0,0,0,0,0,0,0,0,0,0,0,0,0,0,0,0~
,0,0,0,0,0,0,0,0,DF53)';
      PINUSE='POWER';
      NO_LOAD_CHECK='Both';
      NO_IO_CHECK='Both';
      NO_ASSERT_CHECK='TRUE';
      NO_DIR_CHECK='TRUE';
      ALLOW_CONNECT='TRUE';
    'VSS_DF54':
      PIN_NUMBER='(0,0,0,0,0,0,0,0,0,0,0,0,0,0,0,0,0,0,0,0,0,0,0,0,0,0,0,0,0,0,0~
,0,0,0,0,0,0,0,0,DF54)';
      PINUSE='POWER';
      NO_LOAD_CHECK='Both';
      NO_IO_CHECK='Both';
      NO_ASSERT_CHECK='TRUE';
      NO_DIR_CHECK='TRUE';
      ALLOW_CONNECT='TRUE';
    'VSS_DF66':
      PIN_NUMBER='(0,0,0,0,0,0,0,0,0,0,0,0,0,0,0,0,0,0,0,0,0,0,0,0,0,0,0,0,0,0,0~
,0,0,0,0,0,0,0,0,DF66)';
      PINUSE='POWER';
      NO_LOAD_CHECK='Both';
      NO_IO_CHECK='Both';
      NO_ASSERT_CHECK='TRUE';
      NO_DIR_CHECK='TRUE';
      ALLOW_CONNECT='TRUE';
    'VSS_DF68':
      PIN_NUMBER='(0,0,0,0,0,0,0,0,0,0,0,0,0,0,0,0,0,0,0,0,0,0,0,0,0,0,0,0,0,0,0~
,0,0,0,0,0,0,0,0,DF68)';
      PINUSE='POWER';
      NO_LOAD_CHECK='Both';
      NO_IO_CHECK='Both';
      NO_ASSERT_CHECK='TRUE';
      NO_DIR_CHECK='TRUE';
      ALLOW_CONNECT='TRUE';
    'VSS_DF70':
      PIN_NUMBER='(0,0,0,0,0,0,0,0,0,0,0,0,0,0,0,0,0,0,0,0,0,0,0,0,0,0,0,0,0,0,0~
,0,0,0,0,0,0,0,0,DF70)';
      PINUSE='POWER';
      NO_LOAD_CHECK='Both';
      NO_IO_CHECK='Both';
      NO_ASSERT_CHECK='TRUE';
      NO_DIR_CHECK='TRUE';
      ALLOW_CONNECT='TRUE';
    'VSS_DG8':
      PIN_NUMBER='(0,0,0,0,0,0,0,0,0,0,0,0,0,0,0,0,0,0,0,0,0,0,0,0,0,0,0,0,0,0,0~
,0,0,0,0,0,0,0,0,DG8)';
      PINUSE='POWER';
      NO_LOAD_CHECK='Both';
      NO_IO_CHECK='Both';
      NO_ASSERT_CHECK='TRUE';
      NO_DIR_CHECK='TRUE';
      ALLOW_CONNECT='TRUE';
    'VSS_DG9':
      PIN_NUMBER='(0,0,0,0,0,0,0,0,0,0,0,0,0,0,0,0,0,0,0,0,0,0,0,0,0,0,0,0,0,0,0~
,0,0,0,0,0,0,0,0,DG9)';
      PINUSE='POWER';
      NO_LOAD_CHECK='Both';
      NO_IO_CHECK='Both';
      NO_ASSERT_CHECK='TRUE';
      NO_DIR_CHECK='TRUE';
      ALLOW_CONNECT='TRUE';
    'VSS_DG13':
      PIN_NUMBER='(0,0,0,0,0,0,0,0,0,0,0,0,0,0,0,0,0,0,0,0,0,0,0,0,0,0,0,0,0,0,0~
,0,0,0,0,0,0,0,0,DG13)';
      PINUSE='POWER';
      NO_LOAD_CHECK='Both';
      NO_IO_CHECK='Both';
      NO_ASSERT_CHECK='TRUE';
      NO_DIR_CHECK='TRUE';
      ALLOW_CONNECT='TRUE';
    'VSS_DG14':
      PIN_NUMBER='(0,0,0,0,0,0,0,0,0,0,0,0,0,0,0,0,0,0,0,0,0,0,0,0,0,0,0,0,0,0,0~
,0,0,0,0,0,0,0,0,DG14)';
      PINUSE='POWER';
      NO_LOAD_CHECK='Both';
      NO_IO_CHECK='Both';
      NO_ASSERT_CHECK='TRUE';
      NO_DIR_CHECK='TRUE';
      ALLOW_CONNECT='TRUE';
    'VSS_DG30':
      PIN_NUMBER='(0,0,0,0,0,0,0,0,0,0,0,0,0,0,0,0,0,0,0,0,0,0,0,0,0,0,0,0,0,0,0~
,0,0,0,0,0,0,0,0,DG30)';
      PINUSE='POWER';
      NO_LOAD_CHECK='Both';
      NO_IO_CHECK='Both';
      NO_ASSERT_CHECK='TRUE';
      NO_DIR_CHECK='TRUE';
      ALLOW_CONNECT='TRUE';
    'VSS_DG33':
      PIN_NUMBER='(0,0,0,0,0,0,0,0,0,0,0,0,0,0,0,0,0,0,0,0,0,0,0,0,0,0,0,0,0,0,0~
,0,0,0,0,0,0,0,0,DG33)';
      PINUSE='POWER';
      NO_LOAD_CHECK='Both';
      NO_IO_CHECK='Both';
      NO_ASSERT_CHECK='TRUE';
      NO_DIR_CHECK='TRUE';
      ALLOW_CONNECT='TRUE';
    'VSS_DG41':
      PIN_NUMBER='(0,0,0,0,0,0,0,0,0,0,0,0,0,0,0,0,0,0,0,0,0,0,0,0,0,0,0,0,0,0,0~
,0,0,0,0,0,0,0,0,DG41)';
      PINUSE='POWER';
      NO_LOAD_CHECK='Both';
      NO_IO_CHECK='Both';
      NO_ASSERT_CHECK='TRUE';
      NO_DIR_CHECK='TRUE';
      ALLOW_CONNECT='TRUE';
    'VSS_DG43':
      PIN_NUMBER='(0,0,0,0,0,0,0,0,0,0,0,0,0,0,0,0,0,0,0,0,0,0,0,0,0,0,0,0,0,0,0~
,0,0,0,0,0,0,0,0,DG43)';
      PINUSE='POWER';
      NO_LOAD_CHECK='Both';
      NO_IO_CHECK='Both';
      NO_ASSERT_CHECK='TRUE';
      NO_DIR_CHECK='TRUE';
      ALLOW_CONNECT='TRUE';
    'VSS_DG61':
      PIN_NUMBER='(0,0,0,0,0,0,0,0,0,0,0,0,0,0,0,0,0,0,0,0,0,0,0,0,0,0,0,0,0,0,0~
,0,0,0,0,0,0,0,0,DG61)';
      PINUSE='POWER';
      NO_LOAD_CHECK='Both';
      NO_IO_CHECK='Both';
      NO_ASSERT_CHECK='TRUE';
      NO_DIR_CHECK='TRUE';
      ALLOW_CONNECT='TRUE';
    'VSS_DG62':
      PIN_NUMBER='(0,0,0,0,0,0,0,0,0,0,0,0,0,0,0,0,0,0,0,0,0,0,0,0,0,0,0,0,0,0,0~
,0,0,0,0,0,0,0,0,DG62)';
      PINUSE='POWER';
      NO_LOAD_CHECK='Both';
      NO_IO_CHECK='Both';
      NO_ASSERT_CHECK='TRUE';
      NO_DIR_CHECK='TRUE';
      ALLOW_CONNECT='TRUE';
    'VSS_DG63':
      PIN_NUMBER='(0,0,0,0,0,0,0,0,0,0,0,0,0,0,0,0,0,0,0,0,0,0,0,0,0,0,0,0,0,0,0~
,0,0,0,0,0,0,0,0,DG63)';
      PINUSE='POWER';
      NO_LOAD_CHECK='Both';
      NO_IO_CHECK='Both';
      NO_ASSERT_CHECK='TRUE';
      NO_DIR_CHECK='TRUE';
      ALLOW_CONNECT='TRUE';
    'VSS_DG65':
      PIN_NUMBER='(0,0,0,0,0,0,0,0,0,0,0,0,0,0,0,0,0,0,0,0,0,0,0,0,0,0,0,0,0,0,0~
,0,0,0,0,0,0,0,0,DG65)';
      PINUSE='POWER';
      NO_LOAD_CHECK='Both';
      NO_IO_CHECK='Both';
      NO_ASSERT_CHECK='TRUE';
      NO_DIR_CHECK='TRUE';
      ALLOW_CONNECT='TRUE';
    'VSS_DH5':
      PIN_NUMBER='(0,0,0,0,0,0,0,0,0,0,0,0,0,0,0,0,0,0,0,0,0,0,0,0,0,0,0,0,0,0,0~
,0,0,0,0,0,0,0,0,DH5)';
      PINUSE='POWER';
      NO_LOAD_CHECK='Both';
      NO_IO_CHECK='Both';
      NO_ASSERT_CHECK='TRUE';
      NO_DIR_CHECK='TRUE';
      ALLOW_CONNECT='TRUE';
    'VSS_DH11':
      PIN_NUMBER='(0,0,0,0,0,0,0,0,0,0,0,0,0,0,0,0,0,0,0,0,0,0,0,0,0,0,0,0,0,0,0~
,0,0,0,0,0,0,0,0,DH11)';
      PINUSE='POWER';
      NO_LOAD_CHECK='Both';
      NO_IO_CHECK='Both';
      NO_ASSERT_CHECK='TRUE';
      NO_DIR_CHECK='TRUE';
      ALLOW_CONNECT='TRUE';
    'VSS_DH18':
      PIN_NUMBER='(0,0,0,0,0,0,0,0,0,0,0,0,0,0,0,0,0,0,0,0,0,0,0,0,0,0,0,0,0,0,0~
,0,0,0,0,0,0,0,0,DH18)';
      PINUSE='POWER';
      NO_LOAD_CHECK='Both';
      NO_IO_CHECK='Both';
      NO_ASSERT_CHECK='TRUE';
      NO_DIR_CHECK='TRUE';
      ALLOW_CONNECT='TRUE';
    'VSS_DH37':
      PIN_NUMBER='(0,0,0,0,0,0,0,0,0,0,0,0,0,0,0,0,0,0,0,0,0,0,0,0,0,0,0,0,0,0,0~
,0,0,0,0,0,0,0,0,DH37)';
      PINUSE='POWER';
      NO_LOAD_CHECK='Both';
      NO_IO_CHECK='Both';
      NO_ASSERT_CHECK='TRUE';
      NO_DIR_CHECK='TRUE';
      ALLOW_CONNECT='TRUE';
    'VSS_DH61':
      PIN_NUMBER='(0,0,0,0,0,0,0,0,0,0,0,0,0,0,0,0,0,0,0,0,0,0,0,0,0,0,0,0,0,0,0~
,0,0,0,0,0,0,0,0,DH61)';
      PINUSE='POWER';
      NO_LOAD_CHECK='Both';
      NO_IO_CHECK='Both';
      NO_ASSERT_CHECK='TRUE';
      NO_DIR_CHECK='TRUE';
      ALLOW_CONNECT='TRUE';
    'VSS_DH63':
      PIN_NUMBER='(0,0,0,0,0,0,0,0,0,0,0,0,0,0,0,0,0,0,0,0,0,0,0,0,0,0,0,0,0,0,0~
,0,0,0,0,0,0,0,0,DH63)';
      PINUSE='POWER';
      NO_LOAD_CHECK='Both';
      NO_IO_CHECK='Both';
      NO_ASSERT_CHECK='TRUE';
      NO_DIR_CHECK='TRUE';
      ALLOW_CONNECT='TRUE';
    'VSS_DH64':
      PIN_NUMBER='(0,0,0,0,0,0,0,0,0,0,0,0,0,0,0,0,0,0,0,0,0,0,0,0,0,0,0,0,0,0,0~
,0,0,0,0,0,0,0,0,DH64)';
      PINUSE='POWER';
      NO_LOAD_CHECK='Both';
      NO_IO_CHECK='Both';
      NO_ASSERT_CHECK='TRUE';
      NO_DIR_CHECK='TRUE';
      ALLOW_CONNECT='TRUE';
    'VSS_DH66':
      PIN_NUMBER='(0,0,0,0,0,0,0,0,0,0,0,0,0,0,0,0,0,0,0,0,0,0,0,0,0,0,0,0,0,0,0~
,0,0,0,0,0,0,0,0,DH66)';
      PINUSE='POWER';
      NO_LOAD_CHECK='Both';
      NO_IO_CHECK='Both';
      NO_ASSERT_CHECK='TRUE';
      NO_DIR_CHECK='TRUE';
      ALLOW_CONNECT='TRUE';
    'VSS_DA72':
      PIN_NUMBER='(0,0,0,0,0,0,0,0,0,0,0,0,0,0,0,0,0,0,0,0,0,0,0,0,0,0,0,0,0,0,0~
,0,0,0,0,0,0,0,0,DA72)';
      PINUSE='POWER';
      NO_LOAD_CHECK='Both';
      NO_IO_CHECK='Both';
      NO_ASSERT_CHECK='TRUE';
      NO_DIR_CHECK='TRUE';
      ALLOW_CONNECT='TRUE';
    'VSS_DA75':
      PIN_NUMBER='(0,0,0,0,0,0,0,0,0,0,0,0,0,0,0,0,0,0,0,0,0,0,0,0,0,0,0,0,0,0,0~
,0,0,0,0,0,0,0,0,DA75)';
      PINUSE='POWER';
      NO_LOAD_CHECK='Both';
      NO_IO_CHECK='Both';
      NO_ASSERT_CHECK='TRUE';
      NO_DIR_CHECK='TRUE';
      ALLOW_CONNECT='TRUE';
    'VSS_DB3':
      PIN_NUMBER='(0,0,0,0,0,0,0,0,0,0,0,0,0,0,0,0,0,0,0,0,0,0,0,0,0,0,0,0,0,0,0~
,0,0,0,0,0,0,0,0,DB3)';
      PINUSE='POWER';
      NO_LOAD_CHECK='Both';
      NO_IO_CHECK='Both';
      NO_ASSERT_CHECK='TRUE';
      NO_DIR_CHECK='TRUE';
      ALLOW_CONNECT='TRUE';
    'VSS_DB8':
      PIN_NUMBER='(0,0,0,0,0,0,0,0,0,0,0,0,0,0,0,0,0,0,0,0,0,0,0,0,0,0,0,0,0,0,0~
,0,0,0,0,0,0,0,0,DB8)';
      PINUSE='POWER';
      NO_LOAD_CHECK='Both';
      NO_IO_CHECK='Both';
      NO_ASSERT_CHECK='TRUE';
      NO_DIR_CHECK='TRUE';
      ALLOW_CONNECT='TRUE';
    'VSS_DB10':
      PIN_NUMBER='(0,0,0,0,0,0,0,0,0,0,0,0,0,0,0,0,0,0,0,0,0,0,0,0,0,0,0,0,0,0,0~
,0,0,0,0,0,0,0,0,DB10)';
      PINUSE='POWER';
      NO_LOAD_CHECK='Both';
      NO_IO_CHECK='Both';
      NO_ASSERT_CHECK='TRUE';
      NO_DIR_CHECK='TRUE';
      ALLOW_CONNECT='TRUE';
    'VSS_DB28':
      PIN_NUMBER='(0,0,0,0,0,0,0,0,0,0,0,0,0,0,0,0,0,0,0,0,0,0,0,0,0,0,0,0,0,0,0~
,0,0,0,0,0,0,0,0,DB28)';
      PINUSE='POWER';
      NO_LOAD_CHECK='Both';
      NO_IO_CHECK='Both';
      NO_ASSERT_CHECK='TRUE';
      NO_DIR_CHECK='TRUE';
      ALLOW_CONNECT='TRUE';
    'VSS_DB31':
      PIN_NUMBER='(0,0,0,0,0,0,0,0,0,0,0,0,0,0,0,0,0,0,0,0,0,0,0,0,0,0,0,0,0,0,0~
,0,0,0,0,0,0,0,0,DB31)';
      PINUSE='POWER';
      NO_LOAD_CHECK='Both';
      NO_IO_CHECK='Both';
      NO_ASSERT_CHECK='TRUE';
      NO_DIR_CHECK='TRUE';
      ALLOW_CONNECT='TRUE';
    'VSS_DB34':
      PIN_NUMBER='(0,0,0,0,0,0,0,0,0,0,0,0,0,0,0,0,0,0,0,0,0,0,0,0,0,0,0,0,0,0,0~
,0,0,0,0,0,0,0,0,DB34)';
      PINUSE='POWER';
      NO_LOAD_CHECK='Both';
      NO_IO_CHECK='Both';
      NO_ASSERT_CHECK='TRUE';
      NO_DIR_CHECK='TRUE';
      ALLOW_CONNECT='TRUE';
    'VSS_DB37':
      PIN_NUMBER='(0,0,0,0,0,0,0,0,0,0,0,0,0,0,0,0,0,0,0,0,0,0,0,0,0,0,0,0,0,0,0~
,0,0,0,0,0,0,0,0,DB37)';
      PINUSE='POWER';
      NO_LOAD_CHECK='Both';
      NO_IO_CHECK='Both';
      NO_ASSERT_CHECK='TRUE';
      NO_DIR_CHECK='TRUE';
      ALLOW_CONNECT='TRUE';
    'VSS_DB39':
      PIN_NUMBER='(0,0,0,0,0,0,0,0,0,0,0,0,0,0,0,0,0,0,0,0,0,0,0,0,0,0,0,0,0,0,0~
,0,0,0,0,0,0,0,0,DB39)';
      PINUSE='POWER';
      NO_LOAD_CHECK='Both';
      NO_IO_CHECK='Both';
      NO_ASSERT_CHECK='TRUE';
      NO_DIR_CHECK='TRUE';
      ALLOW_CONNECT='TRUE';
    'VSS_DB42':
      PIN_NUMBER='(0,0,0,0,0,0,0,0,0,0,0,0,0,0,0,0,0,0,0,0,0,0,0,0,0,0,0,0,0,0,0~
,0,0,0,0,0,0,0,0,DB42)';
      PINUSE='POWER';
      NO_LOAD_CHECK='Both';
      NO_IO_CHECK='Both';
      NO_ASSERT_CHECK='TRUE';
      NO_DIR_CHECK='TRUE';
      ALLOW_CONNECT='TRUE';
    'VSS_DB45':
      PIN_NUMBER='(0,0,0,0,0,0,0,0,0,0,0,0,0,0,0,0,0,0,0,0,0,0,0,0,0,0,0,0,0,0,0~
,0,0,0,0,0,0,0,0,DB45)';
      PINUSE='POWER';
      NO_LOAD_CHECK='Both';
      NO_IO_CHECK='Both';
      NO_ASSERT_CHECK='TRUE';
      NO_DIR_CHECK='TRUE';
      ALLOW_CONNECT='TRUE';
    'VSS_DB61':
      PIN_NUMBER='(0,0,0,0,0,0,0,0,0,0,0,0,0,0,0,0,0,0,0,0,0,0,0,0,0,0,0,0,0,0,0~
,0,0,0,0,0,0,0,0,DB61)';
      PINUSE='POWER';
      NO_LOAD_CHECK='Both';
      NO_IO_CHECK='Both';
      NO_ASSERT_CHECK='TRUE';
      NO_DIR_CHECK='TRUE';
      ALLOW_CONNECT='TRUE';
    'VSS_DB66':
      PIN_NUMBER='(0,0,0,0,0,0,0,0,0,0,0,0,0,0,0,0,0,0,0,0,0,0,0,0,0,0,0,0,0,0,0~
,0,0,0,0,0,0,0,0,DB66)';
      PINUSE='POWER';
      NO_LOAD_CHECK='Both';
      NO_IO_CHECK='Both';
      NO_ASSERT_CHECK='TRUE';
      NO_DIR_CHECK='TRUE';
      ALLOW_CONNECT='TRUE';
    'VSS_DB68':
      PIN_NUMBER='(0,0,0,0,0,0,0,0,0,0,0,0,0,0,0,0,0,0,0,0,0,0,0,0,0,0,0,0,0,0,0~
,0,0,0,0,0,0,0,0,DB68)';
      PINUSE='POWER';
      NO_LOAD_CHECK='Both';
      NO_IO_CHECK='Both';
      NO_ASSERT_CHECK='TRUE';
      NO_DIR_CHECK='TRUE';
      ALLOW_CONNECT='TRUE';
    'VSS_DB73':
      PIN_NUMBER='(0,0,0,0,0,0,0,0,0,0,0,0,0,0,0,0,0,0,0,0,0,0,0,0,0,0,0,0,0,0,0~
,0,0,0,0,0,0,0,0,DB73)';
      PINUSE='POWER';
      NO_LOAD_CHECK='Both';
      NO_IO_CHECK='Both';
      NO_ASSERT_CHECK='TRUE';
      NO_DIR_CHECK='TRUE';
      ALLOW_CONNECT='TRUE';
    'VSS_DC1':
      PIN_NUMBER='(0,0,0,0,0,0,0,0,0,0,0,0,0,0,0,0,0,0,0,0,0,0,0,0,0,0,0,0,0,0,0~
,0,0,0,0,0,0,0,0,DC1)';
      PINUSE='POWER';
      NO_LOAD_CHECK='Both';
      NO_IO_CHECK='Both';
      NO_ASSERT_CHECK='TRUE';
      NO_DIR_CHECK='TRUE';
      ALLOW_CONNECT='TRUE';
    'VSS_DC4':
      PIN_NUMBER='(0,0,0,0,0,0,0,0,0,0,0,0,0,0,0,0,0,0,0,0,0,0,0,0,0,0,0,0,0,0,0~
,0,0,0,0,0,0,0,0,DC4)';
      PINUSE='POWER';
      NO_LOAD_CHECK='Both';
      NO_IO_CHECK='Both';
      NO_ASSERT_CHECK='TRUE';
      NO_DIR_CHECK='TRUE';
      ALLOW_CONNECT='TRUE';
    'VSS_DC6':
      PIN_NUMBER='(0,0,0,0,0,0,0,0,0,0,0,0,0,0,0,0,0,0,0,0,0,0,0,0,0,0,0,0,0,0,0~
,0,0,0,0,0,0,0,0,DC6)';
      PINUSE='POWER';
      NO_LOAD_CHECK='Both';
      NO_IO_CHECK='Both';
      NO_ASSERT_CHECK='TRUE';
      NO_DIR_CHECK='TRUE';
      ALLOW_CONNECT='TRUE';
    'VSS_DC8':
      PIN_NUMBER='(0,0,0,0,0,0,0,0,0,0,0,0,0,0,0,0,0,0,0,0,0,0,0,0,0,0,0,0,0,0,0~
,0,0,0,0,0,0,0,0,DC8)';
      PINUSE='POWER';
      NO_LOAD_CHECK='Both';
      NO_IO_CHECK='Both';
      NO_ASSERT_CHECK='TRUE';
      NO_DIR_CHECK='TRUE';
      ALLOW_CONNECT='TRUE';
    'VSS_DC11':
      PIN_NUMBER='(0,0,0,0,0,0,0,0,0,0,0,0,0,0,0,0,0,0,0,0,0,0,0,0,0,0,0,0,0,0,0~
,0,0,0,0,0,0,0,0,DC11)';
      PINUSE='POWER';
      NO_LOAD_CHECK='Both';
      NO_IO_CHECK='Both';
      NO_ASSERT_CHECK='TRUE';
      NO_DIR_CHECK='TRUE';
      ALLOW_CONNECT='TRUE';
    'VSS_DC18':
      PIN_NUMBER='(0,0,0,0,0,0,0,0,0,0,0,0,0,0,0,0,0,0,0,0,0,0,0,0,0,0,0,0,0,0,0~
,0,0,0,0,0,0,0,0,DC18)';
      PINUSE='POWER';
      NO_LOAD_CHECK='Both';
      NO_IO_CHECK='Both';
      NO_ASSERT_CHECK='TRUE';
      NO_DIR_CHECK='TRUE';
      ALLOW_CONNECT='TRUE';
    'VSS_DC20':
      PIN_NUMBER='(0,0,0,0,0,0,0,0,0,0,0,0,0,0,0,0,0,0,0,0,0,0,0,0,0,0,0,0,0,0,0~
,0,0,0,0,0,0,0,0,DC20)';
      PINUSE='POWER';
      NO_LOAD_CHECK='Both';
      NO_IO_CHECK='Both';
      NO_ASSERT_CHECK='TRUE';
      NO_DIR_CHECK='TRUE';
      ALLOW_CONNECT='TRUE';
    'VSS_DC22':
      PIN_NUMBER='(0,0,0,0,0,0,0,0,0,0,0,0,0,0,0,0,0,0,0,0,0,0,0,0,0,0,0,0,0,0,0~
,0,0,0,0,0,0,0,0,DC22)';
      PINUSE='POWER';
      NO_LOAD_CHECK='Both';
      NO_IO_CHECK='Both';
      NO_ASSERT_CHECK='TRUE';
      NO_DIR_CHECK='TRUE';
      ALLOW_CONNECT='TRUE';
    'VSS_DC25':
      PIN_NUMBER='(0,0,0,0,0,0,0,0,0,0,0,0,0,0,0,0,0,0,0,0,0,0,0,0,0,0,0,0,0,0,0~
,0,0,0,0,0,0,0,0,DC25)';
      PINUSE='POWER';
      NO_LOAD_CHECK='Both';
      NO_IO_CHECK='Both';
      NO_ASSERT_CHECK='TRUE';
      NO_DIR_CHECK='TRUE';
      ALLOW_CONNECT='TRUE';
    'VSS_DC28':
      PIN_NUMBER='(0,0,0,0,0,0,0,0,0,0,0,0,0,0,0,0,0,0,0,0,0,0,0,0,0,0,0,0,0,0,0~
,0,0,0,0,0,0,0,0,DC28)';
      PINUSE='POWER';
      NO_LOAD_CHECK='Both';
      NO_IO_CHECK='Both';
      NO_ASSERT_CHECK='TRUE';
      NO_DIR_CHECK='TRUE';
      ALLOW_CONNECT='TRUE';
    'VSS_DC31':
      PIN_NUMBER='(0,0,0,0,0,0,0,0,0,0,0,0,0,0,0,0,0,0,0,0,0,0,0,0,0,0,0,0,0,0,0~
,0,0,0,0,0,0,0,0,DC31)';
      PINUSE='POWER';
      NO_LOAD_CHECK='Both';
      NO_IO_CHECK='Both';
      NO_ASSERT_CHECK='TRUE';
      NO_DIR_CHECK='TRUE';
      ALLOW_CONNECT='TRUE';
    'VSS_DC34':
      PIN_NUMBER='(0,0,0,0,0,0,0,0,0,0,0,0,0,0,0,0,0,0,0,0,0,0,0,0,0,0,0,0,0,0,0~
,0,0,0,0,0,0,0,0,DC34)';
      PINUSE='POWER';
      NO_LOAD_CHECK='Both';
      NO_IO_CHECK='Both';
      NO_ASSERT_CHECK='TRUE';
      NO_DIR_CHECK='TRUE';
      ALLOW_CONNECT='TRUE';
    'VSS_DC42':
      PIN_NUMBER='(0,0,0,0,0,0,0,0,0,0,0,0,0,0,0,0,0,0,0,0,0,0,0,0,0,0,0,0,0,0,0~
,0,0,0,0,0,0,0,0,DC42)';
      PINUSE='POWER';
      NO_LOAD_CHECK='Both';
      NO_IO_CHECK='Both';
      NO_ASSERT_CHECK='TRUE';
      NO_DIR_CHECK='TRUE';
      ALLOW_CONNECT='TRUE';
    'VSS_DC54':
      PIN_NUMBER='(0,0,0,0,0,0,0,0,0,0,0,0,0,0,0,0,0,0,0,0,0,0,0,0,0,0,0,0,0,0,0~
,0,0,0,0,0,0,0,0,DC54)';
      PINUSE='POWER';
      NO_LOAD_CHECK='Both';
      NO_IO_CHECK='Both';
      NO_ASSERT_CHECK='TRUE';
      NO_DIR_CHECK='TRUE';
      ALLOW_CONNECT='TRUE';
    'VSS_DC56':
      PIN_NUMBER='(0,0,0,0,0,0,0,0,0,0,0,0,0,0,0,0,0,0,0,0,0,0,0,0,0,0,0,0,0,0,0~
,0,0,0,0,0,0,0,0,DC56)';
      PINUSE='POWER';
      NO_LOAD_CHECK='Both';
      NO_IO_CHECK='Both';
      NO_ASSERT_CHECK='TRUE';
      NO_DIR_CHECK='TRUE';
      ALLOW_CONNECT='TRUE';
    'VSS_DC58':
      PIN_NUMBER='(0,0,0,0,0,0,0,0,0,0,0,0,0,0,0,0,0,0,0,0,0,0,0,0,0,0,0,0,0,0,0~
,0,0,0,0,0,0,0,0,DC58)';
      PINUSE='POWER';
      NO_LOAD_CHECK='Both';
      NO_IO_CHECK='Both';
      NO_ASSERT_CHECK='TRUE';
      NO_DIR_CHECK='TRUE';
      ALLOW_CONNECT='TRUE';
    'VSS_DC61':
      PIN_NUMBER='(0,0,0,0,0,0,0,0,0,0,0,0,0,0,0,0,0,0,0,0,0,0,0,0,0,0,0,0,0,0,0~
,0,0,0,0,0,0,0,0,DC61)';
      PINUSE='POWER';
      NO_LOAD_CHECK='Both';
      NO_IO_CHECK='Both';
      NO_ASSERT_CHECK='TRUE';
      NO_DIR_CHECK='TRUE';
      ALLOW_CONNECT='TRUE';
    'VSS_DC63':
      PIN_NUMBER='(0,0,0,0,0,0,0,0,0,0,0,0,0,0,0,0,0,0,0,0,0,0,0,0,0,0,0,0,0,0,0~
,0,0,0,0,0,0,0,0,DC63)';
      PINUSE='POWER';
      NO_LOAD_CHECK='Both';
      NO_IO_CHECK='Both';
      NO_ASSERT_CHECK='TRUE';
      NO_DIR_CHECK='TRUE';
      ALLOW_CONNECT='TRUE';
    'VSS_DC65':
      PIN_NUMBER='(0,0,0,0,0,0,0,0,0,0,0,0,0,0,0,0,0,0,0,0,0,0,0,0,0,0,0,0,0,0,0~
,0,0,0,0,0,0,0,0,DC65)';
      PINUSE='POWER';
      NO_LOAD_CHECK='Both';
      NO_IO_CHECK='Both';
      NO_ASSERT_CHECK='TRUE';
      NO_DIR_CHECK='TRUE';
      ALLOW_CONNECT='TRUE';
    'VSS_DC68':
      PIN_NUMBER='(0,0,0,0,0,0,0,0,0,0,0,0,0,0,0,0,0,0,0,0,0,0,0,0,0,0,0,0,0,0,0~
,0,0,0,0,0,0,0,0,DC68)';
      PINUSE='POWER';
      NO_LOAD_CHECK='Both';
      NO_IO_CHECK='Both';
      NO_ASSERT_CHECK='TRUE';
      NO_DIR_CHECK='TRUE';
      ALLOW_CONNECT='TRUE';
    'VSS_DD5':
      PIN_NUMBER='(0,0,0,0,0,0,0,0,0,0,0,0,0,0,0,0,0,0,0,0,0,0,0,0,0,0,0,0,0,0,0~
,0,0,0,0,0,0,0,0,DD5)';
      PINUSE='POWER';
      NO_LOAD_CHECK='Both';
      NO_IO_CHECK='Both';
      NO_ASSERT_CHECK='TRUE';
      NO_DIR_CHECK='TRUE';
      ALLOW_CONNECT='TRUE';
    'VSS_DD8':
      PIN_NUMBER='(0,0,0,0,0,0,0,0,0,0,0,0,0,0,0,0,0,0,0,0,0,0,0,0,0,0,0,0,0,0,0~
,0,0,0,0,0,0,0,0,DD8)';
      PINUSE='POWER';
      NO_LOAD_CHECK='Both';
      NO_IO_CHECK='Both';
      NO_ASSERT_CHECK='TRUE';
      NO_DIR_CHECK='TRUE';
      ALLOW_CONNECT='TRUE';
    'VSS_DD10':
      PIN_NUMBER='(0,0,0,0,0,0,0,0,0,0,0,0,0,0,0,0,0,0,0,0,0,0,0,0,0,0,0,0,0,0,0~
,0,0,0,0,0,0,0,0,DD10)';
      PINUSE='POWER';
      NO_LOAD_CHECK='Both';
      NO_IO_CHECK='Both';
      NO_ASSERT_CHECK='TRUE';
      NO_DIR_CHECK='TRUE';
      ALLOW_CONNECT='TRUE';
    'VSS_DD12':
      PIN_NUMBER='(0,0,0,0,0,0,0,0,0,0,0,0,0,0,0,0,0,0,0,0,0,0,0,0,0,0,0,0,0,0,0~
,0,0,0,0,0,0,0,0,DD12)';
      PINUSE='POWER';
      NO_LOAD_CHECK='Both';
      NO_IO_CHECK='Both';
      NO_ASSERT_CHECK='TRUE';
      NO_DIR_CHECK='TRUE';
      ALLOW_CONNECT='TRUE';
    'VSS_DD15':
      PIN_NUMBER='(0,0,0,0,0,0,0,0,0,0,0,0,0,0,0,0,0,0,0,0,0,0,0,0,0,0,0,0,0,0,0~
,0,0,0,0,0,0,0,0,DD15)';
      PINUSE='POWER';
      NO_LOAD_CHECK='Both';
      NO_IO_CHECK='Both';
      NO_ASSERT_CHECK='TRUE';
      NO_DIR_CHECK='TRUE';
      ALLOW_CONNECT='TRUE';
    'VSS_DD17':
      PIN_NUMBER='(0,0,0,0,0,0,0,0,0,0,0,0,0,0,0,0,0,0,0,0,0,0,0,0,0,0,0,0,0,0,0~
,0,0,0,0,0,0,0,0,DD17)';
      PINUSE='POWER';
      NO_LOAD_CHECK='Both';
      NO_IO_CHECK='Both';
      NO_ASSERT_CHECK='TRUE';
      NO_DIR_CHECK='TRUE';
      ALLOW_CONNECT='TRUE';
    'VSS_DD19':
      PIN_NUMBER='(0,0,0,0,0,0,0,0,0,0,0,0,0,0,0,0,0,0,0,0,0,0,0,0,0,0,0,0,0,0,0~
,0,0,0,0,0,0,0,0,DD19)';
      PINUSE='POWER';
      NO_LOAD_CHECK='Both';
      NO_IO_CHECK='Both';
      NO_ASSERT_CHECK='TRUE';
      NO_DIR_CHECK='TRUE';
      ALLOW_CONNECT='TRUE';
    'VSS_DD29':
      PIN_NUMBER='(0,0,0,0,0,0,0,0,0,0,0,0,0,0,0,0,0,0,0,0,0,0,0,0,0,0,0,0,0,0,0~
,0,0,0,0,0,0,0,0,DD29)';
      PINUSE='POWER';
      NO_LOAD_CHECK='Both';
      NO_IO_CHECK='Both';
      NO_ASSERT_CHECK='TRUE';
      NO_DIR_CHECK='TRUE';
      ALLOW_CONNECT='TRUE';
    'VSS_DD30':
      PIN_NUMBER='(0,0,0,0,0,0,0,0,0,0,0,0,0,0,0,0,0,0,0,0,0,0,0,0,0,0,0,0,0,0,0~
,0,0,0,0,0,0,0,0,DD30)';
      PINUSE='POWER';
      NO_LOAD_CHECK='Both';
      NO_IO_CHECK='Both';
      NO_ASSERT_CHECK='TRUE';
      NO_DIR_CHECK='TRUE';
      ALLOW_CONNECT='TRUE';
    'VSS_DD32':
      PIN_NUMBER='(0,0,0,0,0,0,0,0,0,0,0,0,0,0,0,0,0,0,0,0,0,0,0,0,0,0,0,0,0,0,0~
,0,0,0,0,0,0,0,0,DD32)';
      PINUSE='POWER';
      NO_LOAD_CHECK='Both';
      NO_IO_CHECK='Both';
      NO_ASSERT_CHECK='TRUE';
      NO_DIR_CHECK='TRUE';
      ALLOW_CONNECT='TRUE';
    'VSS_DD33':
      PIN_NUMBER='(0,0,0,0,0,0,0,0,0,0,0,0,0,0,0,0,0,0,0,0,0,0,0,0,0,0,0,0,0,0,0~
,0,0,0,0,0,0,0,0,DD33)';
      PINUSE='POWER';
      NO_LOAD_CHECK='Both';
      NO_IO_CHECK='Both';
      NO_ASSERT_CHECK='TRUE';
      NO_DIR_CHECK='TRUE';
      ALLOW_CONNECT='TRUE';
    'VSS_DD35':
      PIN_NUMBER='(0,0,0,0,0,0,0,0,0,0,0,0,0,0,0,0,0,0,0,0,0,0,0,0,0,0,0,0,0,0,0~
,0,0,0,0,0,0,0,0,DD35)';
      PINUSE='POWER';
      NO_LOAD_CHECK='Both';
      NO_IO_CHECK='Both';
      NO_ASSERT_CHECK='TRUE';
      NO_DIR_CHECK='TRUE';
      ALLOW_CONNECT='TRUE';
    'VSS_DD36':
      PIN_NUMBER='(0,0,0,0,0,0,0,0,0,0,0,0,0,0,0,0,0,0,0,0,0,0,0,0,0,0,0,0,0,0,0~
,0,0,0,0,0,0,0,0,DD36)';
      PINUSE='POWER';
      NO_LOAD_CHECK='Both';
      NO_IO_CHECK='Both';
      NO_ASSERT_CHECK='TRUE';
      NO_DIR_CHECK='TRUE';
      ALLOW_CONNECT='TRUE';
    'VSS_DD37':
      PIN_NUMBER='(0,0,0,0,0,0,0,0,0,0,0,0,0,0,0,0,0,0,0,0,0,0,0,0,0,0,0,0,0,0,0~
,0,0,0,0,0,0,0,0,DD37)';
      PINUSE='POWER';
      NO_LOAD_CHECK='Both';
      NO_IO_CHECK='Both';
      NO_ASSERT_CHECK='TRUE';
      NO_DIR_CHECK='TRUE';
      ALLOW_CONNECT='TRUE';
    'VSS_DD44':
      PIN_NUMBER='(0,0,0,0,0,0,0,0,0,0,0,0,0,0,0,0,0,0,0,0,0,0,0,0,0,0,0,0,0,0,0~
,0,0,0,0,0,0,0,0,DD44)';
      PINUSE='POWER';
      NO_LOAD_CHECK='Both';
      NO_IO_CHECK='Both';
      NO_ASSERT_CHECK='TRUE';
      NO_DIR_CHECK='TRUE';
      ALLOW_CONNECT='TRUE';
    'VSS_DD46':
      PIN_NUMBER='(0,0,0,0,0,0,0,0,0,0,0,0,0,0,0,0,0,0,0,0,0,0,0,0,0,0,0,0,0,0,0~
,0,0,0,0,0,0,0,0,DD46)';
      PINUSE='POWER';
      NO_LOAD_CHECK='Both';
      NO_IO_CHECK='Both';
      NO_ASSERT_CHECK='TRUE';
      NO_DIR_CHECK='TRUE';
      ALLOW_CONNECT='TRUE';
    'VSS_DD47':
      PIN_NUMBER='(0,0,0,0,0,0,0,0,0,0,0,0,0,0,0,0,0,0,0,0,0,0,0,0,0,0,0,0,0,0,0~
,0,0,0,0,0,0,0,0,DD47)';
      PINUSE='POWER';
      NO_LOAD_CHECK='Both';
      NO_IO_CHECK='Both';
      NO_ASSERT_CHECK='TRUE';
      NO_DIR_CHECK='TRUE';
      ALLOW_CONNECT='TRUE';
    'VSS_DD49':
      PIN_NUMBER='(0,0,0,0,0,0,0,0,0,0,0,0,0,0,0,0,0,0,0,0,0,0,0,0,0,0,0,0,0,0,0~
,0,0,0,0,0,0,0,0,DD49)';
      PINUSE='POWER';
      NO_LOAD_CHECK='Both';
      NO_IO_CHECK='Both';
      NO_ASSERT_CHECK='TRUE';
      NO_DIR_CHECK='TRUE';
      ALLOW_CONNECT='TRUE';
    'VSS_DD50':
      PIN_NUMBER='(0,0,0,0,0,0,0,0,0,0,0,0,0,0,0,0,0,0,0,0,0,0,0,0,0,0,0,0,0,0,0~
,0,0,0,0,0,0,0,0,DD50)';
      PINUSE='POWER';
      NO_LOAD_CHECK='Both';
      NO_IO_CHECK='Both';
      NO_ASSERT_CHECK='TRUE';
      NO_DIR_CHECK='TRUE';
      ALLOW_CONNECT='TRUE';
    'VSS_DD52':
      PIN_NUMBER='(0,0,0,0,0,0,0,0,0,0,0,0,0,0,0,0,0,0,0,0,0,0,0,0,0,0,0,0,0,0,0~
,0,0,0,0,0,0,0,0,DD52)';
      PINUSE='POWER';
      NO_LOAD_CHECK='Both';
      NO_IO_CHECK='Both';
      NO_ASSERT_CHECK='TRUE';
      NO_DIR_CHECK='TRUE';
      ALLOW_CONNECT='TRUE';
    'VSS_DD53':
      PIN_NUMBER='(0,0,0,0,0,0,0,0,0,0,0,0,0,0,0,0,0,0,0,0,0,0,0,0,0,0,0,0,0,0,0~
,0,0,0,0,0,0,0,0,DD53)';
      PINUSE='POWER';
      NO_LOAD_CHECK='Both';
      NO_IO_CHECK='Both';
      NO_ASSERT_CHECK='TRUE';
      NO_DIR_CHECK='TRUE';
      ALLOW_CONNECT='TRUE';
    'VSS_DD66':
      PIN_NUMBER='(0,0,0,0,0,0,0,0,0,0,0,0,0,0,0,0,0,0,0,0,0,0,0,0,0,0,0,0,0,0,0~
,0,0,0,0,0,0,0,0,DD66)';
      PINUSE='POWER';
      NO_LOAD_CHECK='Both';
      NO_IO_CHECK='Both';
      NO_ASSERT_CHECK='TRUE';
      NO_DIR_CHECK='TRUE';
      ALLOW_CONNECT='TRUE';
    'VSS_DD68':
      PIN_NUMBER='(0,0,0,0,0,0,0,0,0,0,0,0,0,0,0,0,0,0,0,0,0,0,0,0,0,0,0,0,0,0,0~
,0,0,0,0,0,0,0,0,DD68)';
      PINUSE='POWER';
      NO_LOAD_CHECK='Both';
      NO_IO_CHECK='Both';
      NO_ASSERT_CHECK='TRUE';
      NO_DIR_CHECK='TRUE';
      ALLOW_CONNECT='TRUE';
    'VSS_DD71':
      PIN_NUMBER='(0,0,0,0,0,0,0,0,0,0,0,0,0,0,0,0,0,0,0,0,0,0,0,0,0,0,0,0,0,0,0~
,0,0,0,0,0,0,0,0,DD71)';
      PINUSE='POWER';
      NO_LOAD_CHECK='Both';
      NO_IO_CHECK='Both';
      NO_ASSERT_CHECK='TRUE';
      NO_DIR_CHECK='TRUE';
      ALLOW_CONNECT='TRUE';
    'VSS_DD73':
      PIN_NUMBER='(0,0,0,0,0,0,0,0,0,0,0,0,0,0,0,0,0,0,0,0,0,0,0,0,0,0,0,0,0,0,0~
,0,0,0,0,0,0,0,0,DD73)';
      PINUSE='POWER';
      NO_LOAD_CHECK='Both';
      NO_IO_CHECK='Both';
      NO_ASSERT_CHECK='TRUE';
      NO_DIR_CHECK='TRUE';
      ALLOW_CONNECT='TRUE';
    'VSS_DE1':
      PIN_NUMBER='(0,0,0,0,0,0,0,0,0,0,0,0,0,0,0,0,0,0,0,0,0,0,0,0,0,0,0,0,0,0,0~
,0,0,0,0,0,0,0,0,DE1)';
      PINUSE='POWER';
      NO_LOAD_CHECK='Both';
      NO_IO_CHECK='Both';
      NO_ASSERT_CHECK='TRUE';
      NO_DIR_CHECK='TRUE';
      ALLOW_CONNECT='TRUE';
    'VSS_DE6':
      PIN_NUMBER='(0,0,0,0,0,0,0,0,0,0,0,0,0,0,0,0,0,0,0,0,0,0,0,0,0,0,0,0,0,0,0~
,0,0,0,0,0,0,0,0,DE6)';
      PINUSE='POWER';
      NO_LOAD_CHECK='Both';
      NO_IO_CHECK='Both';
      NO_ASSERT_CHECK='TRUE';
      NO_DIR_CHECK='TRUE';
      ALLOW_CONNECT='TRUE';
    'VSS_DE8':
      PIN_NUMBER='(0,0,0,0,0,0,0,0,0,0,0,0,0,0,0,0,0,0,0,0,0,0,0,0,0,0,0,0,0,0,0~
,0,0,0,0,0,0,0,0,DE8)';
      PINUSE='POWER';
      NO_LOAD_CHECK='Both';
      NO_IO_CHECK='Both';
      NO_ASSERT_CHECK='TRUE';
      NO_DIR_CHECK='TRUE';
      ALLOW_CONNECT='TRUE';
    'VSS_DE26':
      PIN_NUMBER='(0,0,0,0,0,0,0,0,0,0,0,0,0,0,0,0,0,0,0,0,0,0,0,0,0,0,0,0,0,0,0~
,0,0,0,0,0,0,0,0,DE26)';
      PINUSE='POWER';
      NO_LOAD_CHECK='Both';
      NO_IO_CHECK='Both';
      NO_ASSERT_CHECK='TRUE';
      NO_DIR_CHECK='TRUE';
      ALLOW_CONNECT='TRUE';
    'VSS_DE29':
      PIN_NUMBER='(0,0,0,0,0,0,0,0,0,0,0,0,0,0,0,0,0,0,0,0,0,0,0,0,0,0,0,0,0,0,0~
,0,0,0,0,0,0,0,0,DE29)';
      PINUSE='POWER';
      NO_LOAD_CHECK='Both';
      NO_IO_CHECK='Both';
      NO_ASSERT_CHECK='TRUE';
      NO_DIR_CHECK='TRUE';
      ALLOW_CONNECT='TRUE';
    'VSS_DE33':
      PIN_NUMBER='(0,0,0,0,0,0,0,0,0,0,0,0,0,0,0,0,0,0,0,0,0,0,0,0,0,0,0,0,0,0,0~
,0,0,0,0,0,0,0,0,DE33)';
      PINUSE='POWER';
      NO_LOAD_CHECK='Both';
      NO_IO_CHECK='Both';
      NO_ASSERT_CHECK='TRUE';
      NO_DIR_CHECK='TRUE';
      ALLOW_CONNECT='TRUE';
    'VSS_DE56':
      PIN_NUMBER='(0,0,0,0,0,0,0,0,0,0,0,0,0,0,0,0,0,0,0,0,0,0,0,0,0,0,0,0,0,0,0~
,0,0,0,0,0,0,0,0,DE56)';
      PINUSE='POWER';
      NO_LOAD_CHECK='Both';
      NO_IO_CHECK='Both';
      NO_ASSERT_CHECK='TRUE';
      NO_DIR_CHECK='TRUE';
      ALLOW_CONNECT='TRUE';
    'VSS_DE61':
      PIN_NUMBER='(0,0,0,0,0,0,0,0,0,0,0,0,0,0,0,0,0,0,0,0,0,0,0,0,0,0,0,0,0,0,0~
,0,0,0,0,0,0,0,0,DE61)';
      PINUSE='POWER';
      NO_LOAD_CHECK='Both';
      NO_IO_CHECK='Both';
      NO_ASSERT_CHECK='TRUE';
      NO_DIR_CHECK='TRUE';
      ALLOW_CONNECT='TRUE';
    'VSS_DE63':
      PIN_NUMBER='(0,0,0,0,0,0,0,0,0,0,0,0,0,0,0,0,0,0,0,0,0,0,0,0,0,0,0,0,0,0,0~
,0,0,0,0,0,0,0,0,DE63)';
      PINUSE='POWER';
      NO_LOAD_CHECK='Both';
      NO_IO_CHECK='Both';
      NO_ASSERT_CHECK='TRUE';
      NO_DIR_CHECK='TRUE';
      ALLOW_CONNECT='TRUE';
    'VSS_DE68':
      PIN_NUMBER='(0,0,0,0,0,0,0,0,0,0,0,0,0,0,0,0,0,0,0,0,0,0,0,0,0,0,0,0,0,0,0~
,0,0,0,0,0,0,0,0,DE68)';
      PINUSE='POWER';
      NO_LOAD_CHECK='Both';
      NO_IO_CHECK='Both';
      NO_ASSERT_CHECK='TRUE';
      NO_DIR_CHECK='TRUE';
      ALLOW_CONNECT='TRUE';
    'VSS_DF5':
      PIN_NUMBER='(0,0,0,0,0,0,0,0,0,0,0,0,0,0,0,0,0,0,0,0,0,0,0,0,0,0,0,0,0,0,0~
,0,0,0,0,0,0,0,0,DF5)';
      PINUSE='POWER';
      NO_LOAD_CHECK='Both';
      NO_IO_CHECK='Both';
      NO_ASSERT_CHECK='TRUE';
      NO_DIR_CHECK='TRUE';
      ALLOW_CONNECT='TRUE';
    'VSS_DF6':
      PIN_NUMBER='(0,0,0,0,0,0,0,0,0,0,0,0,0,0,0,0,0,0,0,0,0,0,0,0,0,0,0,0,0,0,0~
,0,0,0,0,0,0,0,0,DF6)';
      PINUSE='POWER';
      NO_LOAD_CHECK='Both';
      NO_IO_CHECK='Both';
      NO_ASSERT_CHECK='TRUE';
      NO_DIR_CHECK='TRUE';
      ALLOW_CONNECT='TRUE';
    'VSS_DF8':
      PIN_NUMBER='(0,0,0,0,0,0,0,0,0,0,0,0,0,0,0,0,0,0,0,0,0,0,0,0,0,0,0,0,0,0,0~
,0,0,0,0,0,0,0,0,DF8)';
      PINUSE='POWER';
      NO_LOAD_CHECK='Both';
      NO_IO_CHECK='Both';
      NO_ASSERT_CHECK='TRUE';
      NO_DIR_CHECK='TRUE';
      ALLOW_CONNECT='TRUE';
    'VSS_DF10':
      PIN_NUMBER='(0,0,0,0,0,0,0,0,0,0,0,0,0,0,0,0,0,0,0,0,0,0,0,0,0,0,0,0,0,0,0~
,0,0,0,0,0,0,0,0,DF10)';
      PINUSE='POWER';
      NO_LOAD_CHECK='Both';
      NO_IO_CHECK='Both';
      NO_ASSERT_CHECK='TRUE';
      NO_DIR_CHECK='TRUE';
      ALLOW_CONNECT='TRUE';
    'VSS_DF11':
      PIN_NUMBER='(0,0,0,0,0,0,0,0,0,0,0,0,0,0,0,0,0,0,0,0,0,0,0,0,0,0,0,0,0,0,0~
,0,0,0,0,0,0,0,0,DF11)';
      PINUSE='POWER';
      NO_LOAD_CHECK='Both';
      NO_IO_CHECK='Both';
      NO_ASSERT_CHECK='TRUE';
      NO_DIR_CHECK='TRUE';
      ALLOW_CONNECT='TRUE';
    'VSS_DF12':
      PIN_NUMBER='(0,0,0,0,0,0,0,0,0,0,0,0,0,0,0,0,0,0,0,0,0,0,0,0,0,0,0,0,0,0,0~
,0,0,0,0,0,0,0,0,DF12)';
      PINUSE='POWER';
      NO_LOAD_CHECK='Both';
      NO_IO_CHECK='Both';
      NO_ASSERT_CHECK='TRUE';
      NO_DIR_CHECK='TRUE';
      ALLOW_CONNECT='TRUE';
    'VSS_DF13':
      PIN_NUMBER='(0,0,0,0,0,0,0,0,0,0,0,0,0,0,0,0,0,0,0,0,0,0,0,0,0,0,0,0,0,0,0~
,0,0,0,0,0,0,0,0,DF13)';
      PINUSE='POWER';
      NO_LOAD_CHECK='Both';
      NO_IO_CHECK='Both';
      NO_ASSERT_CHECK='TRUE';
      NO_DIR_CHECK='TRUE';
      ALLOW_CONNECT='TRUE';
    'VSS_DF20':
      PIN_NUMBER='(0,0,0,0,0,0,0,0,0,0,0,0,0,0,0,0,0,0,0,0,0,0,0,0,0,0,0,0,0,0,0~
,0,0,0,0,0,0,0,0,DF20)';
      PINUSE='POWER';
      NO_LOAD_CHECK='Both';
      NO_IO_CHECK='Both';
      NO_ASSERT_CHECK='TRUE';
      NO_DIR_CHECK='TRUE';
      ALLOW_CONNECT='TRUE';
    'VSS_DF22':
      PIN_NUMBER='(0,0,0,0,0,0,0,0,0,0,0,0,0,0,0,0,0,0,0,0,0,0,0,0,0,0,0,0,0,0,0~
,0,0,0,0,0,0,0,0,DF22)';
      PINUSE='POWER';
      NO_LOAD_CHECK='Both';
      NO_IO_CHECK='Both';
      NO_ASSERT_CHECK='TRUE';
      NO_DIR_CHECK='TRUE';
      ALLOW_CONNECT='TRUE';
    'VSS_DF23':
      PIN_NUMBER='(0,0,0,0,0,0,0,0,0,0,0,0,0,0,0,0,0,0,0,0,0,0,0,0,0,0,0,0,0,0,0~
,0,0,0,0,0,0,0,0,DF23)';
      PINUSE='POWER';
      NO_LOAD_CHECK='Both';
      NO_IO_CHECK='Both';
      NO_ASSERT_CHECK='TRUE';
      NO_DIR_CHECK='TRUE';
      ALLOW_CONNECT='TRUE';
    'VSS_DF26':
      PIN_NUMBER='(0,0,0,0,0,0,0,0,0,0,0,0,0,0,0,0,0,0,0,0,0,0,0,0,0,0,0,0,0,0,0~
,0,0,0,0,0,0,0,0,DF26)';
      PINUSE='POWER';
      NO_LOAD_CHECK='Both';
      NO_IO_CHECK='Both';
      NO_ASSERT_CHECK='TRUE';
      NO_DIR_CHECK='TRUE';
      ALLOW_CONNECT='TRUE';
    'VSS_DF29':
      PIN_NUMBER='(0,0,0,0,0,0,0,0,0,0,0,0,0,0,0,0,0,0,0,0,0,0,0,0,0,0,0,0,0,0,0~
,0,0,0,0,0,0,0,0,DF29)';
      PINUSE='POWER';
      NO_LOAD_CHECK='Both';
      NO_IO_CHECK='Both';
      NO_ASSERT_CHECK='TRUE';
      NO_DIR_CHECK='TRUE';
      ALLOW_CONNECT='TRUE';
    'VSS_DF32':
      PIN_NUMBER='(0,0,0,0,0,0,0,0,0,0,0,0,0,0,0,0,0,0,0,0,0,0,0,0,0,0,0,0,0,0,0~
,0,0,0,0,0,0,0,0,DF32)';
      PINUSE='POWER';
      NO_LOAD_CHECK='Both';
      NO_IO_CHECK='Both';
      NO_ASSERT_CHECK='TRUE';
      NO_DIR_CHECK='TRUE';
      ALLOW_CONNECT='TRUE';
    'VSS_DF35':
      PIN_NUMBER='(0,0,0,0,0,0,0,0,0,0,0,0,0,0,0,0,0,0,0,0,0,0,0,0,0,0,0,0,0,0,0~
,0,0,0,0,0,0,0,0,DF35)';
      PINUSE='POWER';
      NO_LOAD_CHECK='Both';
      NO_IO_CHECK='Both';
      NO_ASSERT_CHECK='TRUE';
      NO_DIR_CHECK='TRUE';
      ALLOW_CONNECT='TRUE';
    'VSS_DF37':
      PIN_NUMBER='(0,0,0,0,0,0,0,0,0,0,0,0,0,0,0,0,0,0,0,0,0,0,0,0,0,0,0,0,0,0,0~
,0,0,0,0,0,0,0,0,DF37)';
      PINUSE='POWER';
      NO_LOAD_CHECK='Both';
      NO_IO_CHECK='Both';
      NO_ASSERT_CHECK='TRUE';
      NO_DIR_CHECK='TRUE';
      ALLOW_CONNECT='TRUE';
    'VSS_DF39':
      PIN_NUMBER='(0,0,0,0,0,0,0,0,0,0,0,0,0,0,0,0,0,0,0,0,0,0,0,0,0,0,0,0,0,0,0~
,0,0,0,0,0,0,0,0,DF39)';
      PINUSE='POWER';
      NO_LOAD_CHECK='Both';
      NO_IO_CHECK='Both';
      NO_ASSERT_CHECK='TRUE';
      NO_DIR_CHECK='TRUE';
      ALLOW_CONNECT='TRUE';
    'VSS_DF42':
      PIN_NUMBER='(0,0,0,0,0,0,0,0,0,0,0,0,0,0,0,0,0,0,0,0,0,0,0,0,0,0,0,0,0,0,0~
,0,0,0,0,0,0,0,0,DF42)';
      PINUSE='POWER';
      NO_LOAD_CHECK='Both';
      NO_IO_CHECK='Both';
      NO_ASSERT_CHECK='TRUE';
      NO_DIR_CHECK='TRUE';
      ALLOW_CONNECT='TRUE';
    'VSS_DF44':
      PIN_NUMBER='(0,0,0,0,0,0,0,0,0,0,0,0,0,0,0,0,0,0,0,0,0,0,0,0,0,0,0,0,0,0,0~
,0,0,0,0,0,0,0,0,DF44)';
      PINUSE='POWER';
      NO_LOAD_CHECK='Both';
      NO_IO_CHECK='Both';
      NO_ASSERT_CHECK='TRUE';
      NO_DIR_CHECK='TRUE';
      ALLOW_CONNECT='TRUE';
    'VSS_DF45':
      PIN_NUMBER='(0,0,0,0,0,0,0,0,0,0,0,0,0,0,0,0,0,0,0,0,0,0,0,0,0,0,0,0,0,0,0~
,0,0,0,0,0,0,0,0,DF45)';
      PINUSE='POWER';
      NO_LOAD_CHECK='Both';
      NO_IO_CHECK='Both';
      NO_ASSERT_CHECK='TRUE';
      NO_DIR_CHECK='TRUE';
      ALLOW_CONNECT='TRUE';
    'VSS_DF46':
      PIN_NUMBER='(0,0,0,0,0,0,0,0,0,0,0,0,0,0,0,0,0,0,0,0,0,0,0,0,0,0,0,0,0,0,0~
,0,0,0,0,0,0,0,0,DF46)';
      PINUSE='POWER';
      NO_LOAD_CHECK='Both';
      NO_IO_CHECK='Both';
      NO_ASSERT_CHECK='TRUE';
      NO_DIR_CHECK='TRUE';
      ALLOW_CONNECT='TRUE';
    'VSS_DF47':
      PIN_NUMBER='(0,0,0,0,0,0,0,0,0,0,0,0,0,0,0,0,0,0,0,0,0,0,0,0,0,0,0,0,0,0,0~
,0,0,0,0,0,0,0,0,DF47)';
      PINUSE='POWER';
      NO_LOAD_CHECK='Both';
      NO_IO_CHECK='Both';
      NO_ASSERT_CHECK='TRUE';
      NO_DIR_CHECK='TRUE';
      ALLOW_CONNECT='TRUE';
    'VSS_DF48':
      PIN_NUMBER='(0,0,0,0,0,0,0,0,0,0,0,0,0,0,0,0,0,0,0,0,0,0,0,0,0,0,0,0,0,0,0~
,0,0,0,0,0,0,0,0,DF48)';
      PINUSE='POWER';
      NO_LOAD_CHECK='Both';
      NO_IO_CHECK='Both';
      NO_ASSERT_CHECK='TRUE';
      NO_DIR_CHECK='TRUE';
      ALLOW_CONNECT='TRUE';
    'VSS_DF49':
      PIN_NUMBER='(0,0,0,0,0,0,0,0,0,0,0,0,0,0,0,0,0,0,0,0,0,0,0,0,0,0,0,0,0,0,0~
,0,0,0,0,0,0,0,0,DF49)';
      PINUSE='POWER';
      NO_LOAD_CHECK='Both';
      NO_IO_CHECK='Both';
      NO_ASSERT_CHECK='TRUE';
      NO_DIR_CHECK='TRUE';
      ALLOW_CONNECT='TRUE';
    'VSS_DF50':
      PIN_NUMBER='(0,0,0,0,0,0,0,0,0,0,0,0,0,0,0,0,0,0,0,0,0,0,0,0,0,0,0,0,0,0,0~
,0,0,0,0,0,0,0,0,DF50)';
      PINUSE='POWER';
      NO_LOAD_CHECK='Both';
      NO_IO_CHECK='Both';
      NO_ASSERT_CHECK='TRUE';
      NO_DIR_CHECK='TRUE';
      ALLOW_CONNECT='TRUE';
    'VSS_DF51':
      PIN_NUMBER='(0,0,0,0,0,0,0,0,0,0,0,0,0,0,0,0,0,0,0,0,0,0,0,0,0,0,0,0,0,0,0~
,0,0,0,0,0,0,0,0,DF51)';
      PINUSE='POWER';
      NO_LOAD_CHECK='Both';
      NO_IO_CHECK='Both';
      NO_ASSERT_CHECK='TRUE';
      NO_DIR_CHECK='TRUE';
      ALLOW_CONNECT='TRUE';
    'VSS_DF52':
      PIN_NUMBER='(0,0,0,0,0,0,0,0,0,0,0,0,0,0,0,0,0,0,0,0,0,0,0,0,0,0,0,0,0,0,0~
,0,0,0,0,0,0,0,0,DF52)';
      PINUSE='POWER';
      NO_LOAD_CHECK='Both';
      NO_IO_CHECK='Both';
      NO_ASSERT_CHECK='TRUE';
      NO_DIR_CHECK='TRUE';
      ALLOW_CONNECT='TRUE';
    'VSS_DF56':
      PIN_NUMBER='(0,0,0,0,0,0,0,0,0,0,0,0,0,0,0,0,0,0,0,0,0,0,0,0,0,0,0,0,0,0,0~
,0,0,0,0,0,0,0,0,DF56)';
      PINUSE='POWER';
      NO_LOAD_CHECK='Both';
      NO_IO_CHECK='Both';
      NO_ASSERT_CHECK='TRUE';
      NO_DIR_CHECK='TRUE';
      ALLOW_CONNECT='TRUE';
    'VSS_DF57':
      PIN_NUMBER='(0,0,0,0,0,0,0,0,0,0,0,0,0,0,0,0,0,0,0,0,0,0,0,0,0,0,0,0,0,0,0~
,0,0,0,0,0,0,0,0,DF57)';
      PINUSE='POWER';
      NO_LOAD_CHECK='Both';
      NO_IO_CHECK='Both';
      NO_ASSERT_CHECK='TRUE';
      NO_DIR_CHECK='TRUE';
      ALLOW_CONNECT='TRUE';
    'VSS_DF58':
      PIN_NUMBER='(0,0,0,0,0,0,0,0,0,0,0,0,0,0,0,0,0,0,0,0,0,0,0,0,0,0,0,0,0,0,0~
,0,0,0,0,0,0,0,0,DF58)';
      PINUSE='POWER';
      NO_LOAD_CHECK='Both';
      NO_IO_CHECK='Both';
      NO_ASSERT_CHECK='TRUE';
      NO_DIR_CHECK='TRUE';
      ALLOW_CONNECT='TRUE';
    'VSS_DF59':
      PIN_NUMBER='(0,0,0,0,0,0,0,0,0,0,0,0,0,0,0,0,0,0,0,0,0,0,0,0,0,0,0,0,0,0,0~
,0,0,0,0,0,0,0,0,DF59)';
      PINUSE='POWER';
      NO_LOAD_CHECK='Both';
      NO_IO_CHECK='Both';
      NO_ASSERT_CHECK='TRUE';
      NO_DIR_CHECK='TRUE';
      ALLOW_CONNECT='TRUE';
    'VSS_DF61':
      PIN_NUMBER='(0,0,0,0,0,0,0,0,0,0,0,0,0,0,0,0,0,0,0,0,0,0,0,0,0,0,0,0,0,0,0~
,0,0,0,0,0,0,0,0,DF61)';
      PINUSE='POWER';
      NO_LOAD_CHECK='Both';
      NO_IO_CHECK='Both';
      NO_ASSERT_CHECK='TRUE';
      NO_DIR_CHECK='TRUE';
      ALLOW_CONNECT='TRUE';
    'VSS_DF63':
      PIN_NUMBER='(0,0,0,0,0,0,0,0,0,0,0,0,0,0,0,0,0,0,0,0,0,0,0,0,0,0,0,0,0,0,0~
,0,0,0,0,0,0,0,0,DF63)';
      PINUSE='POWER';
      NO_LOAD_CHECK='Both';
      NO_IO_CHECK='Both';
      NO_ASSERT_CHECK='TRUE';
      NO_DIR_CHECK='TRUE';
      ALLOW_CONNECT='TRUE';
    'VSS_DF64':
      PIN_NUMBER='(0,0,0,0,0,0,0,0,0,0,0,0,0,0,0,0,0,0,0,0,0,0,0,0,0,0,0,0,0,0,0~
,0,0,0,0,0,0,0,0,DF64)';
      PINUSE='POWER';
      NO_LOAD_CHECK='Both';
      NO_IO_CHECK='Both';
      NO_ASSERT_CHECK='TRUE';
      NO_DIR_CHECK='TRUE';
      ALLOW_CONNECT='TRUE';
    'VSS_DF65':
      PIN_NUMBER='(0,0,0,0,0,0,0,0,0,0,0,0,0,0,0,0,0,0,0,0,0,0,0,0,0,0,0,0,0,0,0~
,0,0,0,0,0,0,0,0,DF65)';
      PINUSE='POWER';
      NO_LOAD_CHECK='Both';
      NO_IO_CHECK='Both';
      NO_ASSERT_CHECK='TRUE';
      NO_DIR_CHECK='TRUE';
      ALLOW_CONNECT='TRUE';
    'VSS_DF71':
      PIN_NUMBER='(0,0,0,0,0,0,0,0,0,0,0,0,0,0,0,0,0,0,0,0,0,0,0,0,0,0,0,0,0,0,0~
,0,0,0,0,0,0,0,0,DF71)';
      PINUSE='POWER';
      NO_LOAD_CHECK='Both';
      NO_IO_CHECK='Both';
      NO_ASSERT_CHECK='TRUE';
      NO_DIR_CHECK='TRUE';
      ALLOW_CONNECT='TRUE';
    'VSS_DF72':
      PIN_NUMBER='(0,0,0,0,0,0,0,0,0,0,0,0,0,0,0,0,0,0,0,0,0,0,0,0,0,0,0,0,0,0,0~
,0,0,0,0,0,0,0,0,DF72)';
      PINUSE='POWER';
      NO_LOAD_CHECK='Both';
      NO_IO_CHECK='Both';
      NO_ASSERT_CHECK='TRUE';
      NO_DIR_CHECK='TRUE';
      ALLOW_CONNECT='TRUE';
    'VSS_DF73':
      PIN_NUMBER='(0,0,0,0,0,0,0,0,0,0,0,0,0,0,0,0,0,0,0,0,0,0,0,0,0,0,0,0,0,0,0~
,0,0,0,0,0,0,0,0,DF73)';
      PINUSE='POWER';
      NO_LOAD_CHECK='Both';
      NO_IO_CHECK='Both';
      NO_ASSERT_CHECK='TRUE';
      NO_DIR_CHECK='TRUE';
      ALLOW_CONNECT='TRUE';
    'VSS_DG1':
      PIN_NUMBER='(0,0,0,0,0,0,0,0,0,0,0,0,0,0,0,0,0,0,0,0,0,0,0,0,0,0,0,0,0,0,0~
,0,0,0,0,0,0,0,0,DG1)';
      PINUSE='POWER';
      NO_LOAD_CHECK='Both';
      NO_IO_CHECK='Both';
      NO_ASSERT_CHECK='TRUE';
      NO_DIR_CHECK='TRUE';
      ALLOW_CONNECT='TRUE';
    'VSS_DG2':
      PIN_NUMBER='(0,0,0,0,0,0,0,0,0,0,0,0,0,0,0,0,0,0,0,0,0,0,0,0,0,0,0,0,0,0,0~
,0,0,0,0,0,0,0,0,DG2)';
      PINUSE='POWER';
      NO_LOAD_CHECK='Both';
      NO_IO_CHECK='Both';
      NO_ASSERT_CHECK='TRUE';
      NO_DIR_CHECK='TRUE';
      ALLOW_CONNECT='TRUE';
    'VSS_DG6':
      PIN_NUMBER='(0,0,0,0,0,0,0,0,0,0,0,0,0,0,0,0,0,0,0,0,0,0,0,0,0,0,0,0,0,0,0~
,0,0,0,0,0,0,0,0,DG6)';
      PINUSE='POWER';
      NO_LOAD_CHECK='Both';
      NO_IO_CHECK='Both';
      NO_ASSERT_CHECK='TRUE';
      NO_DIR_CHECK='TRUE';
      ALLOW_CONNECT='TRUE';
    'VSS_DG7':
      PIN_NUMBER='(0,0,0,0,0,0,0,0,0,0,0,0,0,0,0,0,0,0,0,0,0,0,0,0,0,0,0,0,0,0,0~
,0,0,0,0,0,0,0,0,DG7)';
      PINUSE='POWER';
      NO_LOAD_CHECK='Both';
      NO_IO_CHECK='Both';
      NO_ASSERT_CHECK='TRUE';
      NO_DIR_CHECK='TRUE';
      ALLOW_CONNECT='TRUE';
    'VSS_DG15':
      PIN_NUMBER='(0,0,0,0,0,0,0,0,0,0,0,0,0,0,0,0,0,0,0,0,0,0,0,0,0,0,0,0,0,0,0~
,0,0,0,0,0,0,0,0,DG15)';
      PINUSE='POWER';
      NO_LOAD_CHECK='Both';
      NO_IO_CHECK='Both';
      NO_ASSERT_CHECK='TRUE';
      NO_DIR_CHECK='TRUE';
      ALLOW_CONNECT='TRUE';
    'VSS_DG16':
      PIN_NUMBER='(0,0,0,0,0,0,0,0,0,0,0,0,0,0,0,0,0,0,0,0,0,0,0,0,0,0,0,0,0,0,0~
,0,0,0,0,0,0,0,0,DG16)';
      PINUSE='POWER';
      NO_LOAD_CHECK='Both';
      NO_IO_CHECK='Both';
      NO_ASSERT_CHECK='TRUE';
      NO_DIR_CHECK='TRUE';
      ALLOW_CONNECT='TRUE';
    'VSS_DG18':
      PIN_NUMBER='(0,0,0,0,0,0,0,0,0,0,0,0,0,0,0,0,0,0,0,0,0,0,0,0,0,0,0,0,0,0,0~
,0,0,0,0,0,0,0,0,DG18)';
      PINUSE='POWER';
      NO_LOAD_CHECK='Both';
      NO_IO_CHECK='Both';
      NO_ASSERT_CHECK='TRUE';
      NO_DIR_CHECK='TRUE';
      ALLOW_CONNECT='TRUE';
    'VSS_DG20':
      PIN_NUMBER='(0,0,0,0,0,0,0,0,0,0,0,0,0,0,0,0,0,0,0,0,0,0,0,0,0,0,0,0,0,0,0~
,0,0,0,0,0,0,0,0,DG20)';
      PINUSE='POWER';
      NO_LOAD_CHECK='Both';
      NO_IO_CHECK='Both';
      NO_ASSERT_CHECK='TRUE';
      NO_DIR_CHECK='TRUE';
      ALLOW_CONNECT='TRUE';
    'VSS_DG21':
      PIN_NUMBER='(0,0,0,0,0,0,0,0,0,0,0,0,0,0,0,0,0,0,0,0,0,0,0,0,0,0,0,0,0,0,0~
,0,0,0,0,0,0,0,0,DG21)';
      PINUSE='POWER';
      NO_LOAD_CHECK='Both';
      NO_IO_CHECK='Both';
      NO_ASSERT_CHECK='TRUE';
      NO_DIR_CHECK='TRUE';
      ALLOW_CONNECT='TRUE';
    'VSS_DG24':
      PIN_NUMBER='(0,0,0,0,0,0,0,0,0,0,0,0,0,0,0,0,0,0,0,0,0,0,0,0,0,0,0,0,0,0,0~
,0,0,0,0,0,0,0,0,DG24)';
      PINUSE='POWER';
      NO_LOAD_CHECK='Both';
      NO_IO_CHECK='Both';
      NO_ASSERT_CHECK='TRUE';
      NO_DIR_CHECK='TRUE';
      ALLOW_CONNECT='TRUE';
    'VSS_DG27':
      PIN_NUMBER='(0,0,0,0,0,0,0,0,0,0,0,0,0,0,0,0,0,0,0,0,0,0,0,0,0,0,0,0,0,0,0~
,0,0,0,0,0,0,0,0,DG27)';
      PINUSE='POWER';
      NO_LOAD_CHECK='Both';
      NO_IO_CHECK='Both';
      NO_ASSERT_CHECK='TRUE';
      NO_DIR_CHECK='TRUE';
      ALLOW_CONNECT='TRUE';
    'VSS_DG46':
      PIN_NUMBER='(0,0,0,0,0,0,0,0,0,0,0,0,0,0,0,0,0,0,0,0,0,0,0,0,0,0,0,0,0,0,0~
,0,0,0,0,0,0,0,0,DG46)';
      PINUSE='POWER';
      NO_LOAD_CHECK='Both';
      NO_IO_CHECK='Both';
      NO_ASSERT_CHECK='TRUE';
      NO_DIR_CHECK='TRUE';
      ALLOW_CONNECT='TRUE';
    'VSS_DG49':
      PIN_NUMBER='(0,0,0,0,0,0,0,0,0,0,0,0,0,0,0,0,0,0,0,0,0,0,0,0,0,0,0,0,0,0,0~
,0,0,0,0,0,0,0,0,DG49)';
      PINUSE='POWER';
      NO_LOAD_CHECK='Both';
      NO_IO_CHECK='Both';
      NO_ASSERT_CHECK='TRUE';
      NO_DIR_CHECK='TRUE';
      ALLOW_CONNECT='TRUE';
    'VSS_DG52':
      PIN_NUMBER='(0,0,0,0,0,0,0,0,0,0,0,0,0,0,0,0,0,0,0,0,0,0,0,0,0,0,0,0,0,0,0~
,0,0,0,0,0,0,0,0,DG52)';
      PINUSE='POWER';
      NO_LOAD_CHECK='Both';
      NO_IO_CHECK='Both';
      NO_ASSERT_CHECK='TRUE';
      NO_DIR_CHECK='TRUE';
      ALLOW_CONNECT='TRUE';
    'VSS_DG55':
      PIN_NUMBER='(0,0,0,0,0,0,0,0,0,0,0,0,0,0,0,0,0,0,0,0,0,0,0,0,0,0,0,0,0,0,0~
,0,0,0,0,0,0,0,0,DG55)';
      PINUSE='POWER';
      NO_LOAD_CHECK='Both';
      NO_IO_CHECK='Both';
      NO_ASSERT_CHECK='TRUE';
      NO_DIR_CHECK='TRUE';
      ALLOW_CONNECT='TRUE';
    'VSS_DG56':
      PIN_NUMBER='(0,0,0,0,0,0,0,0,0,0,0,0,0,0,0,0,0,0,0,0,0,0,0,0,0,0,0,0,0,0,0~
,0,0,0,0,0,0,0,0,DG56)';
      PINUSE='POWER';
      NO_LOAD_CHECK='Both';
      NO_IO_CHECK='Both';
      NO_ASSERT_CHECK='TRUE';
      NO_DIR_CHECK='TRUE';
      ALLOW_CONNECT='TRUE';
    'VSS_DG59':
      PIN_NUMBER='(0,0,0,0,0,0,0,0,0,0,0,0,0,0,0,0,0,0,0,0,0,0,0,0,0,0,0,0,0,0,0~
,0,0,0,0,0,0,0,0,DG59)';
      PINUSE='POWER';
      NO_LOAD_CHECK='Both';
      NO_IO_CHECK='Both';
      NO_ASSERT_CHECK='TRUE';
      NO_DIR_CHECK='TRUE';
      ALLOW_CONNECT='TRUE';
    'VSS_DG60':
      PIN_NUMBER='(0,0,0,0,0,0,0,0,0,0,0,0,0,0,0,0,0,0,0,0,0,0,0,0,0,0,0,0,0,0,0~
,0,0,0,0,0,0,0,0,DG60)';
      PINUSE='POWER';
      NO_LOAD_CHECK='Both';
      NO_IO_CHECK='Both';
      NO_ASSERT_CHECK='TRUE';
      NO_DIR_CHECK='TRUE';
      ALLOW_CONNECT='TRUE';
    'VSS_DG66':
      PIN_NUMBER='(0,0,0,0,0,0,0,0,0,0,0,0,0,0,0,0,0,0,0,0,0,0,0,0,0,0,0,0,0,0,0~
,0,0,0,0,0,0,0,0,DG66)';
      PINUSE='POWER';
      NO_LOAD_CHECK='Both';
      NO_IO_CHECK='Both';
      NO_ASSERT_CHECK='TRUE';
      NO_DIR_CHECK='TRUE';
      ALLOW_CONNECT='TRUE';
    'VSS_DG67':
      PIN_NUMBER='(0,0,0,0,0,0,0,0,0,0,0,0,0,0,0,0,0,0,0,0,0,0,0,0,0,0,0,0,0,0,0~
,0,0,0,0,0,0,0,0,DG67)';
      PINUSE='POWER';
      NO_LOAD_CHECK='Both';
      NO_IO_CHECK='Both';
      NO_ASSERT_CHECK='TRUE';
      NO_DIR_CHECK='TRUE';
      ALLOW_CONNECT='TRUE';
    'VSS_DG68':
      PIN_NUMBER='(0,0,0,0,0,0,0,0,0,0,0,0,0,0,0,0,0,0,0,0,0,0,0,0,0,0,0,0,0,0,0~
,0,0,0,0,0,0,0,0,DG68)';
      PINUSE='POWER';
      NO_LOAD_CHECK='Both';
      NO_IO_CHECK='Both';
      NO_ASSERT_CHECK='TRUE';
      NO_DIR_CHECK='TRUE';
      ALLOW_CONNECT='TRUE';
    'VSS_DG69':
      PIN_NUMBER='(0,0,0,0,0,0,0,0,0,0,0,0,0,0,0,0,0,0,0,0,0,0,0,0,0,0,0,0,0,0,0~
,0,0,0,0,0,0,0,0,DG69)';
      PINUSE='POWER';
      NO_LOAD_CHECK='Both';
      NO_IO_CHECK='Both';
      NO_ASSERT_CHECK='TRUE';
      NO_DIR_CHECK='TRUE';
      ALLOW_CONNECT='TRUE';
    'VSS_DG70':
      PIN_NUMBER='(0,0,0,0,0,0,0,0,0,0,0,0,0,0,0,0,0,0,0,0,0,0,0,0,0,0,0,0,0,0,0~
,0,0,0,0,0,0,0,0,DG70)';
      PINUSE='POWER';
      NO_LOAD_CHECK='Both';
      NO_IO_CHECK='Both';
      NO_ASSERT_CHECK='TRUE';
      NO_DIR_CHECK='TRUE';
      ALLOW_CONNECT='TRUE';
    'VSS_DG74':
      PIN_NUMBER='(0,0,0,0,0,0,0,0,0,0,0,0,0,0,0,0,0,0,0,0,0,0,0,0,0,0,0,0,0,0,0~
,0,0,0,0,0,0,0,0,DG74)';
      PINUSE='POWER';
      NO_LOAD_CHECK='Both';
      NO_IO_CHECK='Both';
      NO_ASSERT_CHECK='TRUE';
      NO_DIR_CHECK='TRUE';
      ALLOW_CONNECT='TRUE';
    'VSS_DG75':
      PIN_NUMBER='(0,0,0,0,0,0,0,0,0,0,0,0,0,0,0,0,0,0,0,0,0,0,0,0,0,0,0,0,0,0,0~
,0,0,0,0,0,0,0,0,DG75)';
      PINUSE='POWER';
      NO_LOAD_CHECK='Both';
      NO_IO_CHECK='Both';
      NO_ASSERT_CHECK='TRUE';
      NO_DIR_CHECK='TRUE';
      ALLOW_CONNECT='TRUE';
    'VSS_DH39':
      PIN_NUMBER='(0,0,0,0,0,0,0,0,0,0,0,0,0,0,0,0,0,0,0,0,0,0,0,0,0,0,0,0,0,0,0~
,0,0,0,0,0,0,0,0,DH39)';
      PINUSE='POWER';
      NO_LOAD_CHECK='Both';
      NO_IO_CHECK='Both';
      NO_ASSERT_CHECK='TRUE';
      NO_DIR_CHECK='TRUE';
      ALLOW_CONNECT='TRUE';
    'VSS_DH43':
      PIN_NUMBER='(0,0,0,0,0,0,0,0,0,0,0,0,0,0,0,0,0,0,0,0,0,0,0,0,0,0,0,0,0,0,0~
,0,0,0,0,0,0,0,0,DH43)';
      PINUSE='POWER';
      NO_LOAD_CHECK='Both';
      NO_IO_CHECK='Both';
      NO_ASSERT_CHECK='TRUE';
      NO_DIR_CHECK='TRUE';
      ALLOW_CONNECT='TRUE';
    'VSS_DH46':
      PIN_NUMBER='(0,0,0,0,0,0,0,0,0,0,0,0,0,0,0,0,0,0,0,0,0,0,0,0,0,0,0,0,0,0,0~
,0,0,0,0,0,0,0,0,DH46)';
      PINUSE='POWER';
      NO_LOAD_CHECK='Both';
      NO_IO_CHECK='Both';
      NO_ASSERT_CHECK='TRUE';
      NO_DIR_CHECK='TRUE';
      ALLOW_CONNECT='TRUE';
    'VSS_DH49':
      PIN_NUMBER='(0,0,0,0,0,0,0,0,0,0,0,0,0,0,0,0,0,0,0,0,0,0,0,0,0,0,0,0,0,0,0~
,0,0,0,0,0,0,0,0,DH49)';
      PINUSE='POWER';
      NO_LOAD_CHECK='Both';
      NO_IO_CHECK='Both';
      NO_ASSERT_CHECK='TRUE';
      NO_DIR_CHECK='TRUE';
      ALLOW_CONNECT='TRUE';
    'VSS_DH52':
      PIN_NUMBER='(0,0,0,0,0,0,0,0,0,0,0,0,0,0,0,0,0,0,0,0,0,0,0,0,0,0,0,0,0,0,0~
,0,0,0,0,0,0,0,0,DH52)';
      PINUSE='POWER';
      NO_LOAD_CHECK='Both';
      NO_IO_CHECK='Both';
      NO_ASSERT_CHECK='TRUE';
      NO_DIR_CHECK='TRUE';
      ALLOW_CONNECT='TRUE';
    'VSS_DH55':
      PIN_NUMBER='(0,0,0,0,0,0,0,0,0,0,0,0,0,0,0,0,0,0,0,0,0,0,0,0,0,0,0,0,0,0,0~
,0,0,0,0,0,0,0,0,DH55)';
      PINUSE='POWER';
      NO_LOAD_CHECK='Both';
      NO_IO_CHECK='Both';
      NO_ASSERT_CHECK='TRUE';
      NO_DIR_CHECK='TRUE';
      ALLOW_CONNECT='TRUE';
    'VSS_DH59':
      PIN_NUMBER='(0,0,0,0,0,0,0,0,0,0,0,0,0,0,0,0,0,0,0,0,0,0,0,0,0,0,0,0,0,0,0~
,0,0,0,0,0,0,0,0,DH59)';
      PINUSE='POWER';
      NO_LOAD_CHECK='Both';
      NO_IO_CHECK='Both';
      NO_ASSERT_CHECK='TRUE';
      NO_DIR_CHECK='TRUE';
      ALLOW_CONNECT='TRUE';
    'VSS_DH68':
      PIN_NUMBER='(0,0,0,0,0,0,0,0,0,0,0,0,0,0,0,0,0,0,0,0,0,0,0,0,0,0,0,0,0,0,0~
,0,0,0,0,0,0,0,0,DH68)';
      PINUSE='POWER';
      NO_LOAD_CHECK='Both';
      NO_IO_CHECK='Both';
      NO_ASSERT_CHECK='TRUE';
      NO_DIR_CHECK='TRUE';
      ALLOW_CONNECT='TRUE';
    'VSS_DH70':
      PIN_NUMBER='(0,0,0,0,0,0,0,0,0,0,0,0,0,0,0,0,0,0,0,0,0,0,0,0,0,0,0,0,0,0,0~
,0,0,0,0,0,0,0,0,DH70)';
      PINUSE='POWER';
      NO_LOAD_CHECK='Both';
      NO_IO_CHECK='Both';
      NO_ASSERT_CHECK='TRUE';
      NO_DIR_CHECK='TRUE';
      ALLOW_CONNECT='TRUE';
    'VSS_DJ7':
      PIN_NUMBER='(0,0,0,0,0,0,0,0,0,0,0,0,0,0,0,0,0,0,0,0,0,0,0,0,0,0,0,0,0,0,0~
,0,0,0,0,0,0,0,0,DJ7)';
      PINUSE='POWER';
      NO_LOAD_CHECK='Both';
      NO_IO_CHECK='Both';
      NO_ASSERT_CHECK='TRUE';
      NO_DIR_CHECK='TRUE';
      ALLOW_CONNECT='TRUE';
    'VSS_DJ15':
      PIN_NUMBER='(0,0,0,0,0,0,0,0,0,0,0,0,0,0,0,0,0,0,0,0,0,0,0,0,0,0,0,0,0,0,0~
,0,0,0,0,0,0,0,0,DJ15)';
      PINUSE='POWER';
      NO_LOAD_CHECK='Both';
      NO_IO_CHECK='Both';
      NO_ASSERT_CHECK='TRUE';
      NO_DIR_CHECK='TRUE';
      ALLOW_CONNECT='TRUE';
    'VSS_DJ19':
      PIN_NUMBER='(0,0,0,0,0,0,0,0,0,0,0,0,0,0,0,0,0,0,0,0,0,0,0,0,0,0,0,0,0,0,0~
,0,0,0,0,0,0,0,0,DJ19)';
      PINUSE='POWER';
      NO_LOAD_CHECK='Both';
      NO_IO_CHECK='Both';
      NO_ASSERT_CHECK='TRUE';
      NO_DIR_CHECK='TRUE';
      ALLOW_CONNECT='TRUE';
    'VSS_DJ43':
      PIN_NUMBER='(0,0,0,0,0,0,0,0,0,0,0,0,0,0,0,0,0,0,0,0,0,0,0,0,0,0,0,0,0,0,0~
,0,0,0,0,0,0,0,0,DJ43)';
      PINUSE='POWER';
      NO_LOAD_CHECK='Both';
      NO_IO_CHECK='Both';
      NO_ASSERT_CHECK='TRUE';
      NO_DIR_CHECK='TRUE';
      ALLOW_CONNECT='TRUE';
    'VSS_DJ49':
      PIN_NUMBER='(0,0,0,0,0,0,0,0,0,0,0,0,0,0,0,0,0,0,0,0,0,0,0,0,0,0,0,0,0,0,0~
,0,0,0,0,0,0,0,0,DJ49)';
      PINUSE='POWER';
      NO_LOAD_CHECK='Both';
      NO_IO_CHECK='Both';
      NO_ASSERT_CHECK='TRUE';
      NO_DIR_CHECK='TRUE';
      ALLOW_CONNECT='TRUE';
    'VSS_DJ59':
      PIN_NUMBER='(0,0,0,0,0,0,0,0,0,0,0,0,0,0,0,0,0,0,0,0,0,0,0,0,0,0,0,0,0,0,0~
,0,0,0,0,0,0,0,0,DJ59)';
      PINUSE='POWER';
      NO_LOAD_CHECK='Both';
      NO_IO_CHECK='Both';
      NO_ASSERT_CHECK='TRUE';
      NO_DIR_CHECK='TRUE';
      ALLOW_CONNECT='TRUE';
    'VSS_DJ61':
      PIN_NUMBER='(0,0,0,0,0,0,0,0,0,0,0,0,0,0,0,0,0,0,0,0,0,0,0,0,0,0,0,0,0,0,0~
,0,0,0,0,0,0,0,0,DJ61)';
      PINUSE='POWER';
      NO_LOAD_CHECK='Both';
      NO_IO_CHECK='Both';
      NO_ASSERT_CHECK='TRUE';
      NO_DIR_CHECK='TRUE';
      ALLOW_CONNECT='TRUE';
    'VSS_DJ63':
      PIN_NUMBER='(0,0,0,0,0,0,0,0,0,0,0,0,0,0,0,0,0,0,0,0,0,0,0,0,0,0,0,0,0,0,0~
,0,0,0,0,0,0,0,0,DJ63)';
      PINUSE='POWER';
      NO_LOAD_CHECK='Both';
      NO_IO_CHECK='Both';
      NO_ASSERT_CHECK='TRUE';
      NO_DIR_CHECK='TRUE';
      ALLOW_CONNECT='TRUE';
    'VSS_DJ66':
      PIN_NUMBER='(0,0,0,0,0,0,0,0,0,0,0,0,0,0,0,0,0,0,0,0,0,0,0,0,0,0,0,0,0,0,0~
,0,0,0,0,0,0,0,0,DJ66)';
      PINUSE='POWER';
      NO_LOAD_CHECK='Both';
      NO_IO_CHECK='Both';
      NO_ASSERT_CHECK='TRUE';
      NO_DIR_CHECK='TRUE';
      ALLOW_CONNECT='TRUE';
    'VSS_DJ68':
      PIN_NUMBER='(0,0,0,0,0,0,0,0,0,0,0,0,0,0,0,0,0,0,0,0,0,0,0,0,0,0,0,0,0,0,0~
,0,0,0,0,0,0,0,0,DJ68)';
      PINUSE='POWER';
      NO_LOAD_CHECK='Both';
      NO_IO_CHECK='Both';
      NO_ASSERT_CHECK='TRUE';
      NO_DIR_CHECK='TRUE';
      ALLOW_CONNECT='TRUE';
    'VSS_DJ73':
      PIN_NUMBER='(0,0,0,0,0,0,0,0,0,0,0,0,0,0,0,0,0,0,0,0,0,0,0,0,0,0,0,0,0,0,0~
,0,0,0,0,0,0,0,0,DJ73)';
      PINUSE='POWER';
      NO_LOAD_CHECK='Both';
      NO_IO_CHECK='Both';
      NO_ASSERT_CHECK='TRUE';
      NO_DIR_CHECK='TRUE';
      ALLOW_CONNECT='TRUE';
    'VSS_CY57':
      PIN_NUMBER='(0,0,0,0,0,0,0,0,0,0,0,0,0,0,0,0,0,0,0,0,0,0,0,0,0,0,0,0,0,0,0~
,0,0,0,0,0,0,0,0,CY57)';
      PINUSE='POWER';
      NO_LOAD_CHECK='Both';
      NO_IO_CHECK='Both';
      NO_ASSERT_CHECK='TRUE';
      NO_DIR_CHECK='TRUE';
      ALLOW_CONNECT='TRUE';
    'VSS_CK31':
      PIN_NUMBER='(0,0,0,0,0,0,0,0,0,0,0,0,0,0,0,0,0,0,0,0,0,0,0,0,0,0,0,0,0,0,0~
,0,0,0,0,0,0,0,0,CK31)';
      PINUSE='POWER';
      NO_LOAD_CHECK='Both';
      NO_IO_CHECK='Both';
      NO_ASSERT_CHECK='TRUE';
      NO_DIR_CHECK='TRUE';
      ALLOW_CONNECT='TRUE';
    'VSS_CB44':
      PIN_NUMBER='(0,0,0,0,0,0,0,0,0,0,0,0,0,0,0,0,0,0,0,0,0,0,0,0,0,0,0,0,0,0,0~
,0,0,0,0,0,0,0,0,CB44)';
      PINUSE='POWER';
      NO_LOAD_CHECK='Both';
      NO_IO_CHECK='Both';
      NO_ASSERT_CHECK='TRUE';
      NO_DIR_CHECK='TRUE';
      ALLOW_CONNECT='TRUE';
    'VSS_AM37':
      PIN_NUMBER='(0,0,0,0,0,0,0,0,0,0,0,0,0,0,0,0,0,0,0,0,0,0,0,0,0,0,0,0,0,0,0~
,0,0,0,0,0,0,0,0,AM37)';
      PINUSE='POWER';
      NO_LOAD_CHECK='Both';
      NO_IO_CHECK='Both';
      NO_ASSERT_CHECK='TRUE';
      NO_DIR_CHECK='TRUE';
      ALLOW_CONNECT='TRUE';
    'VSS_K23':
      PIN_NUMBER='(0,0,0,0,0,0,0,0,0,0,0,0,0,0,0,0,0,0,0,0,0,0,0,0,0,0,0,0,0,0,0~
,0,0,0,0,0,0,0,0,K23)';
      PINUSE='POWER';
      NO_LOAD_CHECK='Both';
      NO_IO_CHECK='Both';
      NO_ASSERT_CHECK='TRUE';
      NO_DIR_CHECK='TRUE';
      ALLOW_CONNECT='TRUE';
    'VSS_CN54':
      PIN_NUMBER='(0,0,0,0,0,0,0,0,0,0,0,0,0,0,0,0,0,0,0,0,0,0,0,0,0,0,0,0,0,0,0~
,0,0,0,0,0,0,0,0,CN54)';
      PINUSE='POWER';
      NO_LOAD_CHECK='Both';
      NO_IO_CHECK='Both';
      NO_ASSERT_CHECK='TRUE';
      NO_DIR_CHECK='TRUE';
      ALLOW_CONNECT='TRUE';
    'VSS_CK10':
      PIN_NUMBER='(0,0,0,0,0,0,0,0,0,0,0,0,0,0,0,0,0,0,0,0,0,0,0,0,0,0,0,0,0,0,0~
,0,0,0,0,0,0,0,0,CK10)';
      PINUSE='POWER';
      NO_LOAD_CHECK='Both';
      NO_IO_CHECK='Both';
      NO_ASSERT_CHECK='TRUE';
      NO_DIR_CHECK='TRUE';
      ALLOW_CONNECT='TRUE';
    'VSS_AA72':
      PIN_NUMBER='(0,0,0,0,0,0,0,0,0,0,0,0,0,0,0,0,0,0,0,0,0,0,0,0,0,0,0,0,0,0,0~
,0,0,0,0,0,0,0,0,AA72)';
      PINUSE='POWER';
      NO_LOAD_CHECK='Both';
      NO_IO_CHECK='Both';
      NO_ASSERT_CHECK='TRUE';
      NO_DIR_CHECK='TRUE';
      ALLOW_CONNECT='TRUE';
    'VSS_AJ13':
      PIN_NUMBER='(0,0,0,0,0,0,0,0,0,0,0,0,0,0,0,0,0,0,0,0,0,0,0,0,0,0,0,0,0,0,0~
,0,0,0,0,0,0,0,0,AJ13)';
      PINUSE='POWER';
      NO_LOAD_CHECK='Both';
      NO_IO_CHECK='Both';
      NO_ASSERT_CHECK='TRUE';
      NO_DIR_CHECK='TRUE';
      ALLOW_CONNECT='TRUE';
    'VSS_AD31':
      PIN_NUMBER='(0,0,0,0,0,0,0,0,0,0,0,0,0,0,0,0,0,0,0,0,0,0,0,0,0,0,0,0,0,0,0~
,0,0,0,0,0,0,0,0,AD31)';
      PINUSE='POWER';
      NO_LOAD_CHECK='Both';
      NO_IO_CHECK='Both';
      NO_ASSERT_CHECK='TRUE';
      NO_DIR_CHECK='TRUE';
      ALLOW_CONNECT='TRUE';
    'VSS_AA42':
      PIN_NUMBER='(0,0,0,0,0,0,0,0,0,0,0,0,0,0,0,0,0,0,0,0,0,0,0,0,0,0,0,0,0,0,0~
,0,0,0,0,0,0,0,0,AA42)';
      PINUSE='POWER';
      NO_LOAD_CHECK='Both';
      NO_IO_CHECK='Both';
      NO_ASSERT_CHECK='TRUE';
      NO_DIR_CHECK='TRUE';
      ALLOW_CONNECT='TRUE';
    'VSS_V27':
      PIN_NUMBER='(0,0,0,0,0,0,0,0,0,0,0,0,0,0,0,0,0,0,0,0,0,0,0,0,0,0,0,0,0,0,0~
,0,0,0,0,0,0,0,0,V27)';
      PINUSE='POWER';
      NO_LOAD_CHECK='Both';
      NO_IO_CHECK='Both';
      NO_ASSERT_CHECK='TRUE';
      NO_DIR_CHECK='TRUE';
      ALLOW_CONNECT='TRUE';
    'VSS_CF46':
      PIN_NUMBER='(0,0,0,0,0,0,0,0,0,0,0,0,0,0,0,0,0,0,0,0,0,0,0,0,0,0,0,0,0,0,0~
,0,0,0,0,0,0,0,0,CF46)';
      PINUSE='POWER';
      NO_LOAD_CHECK='Both';
      NO_IO_CHECK='Both';
      NO_ASSERT_CHECK='TRUE';
      NO_DIR_CHECK='TRUE';
      ALLOW_CONNECT='TRUE';
    'VSS_CC22':
      PIN_NUMBER='(0,0,0,0,0,0,0,0,0,0,0,0,0,0,0,0,0,0,0,0,0,0,0,0,0,0,0,0,0,0,0~
,0,0,0,0,0,0,0,0,CC22)';
      PINUSE='POWER';
      NO_LOAD_CHECK='Both';
      NO_IO_CHECK='Both';
      NO_ASSERT_CHECK='TRUE';
      NO_DIR_CHECK='TRUE';
      ALLOW_CONNECT='TRUE';
    'VSS_AN20':
      PIN_NUMBER='(0,0,0,0,0,0,0,0,0,0,0,0,0,0,0,0,0,0,0,0,0,0,0,0,0,0,0,0,0,0,0~
,0,0,0,0,0,0,0,0,AN20)';
      PINUSE='POWER';
      NO_LOAD_CHECK='Both';
      NO_IO_CHECK='Both';
      NO_ASSERT_CHECK='TRUE';
      NO_DIR_CHECK='TRUE';
      ALLOW_CONNECT='TRUE';
    'VSS_P68':
      PIN_NUMBER='(0,0,0,0,0,0,0,0,0,0,0,0,0,0,0,0,0,0,0,0,0,0,0,0,0,0,0,0,0,0,0~
,0,0,0,0,0,0,0,0,P68)';
      PINUSE='POWER';
      NO_LOAD_CHECK='Both';
      NO_IO_CHECK='Both';
      NO_ASSERT_CHECK='TRUE';
      NO_DIR_CHECK='TRUE';
      ALLOW_CONNECT='TRUE';
    'VSS_P25':
      PIN_NUMBER='(0,0,0,0,0,0,0,0,0,0,0,0,0,0,0,0,0,0,0,0,0,0,0,0,0,0,0,0,0,0,0~
,0,0,0,0,0,0,0,0,P25)';
      PINUSE='POWER';
      NO_LOAD_CHECK='Both';
      NO_IO_CHECK='Both';
      NO_ASSERT_CHECK='TRUE';
      NO_DIR_CHECK='TRUE';
      ALLOW_CONNECT='TRUE';
    'VSS_CU58':
      PIN_NUMBER='(0,0,0,0,0,0,0,0,0,0,0,0,0,0,0,0,0,0,0,0,0,0,0,0,0,0,0,0,0,0,0~
,0,0,0,0,0,0,0,0,CU58)';
      PINUSE='POWER';
      NO_LOAD_CHECK='Both';
      NO_IO_CHECK='Both';
      NO_ASSERT_CHECK='TRUE';
      NO_DIR_CHECK='TRUE';
      ALLOW_CONNECT='TRUE';
    'VSS_BW25':
      PIN_NUMBER='(0,0,0,0,0,0,0,0,0,0,0,0,0,0,0,0,0,0,0,0,0,0,0,0,0,0,0,0,0,0,0~
,0,0,0,0,0,0,0,0,BW25)';
      PINUSE='POWER';
      NO_LOAD_CHECK='Both';
      NO_IO_CHECK='Both';
      NO_ASSERT_CHECK='TRUE';
      NO_DIR_CHECK='TRUE';
      ALLOW_CONNECT='TRUE';
    'VSS_AH33':
      PIN_NUMBER='(0,0,0,0,0,0,0,0,0,0,0,0,0,0,0,0,0,0,0,0,0,0,0,0,0,0,0,0,0,0,0~
,0,0,0,0,0,0,0,0,AH33)';
      PINUSE='POWER';
      NO_LOAD_CHECK='Both';
      NO_IO_CHECK='Both';
      NO_ASSERT_CHECK='TRUE';
      NO_DIR_CHECK='TRUE';
      ALLOW_CONNECT='TRUE';
    'VSS_AE4':
      PIN_NUMBER='(0,0,0,0,0,0,0,0,0,0,0,0,0,0,0,0,0,0,0,0,0,0,0,0,0,0,0,0,0,0,0~
,0,0,0,0,0,0,0,0,AE4)';
      PINUSE='POWER';
      NO_LOAD_CHECK='Both';
      NO_IO_CHECK='Both';
      NO_ASSERT_CHECK='TRUE';
      NO_DIR_CHECK='TRUE';
      ALLOW_CONNECT='TRUE';
    'VSS_CG42':
      PIN_NUMBER='(0,0,0,0,0,0,0,0,0,0,0,0,0,0,0,0,0,0,0,0,0,0,0,0,0,0,0,0,0,0,0~
,0,0,0,0,0,0,0,0,CG42)';
      PINUSE='POWER';
      NO_LOAD_CHECK='Both';
      NO_IO_CHECK='Both';
      NO_ASSERT_CHECK='TRUE';
      NO_DIR_CHECK='TRUE';
      ALLOW_CONNECT='TRUE';
    'VSS_DA56':
      PIN_NUMBER='(0,0,0,0,0,0,0,0,0,0,0,0,0,0,0,0,0,0,0,0,0,0,0,0,0,0,0,0,0,0,0~
,0,0,0,0,0,0,0,0,DA56)';
      PINUSE='POWER';
      NO_LOAD_CHECK='Both';
      NO_IO_CHECK='Both';
      NO_ASSERT_CHECK='TRUE';
      NO_DIR_CHECK='TRUE';
      ALLOW_CONNECT='TRUE';
    'VSS_K59':
      PIN_NUMBER='(0,0,0,0,0,0,0,0,0,0,0,0,0,0,0,0,0,0,0,0,0,0,0,0,0,0,0,0,0,0,0~
,0,0,0,0,0,0,0,0,K59)';
      PINUSE='POWER';
      NO_LOAD_CHECK='Both';
      NO_IO_CHECK='Both';
      NO_ASSERT_CHECK='TRUE';
      NO_DIR_CHECK='TRUE';
      ALLOW_CONNECT='TRUE';
    'VSS_CM50':
      PIN_NUMBER='(0,0,0,0,0,0,0,0,0,0,0,0,0,0,0,0,0,0,0,0,0,0,0,0,0,0,0,0,0,0,0~
,0,0,0,0,0,0,0,0,CM50)';
      PINUSE='POWER';
      NO_LOAD_CHECK='Both';
      NO_IO_CHECK='Both';
      NO_ASSERT_CHECK='TRUE';
      NO_DIR_CHECK='TRUE';
      ALLOW_CONNECT='TRUE';
    'VSS_CT52':
      PIN_NUMBER='(0,0,0,0,0,0,0,0,0,0,0,0,0,0,0,0,0,0,0,0,0,0,0,0,0,0,0,0,0,0,0~
,0,0,0,0,0,0,0,0,CT52)';
      PINUSE='POWER';
      NO_LOAD_CHECK='Both';
      NO_IO_CHECK='Both';
      NO_ASSERT_CHECK='TRUE';
      NO_DIR_CHECK='TRUE';
      ALLOW_CONNECT='TRUE';
    'VSS_BV42':
      PIN_NUMBER='(0,0,0,0,0,0,0,0,0,0,0,0,0,0,0,0,0,0,0,0,0,0,0,0,0,0,0,0,0,0,0~
,0,0,0,0,0,0,0,0,BV42)';
      PINUSE='POWER';
      NO_LOAD_CHECK='Both';
      NO_IO_CHECK='Both';
      NO_ASSERT_CHECK='TRUE';
      NO_DIR_CHECK='TRUE';
      ALLOW_CONNECT='TRUE';
    'VSS_V68':
      PIN_NUMBER='(0,0,0,0,0,0,0,0,0,0,0,0,0,0,0,0,0,0,0,0,0,0,0,0,0,0,0,0,0,0,0~
,0,0,0,0,0,0,0,0,V68)';
      PINUSE='POWER';
      NO_LOAD_CHECK='Both';
      NO_IO_CHECK='Both';
      NO_ASSERT_CHECK='TRUE';
      NO_DIR_CHECK='TRUE';
      ALLOW_CONNECT='TRUE';
  end_pin;
  body
      PART_NAME='GENOA_SP5';
      VALUE='SP5';
      BODY_NAME='GENOA_SP5';
      PHYS_DES_PREFIX='U';
      CLASS='IO';
      NC_PINS='(MH1,MH2,MH3,MH4,MH5,MH6)';
      STANDARD='';
      LIFECYCLE='';
      PART_NUMBER='DGA^6000030';
      JEDEC_TYPE='SOCKET6096_93-4X120-45XA';
      DESCRIPTION='SOCKET SP5 6096P LGA(P0.94,H4)';
      MANUFTR='APL';
      MANUF_PN='13568-001';
      RD_CMPLS_LVL='EP(V1)';
      CMPLS_LVL='';
      DIP_SMD='';
      FROM_PJ='TITANITE-TOM';
      DATA='APL_13568-001.pdf';
      FP_ECN='13568-001.xlsx';
      EE_CHECK_LIST='';
      CREATOR='';
      CREATEDAY='20210715';
      PSL='';
      STATUS='';
      ESD_CDM='';
      ESD_HBM='';
      ESD_MM='';
      MSD='';
      PIN_LENGTH_LONG_PIN='0 MILS';
      PIN_LENGTH_SHORT_PIN='0 MILS';
      PARENT_PART_TYPE='GENOA_SP5';
      PARENT_PPT='GENOA_SP5';
      PARENT_PPT_PART='GENOA_SP5-SOCKET6096_13568-001,SMLF,IO,DGA^6000030';
  end_body;
end_primitive;
primitive 'GL852GOHY60-GL852G-OHY60,SMLF,IC,AL000852001';
  pin
    'X1':
      PIN_NUMBER='(10)';
      INPUT_LOAD='(-0.01,0.01)';
      PINUSE='IN';
    'X2':
      PIN_NUMBER='(11)';
      OUTPUT_LOAD='(1.0,-1.0)';
      PINUSE='OUT';
    'TEST||SCL':
      PIN_NUMBER='(18)';
      BIDIRECTIONAL='TRUE';
      INPUT_LOAD='(-0.01,0.01)';
      OUTPUT_LOAD='(1.0,-1.0)';
      PINUSE='BI';
    'SDA':
      PIN_NUMBER='(26)';
      BIDIRECTIONAL='TRUE';
      INPUT_LOAD='(-0.01,0.01)';
      OUTPUT_LOAD='(1.0,-1.0)';
      PINUSE='BI';
    'V5':
      PIN_NUMBER='(27)';
      PINUSE='POWER';
      NO_LOAD_CHECK='Both';
      NO_IO_CHECK='Both';
      NO_ASSERT_CHECK='TRUE';
      NO_DIR_CHECK='TRUE';
      ALLOW_CONNECT='TRUE';
    'V33':
      PIN_NUMBER='(28)';
      PINUSE='POWER';
      NO_LOAD_CHECK='Both';
      NO_IO_CHECK='Both';
      NO_ASSERT_CHECK='TRUE';
      NO_DIR_CHECK='TRUE';
      ALLOW_CONNECT='TRUE';
    'AVDD'<0>:
      PIN_NUMBER='(5)';
      PINUSE='POWER';
      NO_LOAD_CHECK='Both';
      NO_IO_CHECK='Both';
      NO_ASSERT_CHECK='TRUE';
      NO_DIR_CHECK='TRUE';
      ALLOW_CONNECT='TRUE';
    'AVDD'<1>:
      PIN_NUMBER='(9)';
      PINUSE='POWER';
      NO_LOAD_CHECK='Both';
      NO_IO_CHECK='Both';
      NO_ASSERT_CHECK='TRUE';
      NO_DIR_CHECK='TRUE';
      ALLOW_CONNECT='TRUE';
    'AVDD'<2>:
      PIN_NUMBER='(14)';
      PINUSE='POWER';
      NO_LOAD_CHECK='Both';
      NO_IO_CHECK='Both';
      NO_ASSERT_CHECK='TRUE';
      NO_DIR_CHECK='TRUE';
      ALLOW_CONNECT='TRUE';
    'DVDD':
      PIN_NUMBER='(21)';
      PINUSE='POWER';
      NO_LOAD_CHECK='Both';
      NO_IO_CHECK='Both';
      NO_ASSERT_CHECK='TRUE';
      NO_DIR_CHECK='TRUE';
      ALLOW_CONNECT='TRUE';
    'TH':
      PIN_NUMBER='(TH)';
      PINUSE='POWER';
      NO_LOAD_CHECK='Both';
      NO_IO_CHECK='Both';
      NO_ASSERT_CHECK='TRUE';
      NO_DIR_CHECK='TRUE';
      ALLOW_CONNECT='TRUE';
    'OVCUR1#||SMC':
      PIN_NUMBER='(25)';
      INPUT_LOAD='(-0.01,0.01)';
      PINUSE='IN';
    'OVCUR2#||SMD':
      PIN_NUMBER='(24)';
      BIDIRECTIONAL='TRUE';
      INPUT_LOAD='(-0.01,0.01)';
      OUTPUT_LOAD='(1.0,-1.0)';
      PINUSE='BI';
    'OVCUR3#':
      PIN_NUMBER='(20)';
      INPUT_LOAD='(-0.01,0.01)';
      PINUSE='IN';
    'OVCUR4#':
      PIN_NUMBER='(19)';
      INPUT_LOAD='(-0.01,0.01)';
      PINUSE='IN';
    'RESET#':
      PIN_NUMBER='(17)';
      INPUT_LOAD='(-0.01,0.01)';
      PINUSE='IN';
    'PGANG':
      PIN_NUMBER='(23)';
      BIDIRECTIONAL='TRUE';
      INPUT_LOAD='(-0.01,0.01)';
      OUTPUT_LOAD='(1.0,-1.0)';
      PINUSE='BI';
    'PSELF':
      PIN_NUMBER='(22)';
      INPUT_LOAD='(-0.01,0.01)';
      PINUSE='IN';
    'RREF':
      PIN_NUMBER='(8)';
      INPUT_LOAD='(-0.01,0.01)';
      PINUSE='IN';
    'DP0':
      PIN_NUMBER='(2)';
      BIDIRECTIONAL='TRUE';
      INPUT_LOAD='(-0.01,0.01)';
      OUTPUT_LOAD='(1.0,-1.0)';
      PINUSE='BI';
    'DM0':
      PIN_NUMBER='(1)';
      BIDIRECTIONAL='TRUE';
      INPUT_LOAD='(-0.01,0.01)';
      OUTPUT_LOAD='(1.0,-1.0)';
      PINUSE='BI';
    'DP1':
      PIN_NUMBER='(4)';
      BIDIRECTIONAL='TRUE';
      INPUT_LOAD='(-0.01,0.01)';
      OUTPUT_LOAD='(1.0,-1.0)';
      PINUSE='BI';
    'DM1':
      PIN_NUMBER='(3)';
      BIDIRECTIONAL='TRUE';
      INPUT_LOAD='(-0.01,0.01)';
      OUTPUT_LOAD='(1.0,-1.0)';
      PINUSE='BI';
    'DP2':
      PIN_NUMBER='(7)';
      BIDIRECTIONAL='TRUE';
      INPUT_LOAD='(-0.01,0.01)';
      OUTPUT_LOAD='(1.0,-1.0)';
      PINUSE='BI';
    'DM2':
      PIN_NUMBER='(6)';
      BIDIRECTIONAL='TRUE';
      INPUT_LOAD='(-0.01,0.01)';
      OUTPUT_LOAD='(1.0,-1.0)';
      PINUSE='BI';
    'DP3':
      PIN_NUMBER='(13)';
      BIDIRECTIONAL='TRUE';
      INPUT_LOAD='(-0.01,0.01)';
      OUTPUT_LOAD='(1.0,-1.0)';
      PINUSE='BI';
    'DM3':
      PIN_NUMBER='(12)';
      BIDIRECTIONAL='TRUE';
      INPUT_LOAD='(-0.01,0.01)';
      OUTPUT_LOAD='(1.0,-1.0)';
      PINUSE='BI';
    'DP4':
      PIN_NUMBER='(16)';
      BIDIRECTIONAL='TRUE';
      INPUT_LOAD='(-0.01,0.01)';
      OUTPUT_LOAD='(1.0,-1.0)';
      PINUSE='BI';
    'DM4':
      PIN_NUMBER='(15)';
      BIDIRECTIONAL='TRUE';
      INPUT_LOAD='(-0.01,0.01)';
      OUTPUT_LOAD='(1.0,-1.0)';
      PINUSE='BI';
  end_pin;
  body
      PART_NAME='GL852GOHY60';
      BODY_NAME='GL852GOHY60';
      PHYS_DES_PREFIX='U';
      CLASS='IC';
      STANDARD='';
      LIFECYCLE='';
      PART_NUMBER='AL000852001';
      JEDEC_TYPE='QFN28_THXL';
      DESCRIPTION='IC CTRL(28P) GL852G-OHY60(QFN)';
      MANUFTR='GSL';
      MANUF_PN='GL852G-OHY60';
      RD_CMPLS_LVL='EP(V1)';
      CMPLS_LVL='EP(V1)';
      FROM_PJ='T6UA-CART';
      DIP_SMD='';
      DATA='GSL_GL852G-OHY60.pdf';
      EE_CHECK_LIST='';
      FP_ECN='GL852G-OHY60.msg';
      PSL='';
      CREATOR='';
      STATUS='';
      MSD='';
      ESD_CDM='';
      ESD_HBM='';
      ESD_MM='';
      PIN_LENGTH_SHORT_PIN='0 MILS';
      PIN_LENGTH_LONG_PIN='0 MILS';
      CREATEDAY='20210927';
      PARENT_PART_TYPE='GL852GOHY60';
      PARENT_PPT='GL852GOHY60';
      PARENT_PPT_PART='GL852GOHY60-GL852G-OHY60,SMLF,IC,AL000852001';
  end_body;
end_primitive;
primitive 'GND_HOLE_TH-EMPTY,GND_HOLE140';
  pin
    'GND3':
      PIN_NUMBER='(3)';
      PINUSE='POWER';
    'GND2':
      PIN_NUMBER='(2)';
      PINUSE='POWER';
    'GND9':
      PIN_NUMBER='(9)';
      PINUSE='POWER';
    'GND8':
      PIN_NUMBER='(8)';
      PINUSE='POWER';
    'GND7':
      PIN_NUMBER='(7)';
      PINUSE='POWER';
    'GND6':
      PIN_NUMBER='(6)';
      PINUSE='POWER';
    'GND5':
      PIN_NUMBER='(5)';
      PINUSE='POWER';
    'GND4':
      PIN_NUMBER='(4)';
      PINUSE='POWER';
  end_pin;
  body
      NC_PINS='(1)';
      CLASS='IO';
      PART_NAME='GND_HOLE';
      PHYS_DES_PREFIX='H';
      STANDARD='';
      LIFECYCLE='';
      PART_NUMBER='GND_HOLE140';
      JEDEC_TYPE='GND_C10D5-5B10';
      DESCRIPTION='GNDHOLE_8PIN_C10D5-5B10';
      COMPONENT_TYPE='';
      LEAD_LENGTH='';
      DFM_EXCLUSION='';
      PARENT_PART_TYPE='GND_HOLE';
      PARENT_PPT='GND_HOLE';
      PARENT_PPT_PART='GND_HOLE_TH-EMPTY,GND_HOLE140';
  end_body;
end_primitive;
primitive 'GND_HOLE_TH-EMPTY,GND_HOLE514';
  pin
    'GND3':
      PIN_NUMBER='(3)';
      PINUSE='POWER';
    'GND2':
      PIN_NUMBER='(2)';
      PINUSE='POWER';
    'GND9':
      PIN_NUMBER='(9)';
      PINUSE='POWER';
    'GND8':
      PIN_NUMBER='(8)';
      PINUSE='POWER';
    'GND7':
      PIN_NUMBER='(7)';
      PINUSE='POWER';
    'GND6':
      PIN_NUMBER='(6)';
      PINUSE='POWER';
    'GND5':
      PIN_NUMBER='(5)';
      PINUSE='POWER';
    'GND4':
      PIN_NUMBER='(4)';
      PINUSE='POWER';
  end_pin;
  body
      NC_PINS='(1)';
      CLASS='IO';
      PART_NAME='GND_HOLE';
      PHYS_DES_PREFIX='H';
      STANDARD='';
      LIFECYCLE='';
      PART_NUMBER='GND_HOLE514';
      JEDEC_TYPE='GND_C10D6-5B10_NPM_RB_NSP';
      DESCRIPTION='GND_C10D6-5B10_NPM_RB_NSP';
      COMPONENT_TYPE='';
      LEAD_LENGTH='';
      DFM_EXCLUSION='';
      PARENT_PART_TYPE='GND_HOLE';
      PARENT_PPT='GND_HOLE';
      PARENT_PPT_PART='GND_HOLE_TH-EMPTY,GND_HOLE514';
  end_body;
end_primitive;
primitive 'GND_HOLE_TH-EMPTY,TMP-QGND_HOLE12';
  pin
    'GND3':
      PIN_NUMBER='(3)';
      PINUSE='POWER';
    'GND2':
      PIN_NUMBER='(2)';
      PINUSE='POWER';
    'GND9':
      PIN_NUMBER='(9)';
      PINUSE='POWER';
    'GND8':
      PIN_NUMBER='(8)';
      PINUSE='POWER';
    'GND7':
      PIN_NUMBER='(7)';
      PINUSE='POWER';
    'GND6':
      PIN_NUMBER='(6)';
      PINUSE='POWER';
    'GND5':
      PIN_NUMBER='(5)';
      PINUSE='POWER';
    'GND4':
      PIN_NUMBER='(4)';
      PINUSE='POWER';
  end_pin;
  body
      NC_PINS='(1)';
      CLASS='IO';
      PART_NAME='GND_HOLE';
      PHYS_DES_PREFIX='H';
      STANDARD='';
      LIFECYCLE='';
      PART_NUMBER='TMP-QGND_HOLE12';
      JEDEC_TYPE='GND_C8D4B8';
      DESCRIPTION='GND_C8D4B8';
      COMPONENT_TYPE='';
      LEAD_LENGTH='';
      DFM_EXCLUSION='';
      PARENT_PART_TYPE='GND_HOLE';
      PARENT_PPT='GND_HOLE';
      PARENT_PPT_PART='GND_HOLE_TH-EMPTY,TMP-QGND_HOLE12';
  end_body;
end_primitive;
primitive 'HOLE_TH-EMPTY,DUMMY50';
  pin
    '1':
      PIN_NUMBER='(1)';
      INPUT_LOAD='(-0.01,0.01)';
      OUTPUT_LOAD='(1.0,-1.0)';
      BIDIRECTIONAL='TRUE';
      PINUSE='BI';
  end_pin;
  body
      CLASS='IO';
      PART_NAME='HOLE';
      PHYS_DES_PREFIX='H';
      STANDARD='';
      LIFECYCLE='';
      PART_NUMBER='DUMMY50';
      JEDEC_TYPE='HOLE_TOOLINGD125N_T2-0';
      DESCRIPTION='HOLE_TOOLINGD125N_T2-0';
      COMPONENT_TYPE='';
      LEAD_LENGTH='';
      DFM_EXCLUSION='';
      PARENT_PART_TYPE='HOLE';
      PARENT_PPT='HOLE';
      PARENT_PPT_PART='HOLE_TH-EMPTY,DUMMY50';
  end_body;
end_primitive;
primitive 'HOLE_TH-EMPTY,HOLE1187';
  pin
    '1':
      PIN_NUMBER='(1)';
      INPUT_LOAD='(-0.01,0.01)';
      OUTPUT_LOAD='(1.0,-1.0)';
      BIDIRECTIONAL='TRUE';
      PINUSE='BI';
  end_pin;
  body
      CLASS='IO';
      PART_NAME='HOLE';
      PHYS_DES_PREFIX='H';
      STANDARD='';
      LIFECYCLE='';
      PART_NUMBER='HOLE1187';
      JEDEC_TYPE='HOLE_R4-2X5D2B4_IX0-1T_NPM_RB';
      DESCRIPTION='HOLE_R4-2X5D2B4_IX0-1T_NPM_RB';
      COMPONENT_TYPE='';
      LEAD_LENGTH='';
      DFM_EXCLUSION='';
      PARENT_PART_TYPE='HOLE';
      PARENT_PPT='HOLE';
      PARENT_PPT_PART='HOLE_TH-EMPTY,HOLE1187';
  end_body;
end_primitive;
primitive 'HOLE_TH-EMPTY,HOLE1195';
  pin
    '1':
      PIN_NUMBER='(1)';
      INPUT_LOAD='(-0.01,0.01)';
      OUTPUT_LOAD='(1.0,-1.0)';
      BIDIRECTIONAL='TRUE';
      PINUSE='BI';
  end_pin;
  body
      CLASS='IO';
      PART_NAME='HOLE';
      PHYS_DES_PREFIX='H';
      STANDARD='';
      LIFECYCLE='';
      PART_NUMBER='HOLE1195';
      JEDEC_TYPE='HOLE_C8D4-2B8_NPB';
      DESCRIPTION='HOLE_C8D4-2B8_NPB';
      COMPONENT_TYPE='';
      LEAD_LENGTH='';
      DFM_EXCLUSION='';
      PARENT_PART_TYPE='HOLE';
      PARENT_PPT='HOLE';
      PARENT_PPT_PART='HOLE_TH-EMPTY,HOLE1195';
  end_body;
end_primitive;
primitive 'HOLE_TH-EMPTY,HOLE1226';
  pin
    '1':
      PIN_NUMBER='(1)';
      INPUT_LOAD='(-0.01,0.01)';
      OUTPUT_LOAD='(1.0,-1.0)';
      BIDIRECTIONAL='TRUE';
      PINUSE='BI';
  end_pin;
  body
      CLASS='IO';
      PART_NAME='HOLE';
      PHYS_DES_PREFIX='H';
      STANDARD='';
      LIFECYCLE='';
      PART_NUMBER='HOLE1226';
      JEDEC_TYPE='HOLE_C6-2D3-73B6-2I5-53_RO6-53_NPB';
      DESCRIPTION='HOLE_C6-2D3-73B6-2I5-53_RO6-53_NPB';
      COMPONENT_TYPE='';
      LEAD_LENGTH='';
      DFM_EXCLUSION='';
      PARENT_PART_TYPE='HOLE';
      PARENT_PPT='HOLE';
      PARENT_PPT_PART='HOLE_TH-EMPTY,HOLE1226';
  end_body;
end_primitive;
primitive 'HOLE_TH-EMPTY,HOLE1247';
  pin
    '1':
      PIN_NUMBER='(1)';
      INPUT_LOAD='(-0.01,0.01)';
      OUTPUT_LOAD='(1.0,-1.0)';
      BIDIRECTIONAL='TRUE';
      PINUSE='BI';
  end_pin;
  body
      CLASS='IO';
      PART_NAME='HOLE';
      PHYS_DES_PREFIX='H';
      STANDARD='';
      LIFECYCLE='';
      PART_NUMBER='HOLE1247';
      JEDEC_TYPE='H_OB6-4X8OBD3-2X4-8B6-4X8N_RO6X7-6_NPM';
      DESCRIPTION='HOLE_OB6-4X8OBD3-2X4-8B6-4X8N_RO6X7-6_NPM';
      COMPONENT_TYPE='';
      LEAD_LENGTH='';
      DFM_EXCLUSION='';
      PARENT_PART_TYPE='HOLE';
      PARENT_PPT='HOLE';
      PARENT_PPT_PART='HOLE_TH-EMPTY,HOLE1247';
  end_body;
end_primitive;
primitive 'HOLE_TH-EMPTY,HOLE1248';
  pin
    '1':
      PIN_NUMBER='(1)';
      INPUT_LOAD='(-0.01,0.01)';
      OUTPUT_LOAD='(1.0,-1.0)';
      BIDIRECTIONAL='TRUE';
      PINUSE='BI';
  end_pin;
  body
      CLASS='IO';
      PART_NAME='HOLE';
      PHYS_DES_PREFIX='H';
      STANDARD='';
      LIFECYCLE='';
      PART_NUMBER='HOLE1248';
      JEDEC_TYPE='HOLE_C4-5D3-8B8I5-6_RO6-6_NPT_RB';
      DESCRIPTION='HOLE_C4-5D3-8B8I5-6_RO6-6_NPT_RB';
      COMPONENT_TYPE='';
      LEAD_LENGTH='';
      DFM_EXCLUSION='';
      PARENT_PART_TYPE='HOLE';
      PARENT_PPT='HOLE';
      PARENT_PPT_PART='HOLE_TH-EMPTY,HOLE1248';
  end_body;
end_primitive;
primitive 'HOLE_TH-EMPTY,HOLE372';
  pin
    '1':
      PIN_NUMBER='(1)';
      INPUT_LOAD='(-0.01,0.01)';
      OUTPUT_LOAD='(1.0,-1.0)';
      BIDIRECTIONAL='TRUE';
      PINUSE='BI';
  end_pin;
  body
      CLASS='IO';
      PART_NAME='HOLE';
      PHYS_DES_PREFIX='H';
      STANDARD='';
      LIFECYCLE='';
      PART_NUMBER='HOLE372';
      JEDEC_TYPE='HOLE_C5D3-1N';
      DESCRIPTION='HOLE_C5D3-1N';
      COMPONENT_TYPE='';
      LEAD_LENGTH='';
      DFM_EXCLUSION='';
      PARENT_PART_TYPE='HOLE';
      PARENT_PPT='HOLE';
      PARENT_PPT_PART='HOLE_TH-EMPTY,HOLE372';
  end_body;
end_primitive;
primitive 'HOLE_TH-EMPTY,HOLE596';
  pin
    '1':
      PIN_NUMBER='(1)';
      INPUT_LOAD='(-0.01,0.01)';
      OUTPUT_LOAD='(1.0,-1.0)';
      BIDIRECTIONAL='TRUE';
      PINUSE='BI';
  end_pin;
  body
      CLASS='IO';
      PART_NAME='HOLE';
      PHYS_DES_PREFIX='H';
      STANDARD='';
      LIFECYCLE='';
      PART_NUMBER='HOLE596';
      JEDEC_TYPE='HOLE_C10D5-6B10_NPB';
      DESCRIPTION='HOLE_C10D5-6B10_NPB';
      COMPONENT_TYPE='';
      LEAD_LENGTH='';
      DFM_EXCLUSION='';
      PARENT_PART_TYPE='HOLE';
      PARENT_PPT='HOLE';
      PARENT_PPT_PART='HOLE_TH-EMPTY,HOLE596';
  end_body;
end_primitive;
primitive 'HOLE_TH-EMPTY,TMP-C_T2I_ALEX_1121_1';
  pin
    '1':
      PIN_NUMBER='(1)';
      INPUT_LOAD='(-0.01,0.01)';
      OUTPUT_LOAD='(1.0,-1.0)';
      BIDIRECTIONAL='TRUE';
      PINUSE='BI';
  end_pin;
  body
      CLASS='IO';
      PART_NAME='HOLE';
      PHYS_DES_PREFIX='H';
      STANDARD='';
      LIFECYCLE='';
      PART_NUMBER='TMP-C_T2I_ALEX_1121_1';
      JEDEC_TYPE='HOLE_D10N';
      DESCRIPTION='HOLE_D10N';
      COMPONENT_TYPE='';
      LEAD_LENGTH='';
      DFM_EXCLUSION='';
      PARENT_PART_TYPE='HOLE';
      PARENT_PPT='HOLE';
      PARENT_PPT_PART='HOLE_TH-EMPTY,TMP-C_T2I_ALEX_1121_1';
  end_body;
end_primitive;
primitive 'IML3112Y2B000NCG8-IML3112-Y2B000NCG8,SMLF,EMPTY,ALA';
  pin
    'HSDA':
      PIN_NUMBER='(2)';
      BIDIRECTIONAL='TRUE';
      INPUT_LOAD='(-0.01,0.01)';
      OUTPUT_LOAD='(1.0,-1.0)';
      PINUSE='BI';
    'VDD':
      PIN_NUMBER='(5)';
      PINUSE='POWER';
      NO_LOAD_CHECK='Both';
      NO_IO_CHECK='Both';
      NO_ASSERT_CHECK='TRUE';
      NO_DIR_CHECK='TRUE';
      ALLOW_CONNECT='TRUE';
    'LSCL_1':
      PIN_NUMBER='(6)';
      OUTPUT_LOAD='(1.0,-1.0)';
      PINUSE='OUT';
    'VIO':
      PIN_NUMBER='(7)';
      PINUSE='POWER';
      NO_LOAD_CHECK='Both';
      NO_IO_CHECK='Both';
      NO_ASSERT_CHECK='TRUE';
      NO_DIR_CHECK='TRUE';
      ALLOW_CONNECT='TRUE';
    'LSDA_0':
      PIN_NUMBER='(1)';
      BIDIRECTIONAL='TRUE';
      INPUT_LOAD='(-0.01,0.01)';
      OUTPUT_LOAD='(1.0,-1.0)';
      PINUSE='BI';
    'LSCL_0':
      PIN_NUMBER='(4)';
      OUTPUT_LOAD='(1.0,-1.0)';
      PINUSE='OUT';
    'HSCL':
      PIN_NUMBER='(3)';
      INPUT_LOAD='(-0.01,0.01)';
      PINUSE='IN';
    'LSDA_1||HSA':
      PIN_NUMBER='(8)';
      BIDIRECTIONAL='TRUE';
      INPUT_LOAD='(-0.01,0.01)';
      OUTPUT_LOAD='(1.0,-1.0)';
      PINUSE='BI';
    'TH_GND':
      PIN_NUMBER='(9)';
      PINUSE='POWER';
      NO_LOAD_CHECK='Both';
      NO_IO_CHECK='Both';
      NO_ASSERT_CHECK='TRUE';
      NO_DIR_CHECK='TRUE';
      ALLOW_CONNECT='TRUE';
  end_pin;
  body
      PART_NAME='IML3112Y2B000NCG8';
      BODY_NAME='IML3112Y2B000NCG8';
      PHYS_DES_PREFIX='U';
      CLASS='IC';
      STANDARD='';
      LIFECYCLE='';
      PART_NUMBER='AL003112004';
      JEDEC_TYPE='DFN8_TH_0-5_2X3XC';
      DESCRIPTION='IC(9P)IML3112-Y2B000NCG8(DFN)';
      MANUFTR='RTT';
      MANUF_PN='IML3112-Y2B000NCG8';
      RD_CMPLS_LVL='EP(V1)';
      CMPLS_LVL='';
      FROM_PJ='T6G-JAY';
      DIP_SMD='';
      DATA='RTT_IML3112-Y2B000NCG8.pdf';
      EE_CHECK_LIST='';
      FP_ECN='';
      PSL='';
      CREATOR='';
      STATUS='';
      MSD='';
      ESD_CDM='';
      ESD_HBM='';
      ESD_MM='';
      PIN_LENGTH_SHORT_PIN='0 MILS';
      PIN_LENGTH_LONG_PIN='0 MILS';
      CREATEDAY='20210719';
      PARENT_PART_TYPE='IML3112Y2B000NCG8';
      PARENT_PPT='IML3112Y2B000NCG8';
      PARENT_PPT_PART='IML3112Y2B000NCG8-IML3112-Y2B000NCG8,SMLF,EMPTY,AL003112004';
  end_body;
end_primitive;
primitive 'ISL28022FRZT-ISL28022FRZ-T,SMLF,IC,AL028022003';
  pin
    'VCC':
      PIN_NUMBER='(9)';
      PINUSE='POWER';
      NO_LOAD_CHECK='Both';
      NO_IO_CHECK='Both';
      NO_ASSERT_CHECK='TRUE';
      NO_DIR_CHECK='TRUE';
      ALLOW_CONNECT='TRUE';
    'A1':
      PIN_NUMBER='(1)';
      INPUT_LOAD='(-0.01,0.01)';
      PINUSE='IN';
    'A0':
      PIN_NUMBER='(2)';
      INPUT_LOAD='(-0.01,0.01)';
      PINUSE='IN';
    'SCL|||SMBCLK':
      PIN_NUMBER='(5)';
      INPUT_LOAD='(-0.01,0.01)';
      PINUSE='IN';
    'SDA||SMBDAT':
      PIN_NUMBER='(4)';
      BIDIRECTIONAL='TRUE';
      INPUT_LOAD='(-0.01,0.01)';
      OUTPUT_LOAD='(1.0,-1.0)';
      PINUSE='BI';
    'VBUS':
      PIN_NUMBER='(11)';
      PINUSE='POWER';
      NO_LOAD_CHECK='Both';
      NO_IO_CHECK='Both';
      NO_ASSERT_CHECK='TRUE';
      NO_DIR_CHECK='TRUE';
      ALLOW_CONNECT='TRUE';
    'VINP':
      PIN_NUMBER='(13)';
      INPUT_LOAD='(-0.01,0.01)';
      PINUSE='IN';
    'VINM':
      PIN_NUMBER='(12)';
      INPUT_LOAD='(-0.01,0.01)';
      PINUSE='IN';
    'EXT_CLK||INT':
      PIN_NUMBER='(3)';
      BIDIRECTIONAL='TRUE';
      INPUT_LOAD='(-0.01,0.01)';
      OUTPUT_LOAD='(1.0,-1.0)';
      PINUSE='BI';
    'NC0':
      PIN_NUMBER='(6)';
      OUTPUT_TYPE='(TS,TS)';
      INPUT_LOAD='(-0.01,0.01)';
      OUTPUT_LOAD='(1.0,-1.0)';
      PINUSE='TRI';
    'NC1':
      PIN_NUMBER='(7)';
      OUTPUT_TYPE='(TS,TS)';
      INPUT_LOAD='(-0.01,0.01)';
      OUTPUT_LOAD='(1.0,-1.0)';
      PINUSE='TRI';
    'NC2':
      PIN_NUMBER='(8)';
      OUTPUT_TYPE='(TS,TS)';
      INPUT_LOAD='(-0.01,0.01)';
      OUTPUT_LOAD='(1.0,-1.0)';
      PINUSE='TRI';
    'NC3':
      PIN_NUMBER='(14)';
      OUTPUT_TYPE='(TS,TS)';
      INPUT_LOAD='(-0.01,0.01)';
      OUTPUT_LOAD='(1.0,-1.0)';
      PINUSE='TRI';
    'NC4':
      PIN_NUMBER='(15)';
      OUTPUT_TYPE='(TS,TS)';
      INPUT_LOAD='(-0.01,0.01)';
      OUTPUT_LOAD='(1.0,-1.0)';
      PINUSE='TRI';
    'NC5':
      PIN_NUMBER='(16)';
      OUTPUT_TYPE='(TS,TS)';
      INPUT_LOAD='(-0.01,0.01)';
      OUTPUT_LOAD='(1.0,-1.0)';
      PINUSE='TRI';
    'GND':
      PIN_NUMBER='(10)';
      PINUSE='POWER';
      NO_LOAD_CHECK='Both';
      NO_IO_CHECK='Both';
      NO_ASSERT_CHECK='TRUE';
      NO_DIR_CHECK='TRUE';
      ALLOW_CONNECT='TRUE';
    'TH_GND':
      PIN_NUMBER='(TH)';
      PINUSE='POWER';
      NO_LOAD_CHECK='Both';
      NO_IO_CHECK='Both';
      NO_ASSERT_CHECK='TRUE';
      NO_DIR_CHECK='TRUE';
      ALLOW_CONNECT='TRUE';
  end_pin;
  body
      PART_NAME='ISL28022FRZT';
      BODY_NAME='ISL28022FRZT';
      PHYS_DES_PREFIX='U';
      CLASS='IC';
      STANDARD='';
      LIFECYCLE='';
      PART_NUMBER='AL028022003';
      JEDEC_TYPE='QFN16_TH_0-5_3X3XH';
      DESCRIPTION='IC(16P)ISL28022FRZ-T(QFN)';
      MANUFTR='RTT';
      MANUF_PN='ISL28022FRZ-T';
      RD_CMPLS_LVL='EP(V1)';
      CMPLS_LVL='';
      FROM_PJ='F09C-SEB';
      DIP_SMD='';
      DATA='RTT_ISL28022FRZ-T.pdf';
      EE_CHECK_LIST='';
      FP_ECN='';
      PSL='';
      CREATOR='';
      STATUS='';
      MSD='';
      ESD_CDM='';
      ESD_HBM='';
      ESD_MM='';
      PIN_LENGTH_SHORT_PIN='0 MILS';
      PIN_LENGTH_LONG_PIN='0 MILS';
      CREATEDAY='20210804';
      PARENT_PART_TYPE='ISL28022FRZT';
      PARENT_PPT='ISL28022FRZT';
      PARENT_PPT_PART='ISL28022FRZT-ISL28022FRZ-T,SMLF,IC,AL028022003';
  end_body;
end_primitive;
primitive 'ISL69260IRAZT-ISL69260IRAZ-T,SMLF,IC,AL069260000';
  pin
    'CS7':
      PIN_NUMBER='(23)';
      INPUT_LOAD='(-0.01,0.01)';
      PINUSE='IN';
    'VCC':
      PIN_NUMBER='(39)';
      PINUSE='POWER';
      NO_LOAD_CHECK='Both';
      NO_IO_CHECK='Both';
      NO_ASSERT_CHECK='TRUE';
      NO_DIR_CHECK='TRUE';
      ALLOW_CONNECT='TRUE';
    'EN1':
      PIN_NUMBER='(20)';
      INPUT_LOAD='(-0.01,0.01)';
      PINUSE='IN';
    'PMSCL':
      PIN_NUMBER='(10)';
      INPUT_LOAD='(-0.01,0.01)';
      PINUSE='IN';
    'SVDATA':
      PIN_NUMBER='(18)';
      BIDIRECTIONAL='TRUE';
      INPUT_LOAD='(-0.01,0.01)';
      OUTPUT_LOAD='(1.0,-1.0)';
      PINUSE='BI';
    'CS6':
      PIN_NUMBER='(24)';
      INPUT_LOAD='(-0.01,0.01)';
      PINUSE='IN';
    'NSVALERT#':
      PIN_NUMBER='(19)';
      OUTPUT_LOAD='(1.0,-1.0)';
      PINUSE='OUT';
    'NVRHOT#':
      PIN_NUMBER='(14)';
      OUTPUT_LOAD='(1.0,-1.0)';
      PINUSE='OUT';
    'CS5':
      PIN_NUMBER='(25)';
      INPUT_LOAD='(-0.01,0.01)';
      PINUSE='IN';
    'CS4':
      PIN_NUMBER='(26)';
      INPUT_LOAD='(-0.01,0.01)';
      PINUSE='IN';
    'PG1':
      PIN_NUMBER='(16)';
      OUTPUT_LOAD='(1.0,-1.0)';
      PINUSE='OUT';
    'SVCLK':
      PIN_NUMBER='(17)';
      INPUT_LOAD='(-0.01,0.01)';
      PINUSE='IN';
    'NPMALERT#':
      PIN_NUMBER='(11)';
      OUTPUT_LOAD='(1.0,-1.0)';
      PINUSE='OUT';
    'EN0':
      PIN_NUMBER='(13)';
      INPUT_LOAD='(-0.01,0.01)';
      PINUSE='IN';
    'RGND0':
      PIN_NUMBER='(22)';
      INPUT_LOAD='(-0.01,0.01)';
      PINUSE='IN';
    'PMSDA':
      PIN_NUMBER='(9)';
      BIDIRECTIONAL='TRUE';
      INPUT_LOAD='(-0.01,0.01)';
      OUTPUT_LOAD='(1.0,-1.0)';
      PINUSE='BI';
    'PWM4':
      PIN_NUMBER='(5)';
      OUTPUT_LOAD='(1.0,-1.0)';
      PINUSE='OUT';
    'PWM5':
      PIN_NUMBER='(6)';
      OUTPUT_LOAD='(1.0,-1.0)';
      PINUSE='OUT';
    'VSEN0':
      PIN_NUMBER='(21)';
      INPUT_LOAD='(-0.01,0.01)';
      PINUSE='IN';
    'PWM1':
      PIN_NUMBER='(2)';
      OUTPUT_LOAD='(1.0,-1.0)';
      PINUSE='OUT';
    'PG0':
      PIN_NUMBER='(12)';
      OUTPUT_LOAD='(1.0,-1.0)';
      PINUSE='OUT';
    'PWM6':
      PIN_NUMBER='(7)';
      OUTPUT_LOAD='(1.0,-1.0)';
      PINUSE='OUT';
    'VCCS':
      PIN_NUMBER='(40)';
      PINUSE='POWER';
      NO_LOAD_CHECK='Both';
      NO_IO_CHECK='Both';
      NO_ASSERT_CHECK='TRUE';
      NO_DIR_CHECK='TRUE';
      ALLOW_CONNECT='TRUE';
    'VMON||IINSEN||VSYS||ISYS':
      PIN_NUMBER='(37)';
      INPUT_LOAD='(-0.01,0.01)';
      PINUSE='IN';
    'VINSEN||VSYS':
      PIN_NUMBER='(38)';
      INPUT_LOAD='(-0.01,0.01)';
      PINUSE='IN';
    'TEMP1||ISYS':
      PIN_NUMBER='(36)';
      INPUT_LOAD='(-0.01,0.01)';
      PINUSE='IN';
    'NPINALERT#||NPSYSCRIT#':
      PIN_NUMBER='(15)';
      OUTPUT_LOAD='(1.0,-1.0)';
      PINUSE='OUT';
    'VSEN1':
      PIN_NUMBER='(32)';
      INPUT_LOAD='(-0.01,0.01)';
      PINUSE='IN';
    'RGND1':
      PIN_NUMBER='(31)';
      INPUT_LOAD='(-0.01,0.01)';
      PINUSE='IN';
    'CS1':
      PIN_NUMBER='(29)';
      INPUT_LOAD='(-0.01,0.01)';
      PINUSE='IN';
    'PWM7':
      PIN_NUMBER='(8)';
      OUTPUT_LOAD='(1.0,-1.0)';
      PINUSE='OUT';
    'PWM3':
      PIN_NUMBER='(4)';
      OUTPUT_LOAD='(1.0,-1.0)';
      PINUSE='OUT';
    'CS3':
      PIN_NUMBER='(27)';
      INPUT_LOAD='(-0.01,0.01)';
      PINUSE='IN';
    'PWM2':
      PIN_NUMBER='(3)';
      OUTPUT_LOAD='(1.0,-1.0)';
      PINUSE='OUT';
    'CS2':
      PIN_NUMBER='(28)';
      INPUT_LOAD='(-0.01,0.01)';
      PINUSE='IN';
    'CFP':
      PIN_NUMBER='(33)';
      OUTPUT_LOAD='(1.0,-1.0)';
      PINUSE='OUT';
    'TH_GND':
      PIN_NUMBER='(TH)';
      PINUSE='POWER';
      NO_LOAD_CHECK='Both';
      NO_IO_CHECK='Both';
      NO_ASSERT_CHECK='TRUE';
      NO_DIR_CHECK='TRUE';
      ALLOW_CONNECT='TRUE';
    'ADDR_CFG':
      PIN_NUMBER='(34)';
      INPUT_LOAD='(-0.01,0.01)';
      PINUSE='IN';
    'TEMP0':
      PIN_NUMBER='(35)';
      INPUT_LOAD='(-0.01,0.01)';
      PINUSE='IN';
    'PWM0':
      PIN_NUMBER='(1)';
      OUTPUT_LOAD='(1.0,-1.0)';
      PINUSE='OUT';
    'CS0':
      PIN_NUMBER='(30)';
      INPUT_LOAD='(-0.01,0.01)';
      PINUSE='IN';
  end_pin;
  body
      PART_NAME='ISL69260IRAZT';
      BODY_NAME='ISL69260IRAZT';
      PHYS_DES_PREFIX='U';
      CLASS='IC';
      STANDARD='';
      LIFECYCLE='';
      PART_NUMBER='AL069260000';
      JEDEC_TYPE='QFN40_TH_0-4_5X5XE';
      DESCRIPTION='IC CTRL(40P)ISL69260IRAZ-T(QFN)';
      MANUFTR='RTT';
      MANUF_PN='ISL69260IRAZ-T';
      RD_CMPLS_LVL='EP(V1)';
      CMPLS_LVL='';
      FROM_PJ='S9S-KIMI';
      DIP_SMD='';
      DATA='RTT_ISL69260IRAZ-T.pdf';
      EE_CHECK_LIST='';
      FP_ECN='ISL69260IRAZ-T.msg';
      PSL='';
      CREATOR='';
      STATUS='';
      MSD='NA';
      ESD_CDM='na';
      ESD_HBM='na';
      ESD_MM='na';
      PIN_LENGTH_SHORT_PIN='0 MILS';
      PIN_LENGTH_LONG_PIN='0 MILS';
      CREATEDAY='20200310';
      PARENT_PART_TYPE='ISL69260IRAZT';
      PARENT_PPT='ISL69260IRAZT';
      PARENT_PPT_PART='ISL69260IRAZT-ISL69260IRAZ-T,SMLF,IC,AL069260000';
  end_body;
end_primitive;
primitive 'ISL99390FRZTR5935-ISL99390FRZ-TR5935,SMLF,IC,AL099A';
  pin
    'PWM':
      PIN_NUMBER='(34)';
      INPUT_LOAD='(-0.01,0.01)';
      PINUSE='IN';
    'REFIN':
      PIN_NUMBER='(39)';
      INPUT_LOAD='(-0.01,0.01)';
      PINUSE='IN';
    'VCC':
      PIN_NUMBER='(3)';
      PINUSE='POWER';
      NO_LOAD_CHECK='Both';
      NO_IO_CHECK='Both';
      NO_ASSERT_CHECK='TRUE';
      NO_DIR_CHECK='TRUE';
      ALLOW_CONNECT='TRUE';
    'AGND':
      PIN_NUMBER='(2)';
      PINUSE='POWER';
      NO_LOAD_CHECK='Both';
      NO_IO_CHECK='Both';
      NO_ASSERT_CHECK='TRUE';
      NO_DIR_CHECK='TRUE';
      ALLOW_CONNECT='TRUE';
    'BOOT':
      PIN_NUMBER='(33)';
      PINUSE='POWER';
      NO_LOAD_CHECK='Both';
      NO_IO_CHECK='Both';
      NO_ASSERT_CHECK='TRUE';
      NO_DIR_CHECK='TRUE';
      ALLOW_CONNECT='TRUE';
    'VIN1':
      PIN_NUMBER='(25_29)';
      INPUT_LOAD='(-0.01,0.01)';
      PINUSE='IN';
    'PHASE':
      PIN_NUMBER='(32)';
      PINUSE='POWER';
      NO_LOAD_CHECK='Both';
      NO_IO_CHECK='Both';
      NO_ASSERT_CHECK='TRUE';
      NO_DIR_CHECK='TRUE';
      ALLOW_CONNECT='TRUE';
    'PVCC':
      PIN_NUMBER='(4)';
      PINUSE='POWER';
      NO_LOAD_CHECK='Both';
      NO_IO_CHECK='Both';
      NO_ASSERT_CHECK='TRUE';
      NO_DIR_CHECK='TRUE';
      ALLOW_CONNECT='TRUE';
    'TOUT_FLT':
      PIN_NUMBER='(36)';
      OUTPUT_LOAD='(1.0,-1.0)';
      PINUSE='OUT';
    'IOUT':
      PIN_NUMBER='(38)';
      OUTPUT_LOAD='(1.0,-1.0)';
      PINUSE='OUT';
    'LSET':
      PIN_NUMBER='(37)';
      OUTPUT_LOAD='(1.0,-1.0)';
      PINUSE='OUT';
    'SW':
      PIN_NUMBER='(10_19)';
      OUTPUT_LOAD='(1.0,-1.0)';
      PINUSE='OUT';
    'PGND1':
      PIN_NUMBER='(5)';
      PINUSE='POWER';
      NO_LOAD_CHECK='Both';
      NO_IO_CHECK='Both';
      NO_ASSERT_CHECK='TRUE';
      NO_DIR_CHECK='TRUE';
      ALLOW_CONNECT='TRUE';
    'VIN2':
      PIN_NUMBER='(30)';
      INPUT_LOAD='(-0.01,0.01)';
      PINUSE='IN';
    'VOS':
      PIN_NUMBER='(1)';
      INPUT_LOAD='(-0.01,0.01)';
      PINUSE='IN';
    'PGND3':
      PIN_NUMBER='(40)';
      PINUSE='POWER';
      NO_LOAD_CHECK='Both';
      NO_IO_CHECK='Both';
      NO_ASSERT_CHECK='TRUE';
      NO_DIR_CHECK='TRUE';
      ALLOW_CONNECT='TRUE';
    'EN':
      PIN_NUMBER='(35)';
      INPUT_LOAD='(-0.01,0.01)';
      PINUSE='IN';
    'DNC':
      PIN_NUMBER='(31)';
      OUTPUT_TYPE='(TS,TS)';
      INPUT_LOAD='(-0.01,0.01)';
      OUTPUT_LOAD='(1.0,-1.0)';
      PINUSE='TRI';
    'GL1':
      PIN_NUMBER='(6)';
      OUTPUT_LOAD='(1.0,-1.0)';
      PINUSE='OUT';
    'GL2':
      PIN_NUMBER='(41)';
      OUTPUT_LOAD='(1.0,-1.0)';
      PINUSE='OUT';
    'PGND2':
      PIN_NUMBER='(7_9-20_24)';
      PINUSE='POWER';
      NO_LOAD_CHECK='Both';
      NO_IO_CHECK='Both';
      NO_ASSERT_CHECK='TRUE';
      NO_DIR_CHECK='TRUE';
      ALLOW_CONNECT='TRUE';
  end_pin;
  body
      PART_NAME='ISL99390FRZTR5935';
      BODY_NAME='ISL99390FRZTR5935';
      PHYS_DES_PREFIX='U';
      CLASS='IC';
      STANDARD='';
      LIFECYCLE='';
      PART_NUMBER='AL099390004';
      JEDEC_TYPE='QFN21_6X5XB';
      DESCRIPTION='IC CTRL(41P) ISL99390FRZ-TR5935(QFN)';
      MANUFTR='RTT';
      MANUF_PN='ISL99390FRZ-TR5935';
      RD_CMPLS_LVL='EP(V1)';
      CMPLS_LVL='';
      FROM_PJ='S8A-KENNY';
      DIP_SMD='';
      DATA='RTT_ISL99390FRZ-TR5935.pdf';
      EE_CHECK_LIST='';
      FP_ECN='';
      PSL='';
      CREATOR='';
      STATUS='';
      MSD='NA';
      ESD_CDM='NA';
      ESD_HBM='NA';
      ESD_MM='NA';
      PIN_LENGTH_SHORT_PIN='0 MILS';
      PIN_LENGTH_LONG_PIN='0 MILS';
      CREATEDAY='20200303';
      PARENT_PART_TYPE='ISL99390FRZTR5935';
      PARENT_PPT='ISL99390FRZTR5935';
      PARENT_PPT_PART='ISL99390FRZTR5935-ISL99390FRZ-TR5935,SMLF,IC,AL099390004';
  end_body;
end_primitive;
primitive 'LCMXO3LF9400C5BG484C-LCMXO3LF-9400C-5BG484C,SMLF,IA';
  pin
    'PL2A':
      PIN_NUMBER='(D3,0,0,0,0,0,0)';
      BIDIRECTIONAL='TRUE';
      INPUT_LOAD='(-0.01,0.01)';
      OUTPUT_LOAD='(1.0,-1.0)';
      PINUSE='BI';
    'PL2B':
      PIN_NUMBER='(D4,0,0,0,0,0,0)';
      BIDIRECTIONAL='TRUE';
      INPUT_LOAD='(-0.01,0.01)';
      OUTPUT_LOAD='(1.0,-1.0)';
      PINUSE='BI';
    'PL2C':
      PIN_NUMBER='(F6,0,0,0,0,0,0)';
      BIDIRECTIONAL='TRUE';
      INPUT_LOAD='(-0.01,0.01)';
      OUTPUT_LOAD='(1.0,-1.0)';
      PINUSE='BI';
    'PL2D':
      PIN_NUMBER='(G7,0,0,0,0,0,0)';
      BIDIRECTIONAL='TRUE';
      INPUT_LOAD='(-0.01,0.01)';
      OUTPUT_LOAD='(1.0,-1.0)';
      PINUSE='BI';
    'PL3A||L_GPLLT_FB':
      PIN_NUMBER='(E4,0,0,0,0,0,0)';
      BIDIRECTIONAL='TRUE';
      INPUT_LOAD='(-0.01,0.01)';
      OUTPUT_LOAD='(1.0,-1.0)';
      PINUSE='BI';
    'PL3B||L_GPLLC_FB':
      PIN_NUMBER='(F5,0,0,0,0,0,0)';
      BIDIRECTIONAL='TRUE';
      INPUT_LOAD='(-0.01,0.01)';
      OUTPUT_LOAD='(1.0,-1.0)';
      PINUSE='BI';
    'PL3C':
      PIN_NUMBER='(G6,0,0,0,0,0,0)';
      BIDIRECTIONAL='TRUE';
      INPUT_LOAD='(-0.01,0.01)';
      OUTPUT_LOAD='(1.0,-1.0)';
      PINUSE='BI';
    'PL3D':
      PIN_NUMBER='(H7,0,0,0,0,0,0)';
      BIDIRECTIONAL='TRUE';
      INPUT_LOAD='(-0.01,0.01)';
      OUTPUT_LOAD='(1.0,-1.0)';
      PINUSE='BI';
    'PL4A||L_GPLLT_IN':
      PIN_NUMBER='(C1,0,0,0,0,0,0)';
      BIDIRECTIONAL='TRUE';
      INPUT_LOAD='(-0.01,0.01)';
      OUTPUT_LOAD='(1.0,-1.0)';
      PINUSE='BI';
    'PL4B||L_GPLLC_IN':
      PIN_NUMBER='(D2,0,0,0,0,0,0)';
      BIDIRECTIONAL='TRUE';
      INPUT_LOAD='(-0.01,0.01)';
      OUTPUT_LOAD='(1.0,-1.0)';
      PINUSE='BI';
    'PL4C':
      PIN_NUMBER='(G5,0,0,0,0,0,0)';
      BIDIRECTIONAL='TRUE';
      INPUT_LOAD='(-0.01,0.01)';
      OUTPUT_LOAD='(1.0,-1.0)';
      PINUSE='BI';
    'PL4D':
      PIN_NUMBER='(H6,0,0,0,0,0,0)';
      BIDIRECTIONAL='TRUE';
      INPUT_LOAD='(-0.01,0.01)';
      OUTPUT_LOAD='(1.0,-1.0)';
      PINUSE='BI';
    'PL5A':
      PIN_NUMBER='(D1,0,0,0,0,0,0)';
      BIDIRECTIONAL='TRUE';
      INPUT_LOAD='(-0.01,0.01)';
      OUTPUT_LOAD='(1.0,-1.0)';
      PINUSE='BI';
    'PL5B':
      PIN_NUMBER='(E2,0,0,0,0,0,0)';
      BIDIRECTIONAL='TRUE';
      INPUT_LOAD='(-0.01,0.01)';
      OUTPUT_LOAD='(1.0,-1.0)';
      PINUSE='BI';
    'PL5C':
      PIN_NUMBER='(E3,0,0,0,0,0,0)';
      BIDIRECTIONAL='TRUE';
      INPUT_LOAD='(-0.01,0.01)';
      OUTPUT_LOAD='(1.0,-1.0)';
      PINUSE='BI';
    'PL5D':
      PIN_NUMBER='(F4,0,0,0,0,0,0)';
      BIDIRECTIONAL='TRUE';
      INPUT_LOAD='(-0.01,0.01)';
      OUTPUT_LOAD='(1.0,-1.0)';
      PINUSE='BI';
    'PL13A':
      PIN_NUMBER='(L7,0,0,0,0,0,0)';
      BIDIRECTIONAL='TRUE';
      INPUT_LOAD='(-0.01,0.01)';
      OUTPUT_LOAD='(1.0,-1.0)';
      PINUSE='BI';
    'PL13B':
      PIN_NUMBER='(K5,0,0,0,0,0,0)';
      BIDIRECTIONAL='TRUE';
      INPUT_LOAD='(-0.01,0.01)';
      OUTPUT_LOAD='(1.0,-1.0)';
      PINUSE='BI';
    'PL13C':
      PIN_NUMBER='(K4,0,0,0,0,0,0)';
      BIDIRECTIONAL='TRUE';
      INPUT_LOAD='(-0.01,0.01)';
      OUTPUT_LOAD='(1.0,-1.0)';
      PINUSE='BI';
    'PL13D':
      PIN_NUMBER='(K3,0,0,0,0,0,0)';
      BIDIRECTIONAL='TRUE';
      INPUT_LOAD='(-0.01,0.01)';
      OUTPUT_LOAD='(1.0,-1.0)';
      PINUSE='BI';
    'PL14A':
      PIN_NUMBER='(K2,0,0,0,0,0,0)';
      BIDIRECTIONAL='TRUE';
      INPUT_LOAD='(-0.01,0.01)';
      OUTPUT_LOAD='(1.0,-1.0)';
      PINUSE='BI';
    'PL14B':
      PIN_NUMBER='(K1,0,0,0,0,0,0)';
      BIDIRECTIONAL='TRUE';
      INPUT_LOAD='(-0.01,0.01)';
      OUTPUT_LOAD='(1.0,-1.0)';
      PINUSE='BI';
    'PL16A||PCLKT4_0':
      PIN_NUMBER='(L1,0,0,0,0,0,0)';
      BIDIRECTIONAL='TRUE';
      INPUT_LOAD='(-0.01,0.01)';
      OUTPUT_LOAD='(1.0,-1.0)';
      PINUSE='BI';
    'PL16B||PCLKC4_0':
      PIN_NUMBER='(M2,0,0,0,0,0,0)';
      BIDIRECTIONAL='TRUE';
      INPUT_LOAD='(-0.01,0.01)';
      OUTPUT_LOAD='(1.0,-1.0)';
      PINUSE='BI';
    'PL20A':
      PIN_NUMBER='(P4,0,0,0,0,0,0)';
      BIDIRECTIONAL='TRUE';
      INPUT_LOAD='(-0.01,0.01)';
      OUTPUT_LOAD='(1.0,-1.0)';
      PINUSE='BI';
    'PL20B':
      PIN_NUMBER='(N5,0,0,0,0,0,0)';
      BIDIRECTIONAL='TRUE';
      INPUT_LOAD='(-0.01,0.01)';
      OUTPUT_LOAD='(1.0,-1.0)';
      PINUSE='BI';
    'PL20C':
      PIN_NUMBER='(N6,0,0,0,0,0,0)';
      BIDIRECTIONAL='TRUE';
      INPUT_LOAD='(-0.01,0.01)';
      OUTPUT_LOAD='(1.0,-1.0)';
      PINUSE='BI';
    'PL20D':
      PIN_NUMBER='(N7,0,0,0,0,0,0)';
      BIDIRECTIONAL='TRUE';
      INPUT_LOAD='(-0.01,0.01)';
      OUTPUT_LOAD='(1.0,-1.0)';
      PINUSE='BI';
    'PL21A':
      PIN_NUMBER='(R2,0,0,0,0,0,0)';
      BIDIRECTIONAL='TRUE';
      INPUT_LOAD='(-0.01,0.01)';
      OUTPUT_LOAD='(1.0,-1.0)';
      PINUSE='BI';
    'PL21B':
      PIN_NUMBER='(T1,0,0,0,0,0,0)';
      BIDIRECTIONAL='TRUE';
      INPUT_LOAD='(-0.01,0.01)';
      OUTPUT_LOAD='(1.0,-1.0)';
      PINUSE='BI';
    'PL21C':
      PIN_NUMBER='(P5,0,0,0,0,0,0)';
      BIDIRECTIONAL='TRUE';
      INPUT_LOAD='(-0.01,0.01)';
      OUTPUT_LOAD='(1.0,-1.0)';
      PINUSE='BI';
    'PL21D':
      PIN_NUMBER='(P6,0,0,0,0,0,0)';
      BIDIRECTIONAL='TRUE';
      INPUT_LOAD='(-0.01,0.01)';
      OUTPUT_LOAD='(1.0,-1.0)';
      PINUSE='BI';
    'PL26C':
      PIN_NUMBER='(T5,0,0,0,0,0,0)';
      BIDIRECTIONAL='TRUE';
      INPUT_LOAD='(-0.01,0.01)';
      OUTPUT_LOAD='(1.0,-1.0)';
      PINUSE='BI';
    'PL26D':
      PIN_NUMBER='(T6,0,0,0,0,0,0)';
      BIDIRECTIONAL='TRUE';
      INPUT_LOAD='(-0.01,0.01)';
      OUTPUT_LOAD='(1.0,-1.0)';
      PINUSE='BI';
    'PL14C':
      PIN_NUMBER='(L6,0,0,0,0,0,0)';
      BIDIRECTIONAL='TRUE';
      INPUT_LOAD='(-0.01,0.01)';
      OUTPUT_LOAD='(1.0,-1.0)';
      PINUSE='BI';
    'PL14D':
      PIN_NUMBER='(L5,0,0,0,0,0,0)';
      BIDIRECTIONAL='TRUE';
      INPUT_LOAD='(-0.01,0.01)';
      OUTPUT_LOAD='(1.0,-1.0)';
      PINUSE='BI';
    'PL16C':
      PIN_NUMBER='(L3,0,0,0,0,0,0)';
      BIDIRECTIONAL='TRUE';
      INPUT_LOAD='(-0.01,0.01)';
      OUTPUT_LOAD='(1.0,-1.0)';
      PINUSE='BI';
    'PL16D':
      PIN_NUMBER='(L4,0,0,0,0,0,0)';
      BIDIRECTIONAL='TRUE';
      INPUT_LOAD='(-0.01,0.01)';
      OUTPUT_LOAD='(1.0,-1.0)';
      PINUSE='BI';
    'PL6C':
      PIN_NUMBER='(G3,0,0,0,0,0,0)';
      BIDIRECTIONAL='TRUE';
      INPUT_LOAD='(-0.01,0.01)';
      OUTPUT_LOAD='(1.0,-1.0)';
      PINUSE='BI';
    'PL6D':
      PIN_NUMBER='(G4,0,0,0,0,0,0)';
      BIDIRECTIONAL='TRUE';
      INPUT_LOAD='(-0.01,0.01)';
      OUTPUT_LOAD='(1.0,-1.0)';
      PINUSE='BI';
    'PL6A':
      PIN_NUMBER='(E1,0,0,0,0,0,0)';
      BIDIRECTIONAL='TRUE';
      INPUT_LOAD='(-0.01,0.01)';
      OUTPUT_LOAD='(1.0,-1.0)';
      PINUSE='BI';
    'PL6B':
      PIN_NUMBER='(F1,0,0,0,0,0,0)';
      BIDIRECTIONAL='TRUE';
      INPUT_LOAD='(-0.01,0.01)';
      OUTPUT_LOAD='(1.0,-1.0)';
      PINUSE='BI';
    'PL25A':
      PIN_NUMBER='(T2,0,0,0,0,0,0)';
      BIDIRECTIONAL='TRUE';
      INPUT_LOAD='(-0.01,0.01)';
      OUTPUT_LOAD='(1.0,-1.0)';
      PINUSE='BI';
    'PL25B':
      PIN_NUMBER='(U1,0,0,0,0,0,0)';
      BIDIRECTIONAL='TRUE';
      INPUT_LOAD='(-0.01,0.01)';
      OUTPUT_LOAD='(1.0,-1.0)';
      PINUSE='BI';
    'PL24A':
      PIN_NUMBER='(R3,0,0,0,0,0,0)';
      BIDIRECTIONAL='TRUE';
      INPUT_LOAD='(-0.01,0.01)';
      OUTPUT_LOAD='(1.0,-1.0)';
      PINUSE='BI';
    'PL24B':
      PIN_NUMBER='(R4,0,0,0,0,0,0)';
      BIDIRECTIONAL='TRUE';
      INPUT_LOAD='(-0.01,0.01)';
      OUTPUT_LOAD='(1.0,-1.0)';
      PINUSE='BI';
    'PL24C':
      PIN_NUMBER='(R5,0,0,0,0,0,0)';
      BIDIRECTIONAL='TRUE';
      INPUT_LOAD='(-0.01,0.01)';
      OUTPUT_LOAD='(1.0,-1.0)';
      PINUSE='BI';
    'PL24D':
      PIN_NUMBER='(P7,0,0,0,0,0,0)';
      BIDIRECTIONAL='TRUE';
      INPUT_LOAD='(-0.01,0.01)';
      OUTPUT_LOAD='(1.0,-1.0)';
      PINUSE='BI';
    'PL25C':
      PIN_NUMBER='(R6,0,0,0,0,0,0)';
      BIDIRECTIONAL='TRUE';
      INPUT_LOAD='(-0.01,0.01)';
      OUTPUT_LOAD='(1.0,-1.0)';
      PINUSE='BI';
    'PL25D':
      PIN_NUMBER='(R7,0,0,0,0,0,0)';
      BIDIRECTIONAL='TRUE';
      INPUT_LOAD='(-0.01,0.01)';
      OUTPUT_LOAD='(1.0,-1.0)';
      PINUSE='BI';
    'PL26A':
      PIN_NUMBER='(T3,0,0,0,0,0,0)';
      BIDIRECTIONAL='TRUE';
      INPUT_LOAD='(-0.01,0.01)';
      OUTPUT_LOAD='(1.0,-1.0)';
      PINUSE='BI';
    'PL26B':
      PIN_NUMBER='(T4,0,0,0,0,0,0)';
      BIDIRECTIONAL='TRUE';
      INPUT_LOAD='(-0.01,0.01)';
      OUTPUT_LOAD='(1.0,-1.0)';
      PINUSE='BI';
    'PL17A':
      PIN_NUMBER='(M1,0,0,0,0,0,0)';
      BIDIRECTIONAL='TRUE';
      INPUT_LOAD='(-0.01,0.01)';
      OUTPUT_LOAD='(1.0,-1.0)';
      PINUSE='BI';
    'PL17B':
      PIN_NUMBER='(N1,0,0,0,0,0,0)';
      BIDIRECTIONAL='TRUE';
      INPUT_LOAD='(-0.01,0.01)';
      OUTPUT_LOAD='(1.0,-1.0)';
      PINUSE='BI';
    'PL17C':
      PIN_NUMBER='(M6,0,0,0,0,0,0)';
      BIDIRECTIONAL='TRUE';
      INPUT_LOAD='(-0.01,0.01)';
      OUTPUT_LOAD='(1.0,-1.0)';
      PINUSE='BI';
    'PL17D':
      PIN_NUMBER='(M5,0,0,0,0,0,0)';
      BIDIRECTIONAL='TRUE';
      INPUT_LOAD='(-0.01,0.01)';
      OUTPUT_LOAD='(1.0,-1.0)';
      PINUSE='BI';
    'PL18A':
      PIN_NUMBER='(N2,0,0,0,0,0,0)';
      BIDIRECTIONAL='TRUE';
      INPUT_LOAD='(-0.01,0.01)';
      OUTPUT_LOAD='(1.0,-1.0)';
      PINUSE='BI';
    'PL18B':
      PIN_NUMBER='(P1,0,0,0,0,0,0)';
      BIDIRECTIONAL='TRUE';
      INPUT_LOAD='(-0.01,0.01)';
      OUTPUT_LOAD='(1.0,-1.0)';
      PINUSE='BI';
    'PL18C':
      PIN_NUMBER='(N3,0,0,0,0,0,0)';
      BIDIRECTIONAL='TRUE';
      INPUT_LOAD='(-0.01,0.01)';
      OUTPUT_LOAD='(1.0,-1.0)';
      PINUSE='BI';
    'PL18D':
      PIN_NUMBER='(N4,0,0,0,0,0,0)';
      BIDIRECTIONAL='TRUE';
      INPUT_LOAD='(-0.01,0.01)';
      OUTPUT_LOAD='(1.0,-1.0)';
      PINUSE='BI';
    'PL19A':
      PIN_NUMBER='(P2,0,0,0,0,0,0)';
      BIDIRECTIONAL='TRUE';
      INPUT_LOAD='(-0.01,0.01)';
      OUTPUT_LOAD='(1.0,-1.0)';
      PINUSE='BI';
    'PL19B':
      PIN_NUMBER='(R1,0,0,0,0,0,0)';
      BIDIRECTIONAL='TRUE';
      INPUT_LOAD='(-0.01,0.01)';
      OUTPUT_LOAD='(1.0,-1.0)';
      PINUSE='BI';
    'PL19C':
      PIN_NUMBER='(P3,0,0,0,0,0,0)';
      BIDIRECTIONAL='TRUE';
      INPUT_LOAD='(-0.01,0.01)';
      OUTPUT_LOAD='(1.0,-1.0)';
      PINUSE='BI';
    'PL19D':
      PIN_NUMBER='(M7,0,0,0,0,0,0)';
      BIDIRECTIONAL='TRUE';
      INPUT_LOAD='(-0.01,0.01)';
      OUTPUT_LOAD='(1.0,-1.0)';
      PINUSE='BI';
    'PL27A||PCLKT3_0':
      PIN_NUMBER='(U2,0,0,0,0,0,0)';
      BIDIRECTIONAL='TRUE';
      INPUT_LOAD='(-0.01,0.01)';
      OUTPUT_LOAD='(1.0,-1.0)';
      PINUSE='BI';
    'PL27B||PCLKC3_0':
      PIN_NUMBER='(V1,0,0,0,0,0,0)';
      BIDIRECTIONAL='TRUE';
      INPUT_LOAD='(-0.01,0.01)';
      OUTPUT_LOAD='(1.0,-1.0)';
      PINUSE='BI';
    'PL27C':
      PIN_NUMBER='(U3,0,0,0,0,0,0)';
      BIDIRECTIONAL='TRUE';
      INPUT_LOAD='(-0.01,0.01)';
      OUTPUT_LOAD='(1.0,-1.0)';
      PINUSE='BI';
    'PL27D':
      PIN_NUMBER='(U4,0,0,0,0,0,0)';
      BIDIRECTIONAL='TRUE';
      INPUT_LOAD='(-0.01,0.01)';
      OUTPUT_LOAD='(1.0,-1.0)';
      PINUSE='BI';
    'PL28A':
      PIN_NUMBER='(W1,0,0,0,0,0,0)';
      BIDIRECTIONAL='TRUE';
      INPUT_LOAD='(-0.01,0.01)';
      OUTPUT_LOAD='(1.0,-1.0)';
      PINUSE='BI';
    'PL28B':
      PIN_NUMBER='(W2,0,0,0,0,0,0)';
      BIDIRECTIONAL='TRUE';
      INPUT_LOAD='(-0.01,0.01)';
      OUTPUT_LOAD='(1.0,-1.0)';
      PINUSE='BI';
    'PL28C':
      PIN_NUMBER='(V4,0,0,0,0,0,0)';
      BIDIRECTIONAL='TRUE';
      INPUT_LOAD='(-0.01,0.01)';
      OUTPUT_LOAD='(1.0,-1.0)';
      PINUSE='BI';
    'PL28D':
      PIN_NUMBER='(U5,0,0,0,0,0,0)';
      BIDIRECTIONAL='TRUE';
      INPUT_LOAD='(-0.01,0.01)';
      OUTPUT_LOAD='(1.0,-1.0)';
      PINUSE='BI';
    'PL29A':
      PIN_NUMBER='(Y1,0,0,0,0,0,0)';
      BIDIRECTIONAL='TRUE';
      INPUT_LOAD='(-0.01,0.01)';
      OUTPUT_LOAD='(1.0,-1.0)';
      PINUSE='BI';
    'PL29B':
      PIN_NUMBER='(AA1,0,0,0,0,0,0)';
      BIDIRECTIONAL='TRUE';
      INPUT_LOAD='(-0.01,0.01)';
      OUTPUT_LOAD='(1.0,-1.0)';
      PINUSE='BI';
    'PL29C':
      PIN_NUMBER='(W3,0,0,0,0,0,0)';
      BIDIRECTIONAL='TRUE';
      INPUT_LOAD='(-0.01,0.01)';
      OUTPUT_LOAD='(1.0,-1.0)';
      PINUSE='BI';
    'PL29D':
      PIN_NUMBER='(Y2,0,0,0,0,0,0)';
      BIDIRECTIONAL='TRUE';
      INPUT_LOAD='(-0.01,0.01)';
      OUTPUT_LOAD='(1.0,-1.0)';
      PINUSE='BI';
    'PL30A':
      PIN_NUMBER='(Y3,0,0,0,0,0,0)';
      BIDIRECTIONAL='TRUE';
      INPUT_LOAD='(-0.01,0.01)';
      OUTPUT_LOAD='(1.0,-1.0)';
      PINUSE='BI';
    'PL30B':
      PIN_NUMBER='(W4,0,0,0,0,0,0)';
      BIDIRECTIONAL='TRUE';
      INPUT_LOAD='(-0.01,0.01)';
      OUTPUT_LOAD='(1.0,-1.0)';
      PINUSE='BI';
    'PL30C':
      PIN_NUMBER='(V5,0,0,0,0,0,0)';
      BIDIRECTIONAL='TRUE';
      INPUT_LOAD='(-0.01,0.01)';
      OUTPUT_LOAD='(1.0,-1.0)';
      PINUSE='BI';
    'PL30D':
      PIN_NUMBER='(T7,0,0,0,0,0,0)';
      BIDIRECTIONAL='TRUE';
      INPUT_LOAD='(-0.01,0.01)';
      OUTPUT_LOAD='(1.0,-1.0)';
      PINUSE='BI';
    'PL7A||PCLKT5_0':
      PIN_NUMBER='(G2,0,0,0,0,0,0)';
      BIDIRECTIONAL='TRUE';
      INPUT_LOAD='(-0.01,0.01)';
      OUTPUT_LOAD='(1.0,-1.0)';
      PINUSE='BI';
    'PL7B||PCLKC5_0':
      PIN_NUMBER='(G1,0,0,0,0,0,0)';
      BIDIRECTIONAL='TRUE';
      INPUT_LOAD='(-0.01,0.01)';
      OUTPUT_LOAD='(1.0,-1.0)';
      PINUSE='BI';
    'PL7C':
      PIN_NUMBER='(H4,0,0,0,0,0,0)';
      BIDIRECTIONAL='TRUE';
      INPUT_LOAD='(-0.01,0.01)';
      OUTPUT_LOAD='(1.0,-1.0)';
      PINUSE='BI';
    'PL7D':
      PIN_NUMBER='(H3,0,0,0,0,0,0)';
      BIDIRECTIONAL='TRUE';
      INPUT_LOAD='(-0.01,0.01)';
      OUTPUT_LOAD='(1.0,-1.0)';
      PINUSE='BI';
    'PL10A':
      PIN_NUMBER='(H2,0,0,0,0,0,0)';
      BIDIRECTIONAL='TRUE';
      INPUT_LOAD='(-0.01,0.01)';
      OUTPUT_LOAD='(1.0,-1.0)';
      PINUSE='BI';
    'PL10B':
      PIN_NUMBER='(H1,0,0,0,0,0,0)';
      BIDIRECTIONAL='TRUE';
      INPUT_LOAD='(-0.01,0.01)';
      OUTPUT_LOAD='(1.0,-1.0)';
      PINUSE='BI';
    'PL10C':
      PIN_NUMBER='(J7,0,0,0,0,0,0)';
      BIDIRECTIONAL='TRUE';
      INPUT_LOAD='(-0.01,0.01)';
      OUTPUT_LOAD='(1.0,-1.0)';
      PINUSE='BI';
    'PL10D':
      PIN_NUMBER='(J6,0,0,0,0,0,0)';
      BIDIRECTIONAL='TRUE';
      INPUT_LOAD='(-0.01,0.01)';
      OUTPUT_LOAD='(1.0,-1.0)';
      PINUSE='BI';
    'PL11A':
      PIN_NUMBER='(H5,0,0,0,0,0,0)';
      BIDIRECTIONAL='TRUE';
      INPUT_LOAD='(-0.01,0.01)';
      OUTPUT_LOAD='(1.0,-1.0)';
      PINUSE='BI';
    'PL11B':
      PIN_NUMBER='(J5,0,0,0,0,0,0)';
      BIDIRECTIONAL='TRUE';
      INPUT_LOAD='(-0.01,0.01)';
      OUTPUT_LOAD='(1.0,-1.0)';
      PINUSE='BI';
    'PL11C':
      PIN_NUMBER='(J4,0,0,0,0,0,0)';
      BIDIRECTIONAL='TRUE';
      INPUT_LOAD='(-0.01,0.01)';
      OUTPUT_LOAD='(1.0,-1.0)';
      PINUSE='BI';
    'PL11D':
      PIN_NUMBER='(J3,0,0,0,0,0,0)';
      BIDIRECTIONAL='TRUE';
      INPUT_LOAD='(-0.01,0.01)';
      OUTPUT_LOAD='(1.0,-1.0)';
      PINUSE='BI';
    'PL12A':
      PIN_NUMBER='(J2,0,0,0,0,0,0)';
      BIDIRECTIONAL='TRUE';
      INPUT_LOAD='(-0.01,0.01)';
      OUTPUT_LOAD='(1.0,-1.0)';
      PINUSE='BI';
    'PL12B':
      PIN_NUMBER='(J1,0,0,0,0,0,0)';
      BIDIRECTIONAL='TRUE';
      INPUT_LOAD='(-0.01,0.01)';
      OUTPUT_LOAD='(1.0,-1.0)';
      PINUSE='BI';
    'PL12C':
      PIN_NUMBER='(K7,0,0,0,0,0,0)';
      BIDIRECTIONAL='TRUE';
      INPUT_LOAD='(-0.01,0.01)';
      OUTPUT_LOAD='(1.0,-1.0)';
      PINUSE='BI';
    'PL12D':
      PIN_NUMBER='(K6,0,0,0,0,0,0)';
      BIDIRECTIONAL='TRUE';
      INPUT_LOAD='(-0.01,0.01)';
      OUTPUT_LOAD='(1.0,-1.0)';
      PINUSE='BI';
    'PB5A':
      PIN_NUMBER='(0,AA2,0,0,0,0,0)';
      BIDIRECTIONAL='TRUE';
      INPUT_LOAD='(-0.01,0.01)';
      OUTPUT_LOAD='(1.0,-1.0)';
      PINUSE='BI';
    'PB5B':
      PIN_NUMBER='(0,AB2,0,0,0,0,0)';
      BIDIRECTIONAL='TRUE';
      INPUT_LOAD='(-0.01,0.01)';
      OUTPUT_LOAD='(1.0,-1.0)';
      PINUSE='BI';
    'PB5C':
      PIN_NUMBER='(0,V6,0,0,0,0,0)';
      BIDIRECTIONAL='TRUE';
      INPUT_LOAD='(-0.01,0.01)';
      OUTPUT_LOAD='(1.0,-1.0)';
      PINUSE='BI';
    'PB5D':
      PIN_NUMBER='(0,U6,0,0,0,0,0)';
      BIDIRECTIONAL='TRUE';
      INPUT_LOAD='(-0.01,0.01)';
      OUTPUT_LOAD='(1.0,-1.0)';
      PINUSE='BI';
    'PB7A||CSSPIN':
      PIN_NUMBER='(0,AA3,0,0,0,0,0)';
      BIDIRECTIONAL='TRUE';
      INPUT_LOAD='(-0.01,0.01)';
      OUTPUT_LOAD='(1.0,-1.0)';
      PINUSE='BI';
    'PB7B':
      PIN_NUMBER='(0,AB3,0,0,0,0,0)';
      BIDIRECTIONAL='TRUE';
      INPUT_LOAD='(-0.01,0.01)';
      OUTPUT_LOAD='(1.0,-1.0)';
      PINUSE='BI';
    'PB7C':
      PIN_NUMBER='(0,Y4,0,0,0,0,0)';
      BIDIRECTIONAL='TRUE';
      INPUT_LOAD='(-0.01,0.01)';
      OUTPUT_LOAD='(1.0,-1.0)';
      PINUSE='BI';
    'PB7D':
      PIN_NUMBER='(0,W5,0,0,0,0,0)';
      BIDIRECTIONAL='TRUE';
      INPUT_LOAD='(-0.01,0.01)';
      OUTPUT_LOAD='(1.0,-1.0)';
      PINUSE='BI';
    'PB8C':
      PIN_NUMBER='(0,U7,0,0,0,0,0)';
      BIDIRECTIONAL='TRUE';
      INPUT_LOAD='(-0.01,0.01)';
      OUTPUT_LOAD='(1.0,-1.0)';
      PINUSE='BI';
    'PB8D':
      PIN_NUMBER='(0,T8,0,0,0,0,0)';
      BIDIRECTIONAL='TRUE';
      INPUT_LOAD='(-0.01,0.01)';
      OUTPUT_LOAD='(1.0,-1.0)';
      PINUSE='BI';
    'PB8A':
      PIN_NUMBER='(0,AA4,0,0,0,0,0)';
      BIDIRECTIONAL='TRUE';
      INPUT_LOAD='(-0.01,0.01)';
      OUTPUT_LOAD='(1.0,-1.0)';
      PINUSE='BI';
    'PB8B':
      PIN_NUMBER='(0,AB4,0,0,0,0,0)';
      BIDIRECTIONAL='TRUE';
      INPUT_LOAD='(-0.01,0.01)';
      OUTPUT_LOAD='(1.0,-1.0)';
      PINUSE='BI';
    'PB10A':
      PIN_NUMBER='(0,AA5,0,0,0,0,0)';
      BIDIRECTIONAL='TRUE';
      INPUT_LOAD='(-0.01,0.01)';
      OUTPUT_LOAD='(1.0,-1.0)';
      PINUSE='BI';
    'PB10B':
      PIN_NUMBER='(0,AB5,0,0,0,0,0)';
      BIDIRECTIONAL='TRUE';
      INPUT_LOAD='(-0.01,0.01)';
      OUTPUT_LOAD='(1.0,-1.0)';
      PINUSE='BI';
    'PB10C':
      PIN_NUMBER='(0,Y5,0,0,0,0,0)';
      BIDIRECTIONAL='TRUE';
      INPUT_LOAD='(-0.01,0.01)';
      OUTPUT_LOAD='(1.0,-1.0)';
      PINUSE='BI';
    'PB10D':
      PIN_NUMBER='(0,Y6,0,0,0,0,0)';
      BIDIRECTIONAL='TRUE';
      INPUT_LOAD='(-0.01,0.01)';
      OUTPUT_LOAD='(1.0,-1.0)';
      PINUSE='BI';
    'PB13C':
      PIN_NUMBER='(0,V8,0,0,0,0,0)';
      BIDIRECTIONAL='TRUE';
      INPUT_LOAD='(-0.01,0.01)';
      OUTPUT_LOAD='(1.0,-1.0)';
      PINUSE='BI';
    'PB13D':
      PIN_NUMBER='(0,U8,0,0,0,0,0)';
      BIDIRECTIONAL='TRUE';
      INPUT_LOAD='(-0.01,0.01)';
      OUTPUT_LOAD='(1.0,-1.0)';
      PINUSE='BI';
    'PB16A||MCLK||CCLK':
      PIN_NUMBER='(0,T9,0,0,0,0,0)';
      BIDIRECTIONAL='TRUE';
      INPUT_LOAD='(-0.01,0.01)';
      OUTPUT_LOAD='(1.0,-1.0)';
      PINUSE='BI';
    'PB16B||SO||SPISO':
      PIN_NUMBER='(0,U9,0,0,0,0,0)';
      BIDIRECTIONAL='TRUE';
      INPUT_LOAD='(-0.01,0.01)';
      OUTPUT_LOAD='(1.0,-1.0)';
      PINUSE='BI';
    'PB18A':
      PIN_NUMBER='(0,AA8,0,0,0,0,0)';
      BIDIRECTIONAL='TRUE';
      INPUT_LOAD='(-0.01,0.01)';
      OUTPUT_LOAD='(1.0,-1.0)';
      PINUSE='BI';
    'PB18B':
      PIN_NUMBER='(0,AB8,0,0,0,0,0)';
      BIDIRECTIONAL='TRUE';
      INPUT_LOAD='(-0.01,0.01)';
      OUTPUT_LOAD='(1.0,-1.0)';
      PINUSE='BI';
    'PB21A':
      PIN_NUMBER='(0,V10,0,0,0,0,0)';
      BIDIRECTIONAL='TRUE';
      INPUT_LOAD='(-0.01,0.01)';
      OUTPUT_LOAD='(1.0,-1.0)';
      PINUSE='BI';
    'PB21B':
      PIN_NUMBER='(0,W10,0,0,0,0,0)';
      BIDIRECTIONAL='TRUE';
      INPUT_LOAD='(-0.01,0.01)';
      OUTPUT_LOAD='(1.0,-1.0)';
      PINUSE='BI';
    'PB22A||PCLKT2_0':
      PIN_NUMBER='(0,AA10,0,0,0,0,0)';
      BIDIRECTIONAL='TRUE';
      INPUT_LOAD='(-0.01,0.01)';
      OUTPUT_LOAD='(1.0,-1.0)';
      PINUSE='BI';
    'PB22B||PCLKC2_0':
      PIN_NUMBER='(0,AB10,0,0,0,0,0)';
      BIDIRECTIONAL='TRUE';
      INPUT_LOAD='(-0.01,0.01)';
      OUTPUT_LOAD='(1.0,-1.0)';
      PINUSE='BI';
    'PB24A':
      PIN_NUMBER='(0,AA11,0,0,0,0,0)';
      BIDIRECTIONAL='TRUE';
      INPUT_LOAD='(-0.01,0.01)';
      OUTPUT_LOAD='(1.0,-1.0)';
      PINUSE='BI';
    'PB24B':
      PIN_NUMBER='(0,AB11,0,0,0,0,0)';
      BIDIRECTIONAL='TRUE';
      INPUT_LOAD='(-0.01,0.01)';
      OUTPUT_LOAD='(1.0,-1.0)';
      PINUSE='BI';
    'PB24C':
      PIN_NUMBER='(0,V11,0,0,0,0,0)';
      BIDIRECTIONAL='TRUE';
      INPUT_LOAD='(-0.01,0.01)';
      OUTPUT_LOAD='(1.0,-1.0)';
      PINUSE='BI';
    'PB24D':
      PIN_NUMBER='(0,Y11,0,0,0,0,0)';
      BIDIRECTIONAL='TRUE';
      INPUT_LOAD='(-0.01,0.01)';
      OUTPUT_LOAD='(1.0,-1.0)';
      PINUSE='BI';
    'PB29A||PCLKT2_1':
      PIN_NUMBER='(0,AB12,0,0,0,0,0)';
      BIDIRECTIONAL='TRUE';
      INPUT_LOAD='(-0.01,0.01)';
      OUTPUT_LOAD='(1.0,-1.0)';
      PINUSE='BI';
    'PB29B||PCLKC2_1':
      PIN_NUMBER='(0,AA12,0,0,0,0,0)';
      BIDIRECTIONAL='TRUE';
      INPUT_LOAD='(-0.01,0.01)';
      OUTPUT_LOAD='(1.0,-1.0)';
      PINUSE='BI';
    'PB30A':
      PIN_NUMBER='(0,AB13,0,0,0,0,0)';
      BIDIRECTIONAL='TRUE';
      INPUT_LOAD='(-0.01,0.01)';
      OUTPUT_LOAD='(1.0,-1.0)';
      PINUSE='BI';
    'PB30B':
      PIN_NUMBER='(0,AA13,0,0,0,0,0)';
      BIDIRECTIONAL='TRUE';
      INPUT_LOAD='(-0.01,0.01)';
      OUTPUT_LOAD='(1.0,-1.0)';
      PINUSE='BI';
    'PB33A':
      PIN_NUMBER='(0,AB14,0,0,0,0,0)';
      BIDIRECTIONAL='TRUE';
      INPUT_LOAD='(-0.01,0.01)';
      OUTPUT_LOAD='(1.0,-1.0)';
      PINUSE='BI';
    'PB33B':
      PIN_NUMBER='(0,AA14,0,0,0,0,0)';
      BIDIRECTIONAL='TRUE';
      INPUT_LOAD='(-0.01,0.01)';
      OUTPUT_LOAD='(1.0,-1.0)';
      PINUSE='BI';
    'PB43A':
      PIN_NUMBER='(0,AB19,0,0,0,0,0)';
      BIDIRECTIONAL='TRUE';
      INPUT_LOAD='(-0.01,0.01)';
      OUTPUT_LOAD='(1.0,-1.0)';
      PINUSE='BI';
    'PB43B':
      PIN_NUMBER='(0,AA19,0,0,0,0,0)';
      BIDIRECTIONAL='TRUE';
      INPUT_LOAD='(-0.01,0.01)';
      OUTPUT_LOAD='(1.0,-1.0)';
      PINUSE='BI';
    'PB44A':
      PIN_NUMBER='(0,AB20,0,0,0,0,0)';
      BIDIRECTIONAL='TRUE';
      INPUT_LOAD='(-0.01,0.01)';
      OUTPUT_LOAD='(1.0,-1.0)';
      PINUSE='BI';
    'PB44B':
      PIN_NUMBER='(0,AA20,0,0,0,0,0)';
      BIDIRECTIONAL='TRUE';
      INPUT_LOAD='(-0.01,0.01)';
      OUTPUT_LOAD='(1.0,-1.0)';
      PINUSE='BI';
    'PB46A||SN':
      PIN_NUMBER='(0,AB21,0,0,0,0,0)';
      BIDIRECTIONAL='TRUE';
      INPUT_LOAD='(-0.01,0.01)';
      OUTPUT_LOAD='(1.0,-1.0)';
      PINUSE='BI';
    'PB46B||SI||SISPI':
      PIN_NUMBER='(0,AA21,0,0,0,0,0)';
      BIDIRECTIONAL='TRUE';
      INPUT_LOAD='(-0.01,0.01)';
      OUTPUT_LOAD='(1.0,-1.0)';
      PINUSE='BI';
    'PB35A':
      PIN_NUMBER='(0,AB15,0,0,0,0,0)';
      BIDIRECTIONAL='TRUE';
      INPUT_LOAD='(-0.01,0.01)';
      OUTPUT_LOAD='(1.0,-1.0)';
      PINUSE='BI';
    'PB35B':
      PIN_NUMBER='(0,AA15,0,0,0,0,0)';
      BIDIRECTIONAL='TRUE';
      INPUT_LOAD='(-0.01,0.01)';
      OUTPUT_LOAD='(1.0,-1.0)';
      PINUSE='BI';
    'PB11A':
      PIN_NUMBER='(0,AA6,0,0,0,0,0)';
      BIDIRECTIONAL='TRUE';
      INPUT_LOAD='(-0.01,0.01)';
      OUTPUT_LOAD='(1.0,-1.0)';
      PINUSE='BI';
    'PB11B':
      PIN_NUMBER='(0,AB6,0,0,0,0,0)';
      BIDIRECTIONAL='TRUE';
      INPUT_LOAD='(-0.01,0.01)';
      OUTPUT_LOAD='(1.0,-1.0)';
      PINUSE='BI';
    'PB11C':
      PIN_NUMBER='(0,W6,0,0,0,0,0)';
      BIDIRECTIONAL='TRUE';
      INPUT_LOAD='(-0.01,0.01)';
      OUTPUT_LOAD='(1.0,-1.0)';
      PINUSE='BI';
    'PB11D':
      PIN_NUMBER='(0,V7,0,0,0,0,0)';
      BIDIRECTIONAL='TRUE';
      INPUT_LOAD='(-0.01,0.01)';
      OUTPUT_LOAD='(1.0,-1.0)';
      PINUSE='BI';
    'PB13A':
      PIN_NUMBER='(0,AA7,0,0,0,0,0)';
      BIDIRECTIONAL='TRUE';
      INPUT_LOAD='(-0.01,0.01)';
      OUTPUT_LOAD='(1.0,-1.0)';
      PINUSE='BI';
    'PB13B':
      PIN_NUMBER='(0,AB7,0,0,0,0,0)';
      BIDIRECTIONAL='TRUE';
      INPUT_LOAD='(-0.01,0.01)';
      OUTPUT_LOAD='(1.0,-1.0)';
      PINUSE='BI';
    'PB16C':
      PIN_NUMBER='(0,V9,0,0,0,0,0)';
      BIDIRECTIONAL='TRUE';
      INPUT_LOAD='(-0.01,0.01)';
      OUTPUT_LOAD='(1.0,-1.0)';
      PINUSE='BI';
    'PB16D':
      PIN_NUMBER='(0,W8,0,0,0,0,0)';
      BIDIRECTIONAL='TRUE';
      INPUT_LOAD='(-0.01,0.01)';
      OUTPUT_LOAD='(1.0,-1.0)';
      PINUSE='BI';
    'PB18C':
      PIN_NUMBER='(0,Y8,0,0,0,0,0)';
      BIDIRECTIONAL='TRUE';
      INPUT_LOAD='(-0.01,0.01)';
      OUTPUT_LOAD='(1.0,-1.0)';
      PINUSE='BI';
    'PB18D':
      PIN_NUMBER='(0,W9,0,0,0,0,0)';
      BIDIRECTIONAL='TRUE';
      INPUT_LOAD='(-0.01,0.01)';
      OUTPUT_LOAD='(1.0,-1.0)';
      PINUSE='BI';
    'PB19A':
      PIN_NUMBER='(0,AA9,0,0,0,0,0)';
      BIDIRECTIONAL='TRUE';
      INPUT_LOAD='(-0.01,0.01)';
      OUTPUT_LOAD='(1.0,-1.0)';
      PINUSE='BI';
    'PB19B':
      PIN_NUMBER='(0,AB9,0,0,0,0,0)';
      BIDIRECTIONAL='TRUE';
      INPUT_LOAD='(-0.01,0.01)';
      OUTPUT_LOAD='(1.0,-1.0)';
      PINUSE='BI';
    'PB19C':
      PIN_NUMBER='(0,T10,0,0,0,0,0)';
      BIDIRECTIONAL='TRUE';
      INPUT_LOAD='(-0.01,0.01)';
      OUTPUT_LOAD='(1.0,-1.0)';
      PINUSE='BI';
    'PB19D':
      PIN_NUMBER='(0,U10,0,0,0,0,0)';
      BIDIRECTIONAL='TRUE';
      INPUT_LOAD='(-0.01,0.01)';
      OUTPUT_LOAD='(1.0,-1.0)';
      PINUSE='BI';
    'PB22C':
      PIN_NUMBER='(0,T11,0,0,0,0,0)';
      BIDIRECTIONAL='TRUE';
      INPUT_LOAD='(-0.01,0.01)';
      OUTPUT_LOAD='(1.0,-1.0)';
      PINUSE='BI';
    'PB22D':
      PIN_NUMBER='(0,U11,0,0,0,0,0)';
      BIDIRECTIONAL='TRUE';
      INPUT_LOAD='(-0.01,0.01)';
      OUTPUT_LOAD='(1.0,-1.0)';
      PINUSE='BI';
    'PB27A':
      PIN_NUMBER='(0,Y12,0,0,0,0,0)';
      BIDIRECTIONAL='TRUE';
      INPUT_LOAD='(-0.01,0.01)';
      OUTPUT_LOAD='(1.0,-1.0)';
      PINUSE='BI';
    'PB27B':
      PIN_NUMBER='(0,T12,0,0,0,0,0)';
      BIDIRECTIONAL='TRUE';
      INPUT_LOAD='(-0.01,0.01)';
      OUTPUT_LOAD='(1.0,-1.0)';
      PINUSE='BI';
    'PB27C':
      PIN_NUMBER='(0,U12,0,0,0,0,0)';
      BIDIRECTIONAL='TRUE';
      INPUT_LOAD='(-0.01,0.01)';
      OUTPUT_LOAD='(1.0,-1.0)';
      PINUSE='BI';
    'PB27D':
      PIN_NUMBER='(0,V12,0,0,0,0,0)';
      BIDIRECTIONAL='TRUE';
      INPUT_LOAD='(-0.01,0.01)';
      OUTPUT_LOAD='(1.0,-1.0)';
      PINUSE='BI';
    'PB29C':
      PIN_NUMBER='(0,V13,0,0,0,0,0)';
      BIDIRECTIONAL='TRUE';
      INPUT_LOAD='(-0.01,0.01)';
      OUTPUT_LOAD='(1.0,-1.0)';
      PINUSE='BI';
    'PB29D':
      PIN_NUMBER='(0,U13,0,0,0,0,0)';
      BIDIRECTIONAL='TRUE';
      INPUT_LOAD='(-0.01,0.01)';
      OUTPUT_LOAD='(1.0,-1.0)';
      PINUSE='BI';
    'PB30C':
      PIN_NUMBER='(0,Y13,0,0,0,0,0)';
      BIDIRECTIONAL='TRUE';
      INPUT_LOAD='(-0.01,0.01)';
      OUTPUT_LOAD='(1.0,-1.0)';
      PINUSE='BI';
    'PB30D':
      PIN_NUMBER='(0,W13,0,0,0,0,0)';
      BIDIRECTIONAL='TRUE';
      INPUT_LOAD='(-0.01,0.01)';
      OUTPUT_LOAD='(1.0,-1.0)';
      PINUSE='BI';
    'PB33C':
      PIN_NUMBER='(0,Y14,0,0,0,0,0)';
      BIDIRECTIONAL='TRUE';
      INPUT_LOAD='(-0.01,0.01)';
      OUTPUT_LOAD='(1.0,-1.0)';
      PINUSE='BI';
    'PB33D':
      PIN_NUMBER='(0,W14,0,0,0,0,0)';
      BIDIRECTIONAL='TRUE';
      INPUT_LOAD='(-0.01,0.01)';
      OUTPUT_LOAD='(1.0,-1.0)';
      PINUSE='BI';
    'PB32A':
      PIN_NUMBER='(0,T13,0,0,0,0,0)';
      BIDIRECTIONAL='TRUE';
      INPUT_LOAD='(-0.01,0.01)';
      OUTPUT_LOAD='(1.0,-1.0)';
      PINUSE='BI';
    'PB32B':
      PIN_NUMBER='(0,T14,0,0,0,0,0)';
      BIDIRECTIONAL='TRUE';
      INPUT_LOAD='(-0.01,0.01)';
      OUTPUT_LOAD='(1.0,-1.0)';
      PINUSE='BI';
    'PB32C':
      PIN_NUMBER='(0,U14,0,0,0,0,0)';
      BIDIRECTIONAL='TRUE';
      INPUT_LOAD='(-0.01,0.01)';
      OUTPUT_LOAD='(1.0,-1.0)';
      PINUSE='BI';
    'PB32D':
      PIN_NUMBER='(0,V14,0,0,0,0,0)';
      BIDIRECTIONAL='TRUE';
      INPUT_LOAD='(-0.01,0.01)';
      OUTPUT_LOAD='(1.0,-1.0)';
      PINUSE='BI';
    'PB35C':
      PIN_NUMBER='(0,Y15,0,0,0,0,0)';
      BIDIRECTIONAL='TRUE';
      INPUT_LOAD='(-0.01,0.01)';
      OUTPUT_LOAD='(1.0,-1.0)';
      PINUSE='BI';
    'PB35D':
      PIN_NUMBER='(0,W15,0,0,0,0,0)';
      BIDIRECTIONAL='TRUE';
      INPUT_LOAD='(-0.01,0.01)';
      OUTPUT_LOAD='(1.0,-1.0)';
      PINUSE='BI';
    'PB38A':
      PIN_NUMBER='(0,AB16,0,0,0,0,0)';
      BIDIRECTIONAL='TRUE';
      INPUT_LOAD='(-0.01,0.01)';
      OUTPUT_LOAD='(1.0,-1.0)';
      PINUSE='BI';
    'PB38B':
      PIN_NUMBER='(0,AA16,0,0,0,0,0)';
      BIDIRECTIONAL='TRUE';
      INPUT_LOAD='(-0.01,0.01)';
      OUTPUT_LOAD='(1.0,-1.0)';
      PINUSE='BI';
    'PB38C':
      PIN_NUMBER='(0,V15,0,0,0,0,0)';
      BIDIRECTIONAL='TRUE';
      INPUT_LOAD='(-0.01,0.01)';
      OUTPUT_LOAD='(1.0,-1.0)';
      PINUSE='BI';
    'PB38D':
      PIN_NUMBER='(0,U15,0,0,0,0,0)';
      BIDIRECTIONAL='TRUE';
      INPUT_LOAD='(-0.01,0.01)';
      OUTPUT_LOAD='(1.0,-1.0)';
      PINUSE='BI';
    'PB40A':
      PIN_NUMBER='(0,AB17,0,0,0,0,0)';
      BIDIRECTIONAL='TRUE';
      INPUT_LOAD='(-0.01,0.01)';
      OUTPUT_LOAD='(1.0,-1.0)';
      PINUSE='BI';
    'PB40B':
      PIN_NUMBER='(0,AA17,0,0,0,0,0)';
      BIDIRECTIONAL='TRUE';
      INPUT_LOAD='(-0.01,0.01)';
      OUTPUT_LOAD='(1.0,-1.0)';
      PINUSE='BI';
    'PB40C':
      PIN_NUMBER='(0,Y17,0,0,0,0,0)';
      BIDIRECTIONAL='TRUE';
      INPUT_LOAD='(-0.01,0.01)';
      OUTPUT_LOAD='(1.0,-1.0)';
      PINUSE='BI';
    'PB40D':
      PIN_NUMBER='(0,V16,0,0,0,0,0)';
      BIDIRECTIONAL='TRUE';
      INPUT_LOAD='(-0.01,0.01)';
      OUTPUT_LOAD='(1.0,-1.0)';
      PINUSE='BI';
    'PB41A':
      PIN_NUMBER='(0,AB18,0,0,0,0,0)';
      BIDIRECTIONAL='TRUE';
      INPUT_LOAD='(-0.01,0.01)';
      OUTPUT_LOAD='(1.0,-1.0)';
      PINUSE='BI';
    'PB41B':
      PIN_NUMBER='(0,AA18,0,0,0,0,0)';
      BIDIRECTIONAL='TRUE';
      INPUT_LOAD='(-0.01,0.01)';
      OUTPUT_LOAD='(1.0,-1.0)';
      PINUSE='BI';
    'PB41C':
      PIN_NUMBER='(0,Y18,0,0,0,0,0)';
      BIDIRECTIONAL='TRUE';
      INPUT_LOAD='(-0.01,0.01)';
      OUTPUT_LOAD='(1.0,-1.0)';
      PINUSE='BI';
    'PB41D':
      PIN_NUMBER='(0,W17,0,0,0,0,0)';
      BIDIRECTIONAL='TRUE';
      INPUT_LOAD='(-0.01,0.01)';
      OUTPUT_LOAD='(1.0,-1.0)';
      PINUSE='BI';
    'PB43C':
      PIN_NUMBER='(0,T15,0,0,0,0,0)';
      BIDIRECTIONAL='TRUE';
      INPUT_LOAD='(-0.01,0.01)';
      OUTPUT_LOAD='(1.0,-1.0)';
      PINUSE='BI';
    'PB43D':
      PIN_NUMBER='(0,U16,0,0,0,0,0)';
      BIDIRECTIONAL='TRUE';
      INPUT_LOAD='(-0.01,0.01)';
      OUTPUT_LOAD='(1.0,-1.0)';
      PINUSE='BI';
    'PB44C':
      PIN_NUMBER='(0,Y19,0,0,0,0,0)';
      BIDIRECTIONAL='TRUE';
      INPUT_LOAD='(-0.01,0.01)';
      OUTPUT_LOAD='(1.0,-1.0)';
      PINUSE='BI';
    'PB44D':
      PIN_NUMBER='(0,W18,0,0,0,0,0)';
      BIDIRECTIONAL='TRUE';
      INPUT_LOAD='(-0.01,0.01)';
      OUTPUT_LOAD='(1.0,-1.0)';
      PINUSE='BI';
    'PB46C':
      PIN_NUMBER='(0,V17,0,0,0,0,0)';
      BIDIRECTIONAL='TRUE';
      INPUT_LOAD='(-0.01,0.01)';
      OUTPUT_LOAD='(1.0,-1.0)';
      PINUSE='BI';
    'PB46D':
      PIN_NUMBER='(0,T16,0,0,0,0,0)';
      BIDIRECTIONAL='TRUE';
      INPUT_LOAD='(-0.01,0.01)';
      OUTPUT_LOAD='(1.0,-1.0)';
      PINUSE='BI';
    'PB21C':
      PIN_NUMBER='(0,Y9,0,0,0,0,0)';
      BIDIRECTIONAL='TRUE';
      INPUT_LOAD='(-0.01,0.01)';
      OUTPUT_LOAD='(1.0,-1.0)';
      PINUSE='BI';
    'PB21D':
      PIN_NUMBER='(0,Y10,0,0,0,0,0)';
      BIDIRECTIONAL='TRUE';
      INPUT_LOAD='(-0.01,0.01)';
      OUTPUT_LOAD='(1.0,-1.0)';
      PINUSE='BI';
    'PT43B||R_GPLLC':
      PIN_NUMBER='(0,0,B21,0,0,0,0)';
      BIDIRECTIONAL='TRUE';
      INPUT_LOAD='(-0.01,0.01)';
      OUTPUT_LOAD='(1.0,-1.0)';
      PINUSE='BI';
    'PT43A||R_GPLLT':
      PIN_NUMBER='(0,0,A20,0,0,0,0)';
      BIDIRECTIONAL='TRUE';
      INPUT_LOAD='(-0.01,0.01)';
      OUTPUT_LOAD='(1.0,-1.0)';
      PINUSE='BI';
    'PT41B':
      PIN_NUMBER='(0,0,B19,0,0,0,0)';
      BIDIRECTIONAL='TRUE';
      INPUT_LOAD='(-0.01,0.01)';
      OUTPUT_LOAD='(1.0,-1.0)';
      PINUSE='BI';
    'PT41A':
      PIN_NUMBER='(0,0,A18,0,0,0,0)';
      BIDIRECTIONAL='TRUE';
      INPUT_LOAD='(-0.01,0.01)';
      OUTPUT_LOAD='(1.0,-1.0)';
      PINUSE='BI';
    'PT31B':
      PIN_NUMBER='(0,0,F14,0,0,0,0)';
      BIDIRECTIONAL='TRUE';
      INPUT_LOAD='(-0.01,0.01)';
      OUTPUT_LOAD='(1.0,-1.0)';
      PINUSE='BI';
    'PT31A':
      PIN_NUMBER='(0,0,G14,0,0,0,0)';
      BIDIRECTIONAL='TRUE';
      INPUT_LOAD='(-0.01,0.01)';
      OUTPUT_LOAD='(1.0,-1.0)';
      PINUSE='BI';
    'PT28B':
      PIN_NUMBER='(0,0,F12,0,0,0,0)';
      BIDIRECTIONAL='TRUE';
      INPUT_LOAD='(-0.01,0.01)';
      OUTPUT_LOAD='(1.0,-1.0)';
      PINUSE='BI';
    'PT28A':
      PIN_NUMBER='(0,0,G12,0,0,0,0)';
      BIDIRECTIONAL='TRUE';
      INPUT_LOAD='(-0.01,0.01)';
      OUTPUT_LOAD='(1.0,-1.0)';
      PINUSE='BI';
    'PT27D||SDA||PCLKC0_0':
      PIN_NUMBER='(0,0,A12,0,0,0,0)';
      BIDIRECTIONAL='TRUE';
      INPUT_LOAD='(-0.01,0.01)';
      OUTPUT_LOAD='(1.0,-1.0)';
      PINUSE='BI';
    'PT27C||SCL||PCLKT0_0':
      PIN_NUMBER='(0,0,B12,0,0,0,0)';
      BIDIRECTIONAL='TRUE';
      INPUT_LOAD='(-0.01,0.01)';
      OUTPUT_LOAD='(1.0,-1.0)';
      PINUSE='BI';
    'PT44B||R_GPLLC':
      PIN_NUMBER='(0,0,B22,0,0,0,0)';
      BIDIRECTIONAL='TRUE';
      INPUT_LOAD='(-0.01,0.01)';
      OUTPUT_LOAD='(1.0,-1.0)';
      PINUSE='BI';
    'PT44A||R_GPLLT':
      PIN_NUMBER='(0,0,A21,0,0,0,0)';
      BIDIRECTIONAL='TRUE';
      INPUT_LOAD='(-0.01,0.01)';
      OUTPUT_LOAD='(1.0,-1.0)';
      PINUSE='BI';
    'PT23B||PCLKC0_1':
      PIN_NUMBER='(0,0,A10,0,0,0,0)';
      BIDIRECTIONAL='TRUE';
      INPUT_LOAD='(-0.01,0.01)';
      OUTPUT_LOAD='(1.0,-1.0)';
      PINUSE='BI';
    'PT23A||PCLKT0_1':
      PIN_NUMBER='(0,0,B10,0,0,0,0)';
      BIDIRECTIONAL='TRUE';
      INPUT_LOAD='(-0.01,0.01)';
      OUTPUT_LOAD='(1.0,-1.0)';
      PINUSE='BI';
    'PT15B':
      PIN_NUMBER='(0,0,D8,0,0,0,0)';
      BIDIRECTIONAL='TRUE';
      INPUT_LOAD='(-0.01,0.01)';
      OUTPUT_LOAD='(1.0,-1.0)';
      PINUSE='BI';
    'PT9D':
      PIN_NUMBER='(0,0,F7,0,0,0,0)';
      BIDIRECTIONAL='TRUE';
      INPUT_LOAD='(-0.01,0.01)';
      OUTPUT_LOAD='(1.0,-1.0)';
      PINUSE='BI';
    'PT9B||L_GPLLC':
      PIN_NUMBER='(0,0,A2,0,0,0,0)';
      BIDIRECTIONAL='TRUE';
      INPUT_LOAD='(-0.01,0.01)';
      OUTPUT_LOAD='(1.0,-1.0)';
      PINUSE='BI';
    'PT9C':
      PIN_NUMBER='(0,0,E6,0,0,0,0)';
      BIDIRECTIONAL='TRUE';
      INPUT_LOAD='(-0.01,0.01)';
      OUTPUT_LOAD='(1.0,-1.0)';
      PINUSE='BI';
    'PT9A||L_GPLLT':
      PIN_NUMBER='(0,0,B1,0,0,0,0)';
      BIDIRECTIONAL='TRUE';
      INPUT_LOAD='(-0.01,0.01)';
      OUTPUT_LOAD='(1.0,-1.0)';
      PINUSE='BI';
    'PT15A':
      PIN_NUMBER='(0,0,C8,0,0,0,0)';
      BIDIRECTIONAL='TRUE';
      INPUT_LOAD='(-0.01,0.01)';
      OUTPUT_LOAD='(1.0,-1.0)';
      PINUSE='BI';
    'PT11A':
      PIN_NUMBER='(0,0,B3,0,0,0,0)';
      BIDIRECTIONAL='TRUE';
      INPUT_LOAD='(-0.01,0.01)';
      OUTPUT_LOAD='(1.0,-1.0)';
      PINUSE='BI';
    'PT11B':
      PIN_NUMBER='(0,0,A4,0,0,0,0)';
      BIDIRECTIONAL='TRUE';
      INPUT_LOAD='(-0.01,0.01)';
      OUTPUT_LOAD='(1.0,-1.0)';
      PINUSE='BI';
    'PT22A':
      PIN_NUMBER='(0,0,F10,0,0,0,0)';
      BIDIRECTIONAL='TRUE';
      INPUT_LOAD='(-0.01,0.01)';
      OUTPUT_LOAD='(1.0,-1.0)';
      PINUSE='BI';
    'PT22B':
      PIN_NUMBER='(0,0,E10,0,0,0,0)';
      BIDIRECTIONAL='TRUE';
      INPUT_LOAD='(-0.01,0.01)';
      OUTPUT_LOAD='(1.0,-1.0)';
      PINUSE='BI';
    'PT11C':
      PIN_NUMBER='(0,0,F8,0,0,0,0)';
      BIDIRECTIONAL='TRUE';
      INPUT_LOAD='(-0.01,0.01)';
      OUTPUT_LOAD='(1.0,-1.0)';
      PINUSE='BI';
    'PT11D':
      PIN_NUMBER='(0,0,G8,0,0,0,0)';
      BIDIRECTIONAL='TRUE';
      INPUT_LOAD='(-0.01,0.01)';
      OUTPUT_LOAD='(1.0,-1.0)';
      PINUSE='BI';
    'PT10A':
      PIN_NUMBER='(0,0,B2,0,0,0,0)';
      BIDIRECTIONAL='TRUE';
      INPUT_LOAD='(-0.01,0.01)';
      OUTPUT_LOAD='(1.0,-1.0)';
      PINUSE='BI';
    'PT10B':
      PIN_NUMBER='(0,0,A3,0,0,0,0)';
      BIDIRECTIONAL='TRUE';
      INPUT_LOAD='(-0.01,0.01)';
      OUTPUT_LOAD='(1.0,-1.0)';
      PINUSE='BI';
    'PT10C':
      PIN_NUMBER='(0,0,C3,0,0,0,0)';
      BIDIRECTIONAL='TRUE';
      INPUT_LOAD='(-0.01,0.01)';
      OUTPUT_LOAD='(1.0,-1.0)';
      PINUSE='BI';
    'PT10D':
      PIN_NUMBER='(0,0,C4,0,0,0,0)';
      BIDIRECTIONAL='TRUE';
      INPUT_LOAD='(-0.01,0.01)';
      OUTPUT_LOAD='(1.0,-1.0)';
      PINUSE='BI';
    'PT12A':
      PIN_NUMBER='(0,0,B4,0,0,0,0)';
      BIDIRECTIONAL='TRUE';
      INPUT_LOAD='(-0.01,0.01)';
      OUTPUT_LOAD='(1.0,-1.0)';
      PINUSE='BI';
    'PT12B':
      PIN_NUMBER='(0,0,A5,0,0,0,0)';
      BIDIRECTIONAL='TRUE';
      INPUT_LOAD='(-0.01,0.01)';
      OUTPUT_LOAD='(1.0,-1.0)';
      PINUSE='BI';
    'PT12C':
      PIN_NUMBER='(0,0,D5,0,0,0,0)';
      BIDIRECTIONAL='TRUE';
      INPUT_LOAD='(-0.01,0.01)';
      OUTPUT_LOAD='(1.0,-1.0)';
      PINUSE='BI';
    'PT12D':
      PIN_NUMBER='(0,0,C5,0,0,0,0)';
      BIDIRECTIONAL='TRUE';
      INPUT_LOAD='(-0.01,0.01)';
      OUTPUT_LOAD='(1.0,-1.0)';
      PINUSE='BI';
    'PT13A':
      PIN_NUMBER='(0,0,B5,0,0,0,0)';
      BIDIRECTIONAL='TRUE';
      INPUT_LOAD='(-0.01,0.01)';
      OUTPUT_LOAD='(1.0,-1.0)';
      PINUSE='BI';
    'PT13B':
      PIN_NUMBER='(0,0,A6,0,0,0,0)';
      BIDIRECTIONAL='TRUE';
      INPUT_LOAD='(-0.01,0.01)';
      OUTPUT_LOAD='(1.0,-1.0)';
      PINUSE='BI';
    'PT13C':
      PIN_NUMBER='(0,0,D6,0,0,0,0)';
      BIDIRECTIONAL='TRUE';
      INPUT_LOAD='(-0.01,0.01)';
      OUTPUT_LOAD='(1.0,-1.0)';
      PINUSE='BI';
    'PT13D':
      PIN_NUMBER='(0,0,E7,0,0,0,0)';
      BIDIRECTIONAL='TRUE';
      INPUT_LOAD='(-0.01,0.01)';
      OUTPUT_LOAD='(1.0,-1.0)';
      PINUSE='BI';
    'PT14A':
      PIN_NUMBER='(0,0,B6,0,0,0,0)';
      BIDIRECTIONAL='TRUE';
      INPUT_LOAD='(-0.01,0.01)';
      OUTPUT_LOAD='(1.0,-1.0)';
      PINUSE='BI';
    'PT14B':
      PIN_NUMBER='(0,0,A7,0,0,0,0)';
      BIDIRECTIONAL='TRUE';
      INPUT_LOAD='(-0.01,0.01)';
      OUTPUT_LOAD='(1.0,-1.0)';
      PINUSE='BI';
    'PT14C':
      PIN_NUMBER='(0,0,C6,0,0,0,0)';
      BIDIRECTIONAL='TRUE';
      INPUT_LOAD='(-0.01,0.01)';
      OUTPUT_LOAD='(1.0,-1.0)';
      PINUSE='BI';
    'PT14D':
      PIN_NUMBER='(0,0,D7,0,0,0,0)';
      BIDIRECTIONAL='TRUE';
      INPUT_LOAD='(-0.01,0.01)';
      OUTPUT_LOAD='(1.0,-1.0)';
      PINUSE='BI';
    'PT20A':
      PIN_NUMBER='(0,0,B8,0,0,0,0)';
      BIDIRECTIONAL='TRUE';
      INPUT_LOAD='(-0.01,0.01)';
      OUTPUT_LOAD='(1.0,-1.0)';
      PINUSE='BI';
    'PT20B':
      PIN_NUMBER='(0,0,A8,0,0,0,0)';
      BIDIRECTIONAL='TRUE';
      INPUT_LOAD='(-0.01,0.01)';
      OUTPUT_LOAD='(1.0,-1.0)';
      PINUSE='BI';
    'PT20C':
      PIN_NUMBER='(0,0,C9,0,0,0,0)';
      BIDIRECTIONAL='TRUE';
      INPUT_LOAD='(-0.01,0.01)';
      OUTPUT_LOAD='(1.0,-1.0)';
      PINUSE='BI';
    'PT20D':
      PIN_NUMBER='(0,0,D9,0,0,0,0)';
      BIDIRECTIONAL='TRUE';
      INPUT_LOAD='(-0.01,0.01)';
      OUTPUT_LOAD='(1.0,-1.0)';
      PINUSE='BI';
    'PT21A':
      PIN_NUMBER='(0,0,B9,0,0,0,0)';
      BIDIRECTIONAL='TRUE';
      INPUT_LOAD='(-0.01,0.01)';
      OUTPUT_LOAD='(1.0,-1.0)';
      PINUSE='BI';
    'PT21B':
      PIN_NUMBER='(0,0,A9,0,0,0,0)';
      BIDIRECTIONAL='TRUE';
      INPUT_LOAD='(-0.01,0.01)';
      OUTPUT_LOAD='(1.0,-1.0)';
      PINUSE='BI';
    'PT21C':
      PIN_NUMBER='(0,0,F9,0,0,0,0)';
      BIDIRECTIONAL='TRUE';
      INPUT_LOAD='(-0.01,0.01)';
      OUTPUT_LOAD='(1.0,-1.0)';
      PINUSE='BI';
    'PT21D':
      PIN_NUMBER='(0,0,G9,0,0,0,0)';
      BIDIRECTIONAL='TRUE';
      INPUT_LOAD='(-0.01,0.01)';
      OUTPUT_LOAD='(1.0,-1.0)';
      PINUSE='BI';
    'PT23C':
      PIN_NUMBER='(0,0,G11,0,0,0,0)';
      BIDIRECTIONAL='TRUE';
      INPUT_LOAD='(-0.01,0.01)';
      OUTPUT_LOAD='(1.0,-1.0)';
      PINUSE='BI';
    'PT23D':
      PIN_NUMBER='(0,0,F11,0,0,0,0)';
      BIDIRECTIONAL='TRUE';
      INPUT_LOAD='(-0.01,0.01)';
      OUTPUT_LOAD='(1.0,-1.0)';
      PINUSE='BI';
    'PT24A':
      PIN_NUMBER='(0,0,B11,0,0,0,0)';
      BIDIRECTIONAL='TRUE';
      INPUT_LOAD='(-0.01,0.01)';
      OUTPUT_LOAD='(1.0,-1.0)';
      PINUSE='BI';
    'PT24B':
      PIN_NUMBER='(0,0,A11,0,0,0,0)';
      BIDIRECTIONAL='TRUE';
      INPUT_LOAD='(-0.01,0.01)';
      OUTPUT_LOAD='(1.0,-1.0)';
      PINUSE='BI';
    'PT24C':
      PIN_NUMBER='(0,0,E11,0,0,0,0)';
      BIDIRECTIONAL='TRUE';
      INPUT_LOAD='(-0.01,0.01)';
      OUTPUT_LOAD='(1.0,-1.0)';
      PINUSE='BI';
    'PT24D':
      PIN_NUMBER='(0,0,D11,0,0,0,0)';
      BIDIRECTIONAL='TRUE';
      INPUT_LOAD='(-0.01,0.01)';
      OUTPUT_LOAD='(1.0,-1.0)';
      PINUSE='BI';
    'PT27A':
      PIN_NUMBER='(0,0,D12,0,0,0,0)';
      BIDIRECTIONAL='TRUE';
      INPUT_LOAD='(-0.01,0.01)';
      OUTPUT_LOAD='(1.0,-1.0)';
      PINUSE='BI';
    'PT27B':
      PIN_NUMBER='(0,0,E12,0,0,0,0)';
      BIDIRECTIONAL='TRUE';
      INPUT_LOAD='(-0.01,0.01)';
      OUTPUT_LOAD='(1.0,-1.0)';
      PINUSE='BI';
    'PT28C':
      PIN_NUMBER='(0,0,E13,0,0,0,0)';
      BIDIRECTIONAL='TRUE';
      INPUT_LOAD='(-0.01,0.01)';
      OUTPUT_LOAD='(1.0,-1.0)';
      PINUSE='BI';
    'PT28D':
      PIN_NUMBER='(0,0,F13,0,0,0,0)';
      BIDIRECTIONAL='TRUE';
      INPUT_LOAD='(-0.01,0.01)';
      OUTPUT_LOAD='(1.0,-1.0)';
      PINUSE='BI';
    'PT29A':
      PIN_NUMBER='(0,0,A13,0,0,0,0)';
      BIDIRECTIONAL='TRUE';
      INPUT_LOAD='(-0.01,0.01)';
      OUTPUT_LOAD='(1.0,-1.0)';
      PINUSE='BI';
    'PT29B':
      PIN_NUMBER='(0,0,B13,0,0,0,0)';
      BIDIRECTIONAL='TRUE';
      INPUT_LOAD='(-0.01,0.01)';
      OUTPUT_LOAD='(1.0,-1.0)';
      PINUSE='BI';
    'PT29C':
      PIN_NUMBER='(0,0,C13,0,0,0,0)';
      BIDIRECTIONAL='TRUE';
      INPUT_LOAD='(-0.01,0.01)';
      OUTPUT_LOAD='(1.0,-1.0)';
      PINUSE='BI';
    'PT29D':
      PIN_NUMBER='(0,0,D13,0,0,0,0)';
      BIDIRECTIONAL='TRUE';
      INPUT_LOAD='(-0.01,0.01)';
      OUTPUT_LOAD='(1.0,-1.0)';
      PINUSE='BI';
    'PT30A':
      PIN_NUMBER='(0,0,A14,0,0,0,0)';
      BIDIRECTIONAL='TRUE';
      INPUT_LOAD='(-0.01,0.01)';
      OUTPUT_LOAD='(1.0,-1.0)';
      PINUSE='BI';
    'PT30B':
      PIN_NUMBER='(0,0,B14,0,0,0,0)';
      BIDIRECTIONAL='TRUE';
      INPUT_LOAD='(-0.01,0.01)';
      OUTPUT_LOAD='(1.0,-1.0)';
      PINUSE='BI';
    'PT30C':
      PIN_NUMBER='(0,0,C14,0,0,0,0)';
      BIDIRECTIONAL='TRUE';
      INPUT_LOAD='(-0.01,0.01)';
      OUTPUT_LOAD='(1.0,-1.0)';
      PINUSE='BI';
    'PT30D':
      PIN_NUMBER='(0,0,D14,0,0,0,0)';
      BIDIRECTIONAL='TRUE';
      INPUT_LOAD='(-0.01,0.01)';
      OUTPUT_LOAD='(1.0,-1.0)';
      PINUSE='BI';
    'PT38A':
      PIN_NUMBER='(0,0,A15,0,0,0,0)';
      BIDIRECTIONAL='TRUE';
      INPUT_LOAD='(-0.01,0.01)';
      OUTPUT_LOAD='(1.0,-1.0)';
      PINUSE='BI';
    'PT38B':
      PIN_NUMBER='(0,0,B15,0,0,0,0)';
      BIDIRECTIONAL='TRUE';
      INPUT_LOAD='(-0.01,0.01)';
      OUTPUT_LOAD='(1.0,-1.0)';
      PINUSE='BI';
    'PT38C':
      PIN_NUMBER='(0,0,C15,0,0,0,0)';
      BIDIRECTIONAL='TRUE';
      INPUT_LOAD='(-0.01,0.01)';
      OUTPUT_LOAD='(1.0,-1.0)';
      PINUSE='BI';
    'PT38D':
      PIN_NUMBER='(0,0,D15,0,0,0,0)';
      BIDIRECTIONAL='TRUE';
      INPUT_LOAD='(-0.01,0.01)';
      OUTPUT_LOAD='(1.0,-1.0)';
      PINUSE='BI';
    'PT39A':
      PIN_NUMBER='(0,0,A16,0,0,0,0)';
      BIDIRECTIONAL='TRUE';
      INPUT_LOAD='(-0.01,0.01)';
      OUTPUT_LOAD='(1.0,-1.0)';
      PINUSE='BI';
    'PT39B':
      PIN_NUMBER='(0,0,B17,0,0,0,0)';
      BIDIRECTIONAL='TRUE';
      INPUT_LOAD='(-0.01,0.01)';
      OUTPUT_LOAD='(1.0,-1.0)';
      PINUSE='BI';
    'PT39C':
      PIN_NUMBER='(0,0,C17,0,0,0,0)';
      BIDIRECTIONAL='TRUE';
      INPUT_LOAD='(-0.01,0.01)';
      OUTPUT_LOAD='(1.0,-1.0)';
      PINUSE='BI';
    'PT39D':
      PIN_NUMBER='(0,0,D16,0,0,0,0)';
      BIDIRECTIONAL='TRUE';
      INPUT_LOAD='(-0.01,0.01)';
      OUTPUT_LOAD='(1.0,-1.0)';
      PINUSE='BI';
    'PT40A':
      PIN_NUMBER='(0,0,A17,0,0,0,0)';
      BIDIRECTIONAL='TRUE';
      INPUT_LOAD='(-0.01,0.01)';
      OUTPUT_LOAD='(1.0,-1.0)';
      PINUSE='BI';
    'PT40B':
      PIN_NUMBER='(0,0,B18,0,0,0,0)';
      BIDIRECTIONAL='TRUE';
      INPUT_LOAD='(-0.01,0.01)';
      OUTPUT_LOAD='(1.0,-1.0)';
      PINUSE='BI';
    'PT40C':
      PIN_NUMBER='(0,0,E16,0,0,0,0)';
      BIDIRECTIONAL='TRUE';
      INPUT_LOAD='(-0.01,0.01)';
      OUTPUT_LOAD='(1.0,-1.0)';
      PINUSE='BI';
    'PT40D':
      PIN_NUMBER='(0,0,D17,0,0,0,0)';
      BIDIRECTIONAL='TRUE';
      INPUT_LOAD='(-0.01,0.01)';
      OUTPUT_LOAD='(1.0,-1.0)';
      PINUSE='BI';
    'PT41C':
      PIN_NUMBER='(0,0,C18,0,0,0,0)';
      BIDIRECTIONAL='TRUE';
      INPUT_LOAD='(-0.01,0.01)';
      OUTPUT_LOAD='(1.0,-1.0)';
      PINUSE='BI';
    'PT41D':
      PIN_NUMBER='(0,0,D18,0,0,0,0)';
      BIDIRECTIONAL='TRUE';
      INPUT_LOAD='(-0.01,0.01)';
      OUTPUT_LOAD='(1.0,-1.0)';
      PINUSE='BI';
    'PT42A':
      PIN_NUMBER='(0,0,A19,0,0,0,0)';
      BIDIRECTIONAL='TRUE';
      INPUT_LOAD='(-0.01,0.01)';
      OUTPUT_LOAD='(1.0,-1.0)';
      PINUSE='BI';
    'PT42B':
      PIN_NUMBER='(0,0,B20,0,0,0,0)';
      BIDIRECTIONAL='TRUE';
      INPUT_LOAD='(-0.01,0.01)';
      OUTPUT_LOAD='(1.0,-1.0)';
      PINUSE='BI';
    'PT42C':
      PIN_NUMBER='(0,0,F15,0,0,0,0)';
      BIDIRECTIONAL='TRUE';
      INPUT_LOAD='(-0.01,0.01)';
      OUTPUT_LOAD='(1.0,-1.0)';
      PINUSE='BI';
    'PT42D':
      PIN_NUMBER='(0,0,G15,0,0,0,0)';
      BIDIRECTIONAL='TRUE';
      INPUT_LOAD='(-0.01,0.01)';
      OUTPUT_LOAD='(1.0,-1.0)';
      PINUSE='BI';
    'PT43C':
      PIN_NUMBER='(0,0,C19,0,0,0,0)';
      BIDIRECTIONAL='TRUE';
      INPUT_LOAD='(-0.01,0.01)';
      OUTPUT_LOAD='(1.0,-1.0)';
      PINUSE='BI';
    'PT43D':
      PIN_NUMBER='(0,0,C20,0,0,0,0)';
      BIDIRECTIONAL='TRUE';
      INPUT_LOAD='(-0.01,0.01)';
      OUTPUT_LOAD='(1.0,-1.0)';
      PINUSE='BI';
    'PT15C||TDO':
      PIN_NUMBER='(0,0,0,E8,0,0,0)';
      BIDIRECTIONAL='TRUE';
      INPUT_LOAD='(-0.01,0.01)';
      OUTPUT_LOAD='(1.0,-1.0)';
      PINUSE='BI';
    'PT15D||TDI':
      PIN_NUMBER='(0,0,0,E9,0,0,0)';
      BIDIRECTIONAL='TRUE';
      INPUT_LOAD='(-0.01,0.01)';
      OUTPUT_LOAD='(1.0,-1.0)';
      PINUSE='BI';
    'PT22C||TCK':
      PIN_NUMBER='(0,0,0,D10,0,0,0)';
      BIDIRECTIONAL='TRUE';
      INPUT_LOAD='(-0.01,0.01)';
      OUTPUT_LOAD='(1.0,-1.0)';
      PINUSE='BI';
    'PT22D||TMS':
      PIN_NUMBER='(0,0,0,C10,0,0,0)';
      BIDIRECTIONAL='TRUE';
      INPUT_LOAD='(-0.01,0.01)';
      OUTPUT_LOAD='(1.0,-1.0)';
      PINUSE='BI';
    'PT31D||PROGRAMN':
      PIN_NUMBER='(0,0,0,E15,0,0,0)';
      BIDIRECTIONAL='TRUE';
      INPUT_LOAD='(-0.01,0.01)';
      OUTPUT_LOAD='(1.0,-1.0)';
      PINUSE='BI';
    'PT44C||INITN':
      PIN_NUMBER='(0,0,0,F16,0,0,0)';
      BIDIRECTIONAL='TRUE';
      INPUT_LOAD='(-0.01,0.01)';
      OUTPUT_LOAD='(1.0,-1.0)';
      PINUSE='BI';
    'PT44D||DONE':
      PIN_NUMBER='(0,0,0,E17,0,0,0)';
      BIDIRECTIONAL='TRUE';
      INPUT_LOAD='(-0.01,0.01)';
      OUTPUT_LOAD='(1.0,-1.0)';
      PINUSE='BI';
    'PT31C||JTAGENB':
      PIN_NUMBER='(0,0,0,E14,0,0,0)';
      BIDIRECTIONAL='TRUE';
      INPUT_LOAD='(-0.01,0.01)';
      OUTPUT_LOAD='(1.0,-1.0)';
      PINUSE='BI';
    'VCC1':
      PIN_NUMBER='(0,0,0,0,K10,0,0)';
      PINUSE='POWER';
      NO_LOAD_CHECK='Both';
      NO_IO_CHECK='Both';
      NO_ASSERT_CHECK='TRUE';
      NO_DIR_CHECK='TRUE';
      ALLOW_CONNECT='TRUE';
    'VCC2':
      PIN_NUMBER='(0,0,0,0,K11,0,0)';
      PINUSE='POWER';
      NO_LOAD_CHECK='Both';
      NO_IO_CHECK='Both';
      NO_ASSERT_CHECK='TRUE';
      NO_DIR_CHECK='TRUE';
      ALLOW_CONNECT='TRUE';
    'VCC3':
      PIN_NUMBER='(0,0,0,0,K12,0,0)';
      PINUSE='POWER';
      NO_LOAD_CHECK='Both';
      NO_IO_CHECK='Both';
      NO_ASSERT_CHECK='TRUE';
      NO_DIR_CHECK='TRUE';
      ALLOW_CONNECT='TRUE';
    'VCC4':
      PIN_NUMBER='(0,0,0,0,K13,0,0)';
      PINUSE='POWER';
      NO_LOAD_CHECK='Both';
      NO_IO_CHECK='Both';
      NO_ASSERT_CHECK='TRUE';
      NO_DIR_CHECK='TRUE';
      ALLOW_CONNECT='TRUE';
    'VCC5':
      PIN_NUMBER='(0,0,0,0,L11,0,0)';
      PINUSE='POWER';
      NO_LOAD_CHECK='Both';
      NO_IO_CHECK='Both';
      NO_ASSERT_CHECK='TRUE';
      NO_DIR_CHECK='TRUE';
      ALLOW_CONNECT='TRUE';
    'VCC6':
      PIN_NUMBER='(0,0,0,0,L12,0,0)';
      PINUSE='POWER';
      NO_LOAD_CHECK='Both';
      NO_IO_CHECK='Both';
      NO_ASSERT_CHECK='TRUE';
      NO_DIR_CHECK='TRUE';
      ALLOW_CONNECT='TRUE';
    'VCC7':
      PIN_NUMBER='(0,0,0,0,M11,0,0)';
      PINUSE='POWER';
      NO_LOAD_CHECK='Both';
      NO_IO_CHECK='Both';
      NO_ASSERT_CHECK='TRUE';
      NO_DIR_CHECK='TRUE';
      ALLOW_CONNECT='TRUE';
    'VCC8':
      PIN_NUMBER='(0,0,0,0,M12,0,0)';
      PINUSE='POWER';
      NO_LOAD_CHECK='Both';
      NO_IO_CHECK='Both';
      NO_ASSERT_CHECK='TRUE';
      NO_DIR_CHECK='TRUE';
      ALLOW_CONNECT='TRUE';
    'VCC9':
      PIN_NUMBER='(0,0,0,0,N10,0,0)';
      PINUSE='POWER';
      NO_LOAD_CHECK='Both';
      NO_IO_CHECK='Both';
      NO_ASSERT_CHECK='TRUE';
      NO_DIR_CHECK='TRUE';
      ALLOW_CONNECT='TRUE';
    'VCC10':
      PIN_NUMBER='(0,0,0,0,N11,0,0)';
      PINUSE='POWER';
      NO_LOAD_CHECK='Both';
      NO_IO_CHECK='Both';
      NO_ASSERT_CHECK='TRUE';
      NO_DIR_CHECK='TRUE';
      ALLOW_CONNECT='TRUE';
    'VCC11':
      PIN_NUMBER='(0,0,0,0,N12,0,0)';
      PINUSE='POWER';
      NO_LOAD_CHECK='Both';
      NO_IO_CHECK='Both';
      NO_ASSERT_CHECK='TRUE';
      NO_DIR_CHECK='TRUE';
      ALLOW_CONNECT='TRUE';
    'VCC12':
      PIN_NUMBER='(0,0,0,0,N13,0,0)';
      PINUSE='POWER';
      NO_LOAD_CHECK='Both';
      NO_IO_CHECK='Both';
      NO_ASSERT_CHECK='TRUE';
      NO_DIR_CHECK='TRUE';
      ALLOW_CONNECT='TRUE';
    'VCCIO5_1':
      PIN_NUMBER='(0,0,0,0,F3,0,0)';
      PINUSE='POWER';
      NO_LOAD_CHECK='Both';
      NO_IO_CHECK='Both';
      NO_ASSERT_CHECK='TRUE';
      NO_DIR_CHECK='TRUE';
      ALLOW_CONNECT='TRUE';
    'VCCIO5_2':
      PIN_NUMBER='(0,0,0,0,J8,0,0)';
      PINUSE='POWER';
      NO_LOAD_CHECK='Both';
      NO_IO_CHECK='Both';
      NO_ASSERT_CHECK='TRUE';
      NO_DIR_CHECK='TRUE';
      ALLOW_CONNECT='TRUE';
    'VCCIO5_3':
      PIN_NUMBER='(0,0,0,0,K8,0,0)';
      PINUSE='POWER';
      NO_LOAD_CHECK='Both';
      NO_IO_CHECK='Both';
      NO_ASSERT_CHECK='TRUE';
      NO_DIR_CHECK='TRUE';
      ALLOW_CONNECT='TRUE';
    'VCCIO4_1':
      PIN_NUMBER='(0,0,0,0,L8,0,0)';
      PINUSE='POWER';
      NO_LOAD_CHECK='Both';
      NO_IO_CHECK='Both';
      NO_ASSERT_CHECK='TRUE';
      NO_DIR_CHECK='TRUE';
      ALLOW_CONNECT='TRUE';
    'VCCIO4_2':
      PIN_NUMBER='(0,0,0,0,M8,0,0)';
      PINUSE='POWER';
      NO_LOAD_CHECK='Both';
      NO_IO_CHECK='Both';
      NO_ASSERT_CHECK='TRUE';
      NO_DIR_CHECK='TRUE';
      ALLOW_CONNECT='TRUE';
    'VCCIO4_3':
      PIN_NUMBER='(0,0,0,0,M3,0,0)';
      PINUSE='POWER';
      NO_LOAD_CHECK='Both';
      NO_IO_CHECK='Both';
      NO_ASSERT_CHECK='TRUE';
      NO_DIR_CHECK='TRUE';
      ALLOW_CONNECT='TRUE';
    'VCCIO3_1':
      PIN_NUMBER='(0,0,0,0,N8,0,0)';
      PINUSE='POWER';
      NO_LOAD_CHECK='Both';
      NO_IO_CHECK='Both';
      NO_ASSERT_CHECK='TRUE';
      NO_DIR_CHECK='TRUE';
      ALLOW_CONNECT='TRUE';
    'VCCIO3_2':
      PIN_NUMBER='(0,0,0,0,P8,0,0)';
      PINUSE='POWER';
      NO_LOAD_CHECK='Both';
      NO_IO_CHECK='Both';
      NO_ASSERT_CHECK='TRUE';
      NO_DIR_CHECK='TRUE';
      ALLOW_CONNECT='TRUE';
    'VCCIO3_3':
      PIN_NUMBER='(0,0,0,0,V3,0,0)';
      PINUSE='POWER';
      NO_LOAD_CHECK='Both';
      NO_IO_CHECK='Both';
      NO_ASSERT_CHECK='TRUE';
      NO_DIR_CHECK='TRUE';
      ALLOW_CONNECT='TRUE';
    'VCCIO2_1':
      PIN_NUMBER='(0,0,0,0,R9,0,0)';
      PINUSE='POWER';
      NO_LOAD_CHECK='Both';
      NO_IO_CHECK='Both';
      NO_ASSERT_CHECK='TRUE';
      NO_DIR_CHECK='TRUE';
      ALLOW_CONNECT='TRUE';
    'VCCIO2_2':
      PIN_NUMBER='(0,0,0,0,R10,0,0)';
      PINUSE='POWER';
      NO_LOAD_CHECK='Both';
      NO_IO_CHECK='Both';
      NO_ASSERT_CHECK='TRUE';
      NO_DIR_CHECK='TRUE';
      ALLOW_CONNECT='TRUE';
    'VCCIO2_3':
      PIN_NUMBER='(0,0,0,0,R11,0,0)';
      PINUSE='POWER';
      NO_LOAD_CHECK='Both';
      NO_IO_CHECK='Both';
      NO_ASSERT_CHECK='TRUE';
      NO_DIR_CHECK='TRUE';
      ALLOW_CONNECT='TRUE';
    'VCCIO2_4':
      PIN_NUMBER='(0,0,0,0,R12,0,0)';
      PINUSE='POWER';
      NO_LOAD_CHECK='Both';
      NO_IO_CHECK='Both';
      NO_ASSERT_CHECK='TRUE';
      NO_DIR_CHECK='TRUE';
      ALLOW_CONNECT='TRUE';
    'VCCIO2_5':
      PIN_NUMBER='(0,0,0,0,R13,0,0)';
      PINUSE='POWER';
      NO_LOAD_CHECK='Both';
      NO_IO_CHECK='Both';
      NO_ASSERT_CHECK='TRUE';
      NO_DIR_CHECK='TRUE';
      ALLOW_CONNECT='TRUE';
    'VCCIO2_6':
      PIN_NUMBER='(0,0,0,0,R14,0,0)';
      PINUSE='POWER';
      NO_LOAD_CHECK='Both';
      NO_IO_CHECK='Both';
      NO_ASSERT_CHECK='TRUE';
      NO_DIR_CHECK='TRUE';
      ALLOW_CONNECT='TRUE';
    'VCCIO2_7':
      PIN_NUMBER='(0,0,0,0,W7,0,0)';
      PINUSE='POWER';
      NO_LOAD_CHECK='Both';
      NO_IO_CHECK='Both';
      NO_ASSERT_CHECK='TRUE';
      NO_DIR_CHECK='TRUE';
      ALLOW_CONNECT='TRUE';
    'VCCIO2_8':
      PIN_NUMBER='(0,0,0,0,W11,0,0)';
      PINUSE='POWER';
      NO_LOAD_CHECK='Both';
      NO_IO_CHECK='Both';
      NO_ASSERT_CHECK='TRUE';
      NO_DIR_CHECK='TRUE';
      ALLOW_CONNECT='TRUE';
    'VCCIO2_9':
      PIN_NUMBER='(0,0,0,0,W16,0,0)';
      PINUSE='POWER';
      NO_LOAD_CHECK='Both';
      NO_IO_CHECK='Both';
      NO_ASSERT_CHECK='TRUE';
      NO_DIR_CHECK='TRUE';
      ALLOW_CONNECT='TRUE';
    'VCCIO1_1':
      PIN_NUMBER='(0,0,0,0,F20,0,0)';
      PINUSE='POWER';
      NO_LOAD_CHECK='Both';
      NO_IO_CHECK='Both';
      NO_ASSERT_CHECK='TRUE';
      NO_DIR_CHECK='TRUE';
      ALLOW_CONNECT='TRUE';
    'VCCIO1_2':
      PIN_NUMBER='(0,0,0,0,J15,0,0)';
      PINUSE='POWER';
      NO_LOAD_CHECK='Both';
      NO_IO_CHECK='Both';
      NO_ASSERT_CHECK='TRUE';
      NO_DIR_CHECK='TRUE';
      ALLOW_CONNECT='TRUE';
    'VCCIO1_3':
      PIN_NUMBER='(0,0,0,0,K15,0,0)';
      PINUSE='POWER';
      NO_LOAD_CHECK='Both';
      NO_IO_CHECK='Both';
      NO_ASSERT_CHECK='TRUE';
      NO_DIR_CHECK='TRUE';
      ALLOW_CONNECT='TRUE';
    'VCCIO1_4':
      PIN_NUMBER='(0,0,0,0,L15,0,0)';
      PINUSE='POWER';
      NO_LOAD_CHECK='Both';
      NO_IO_CHECK='Both';
      NO_ASSERT_CHECK='TRUE';
      NO_DIR_CHECK='TRUE';
      ALLOW_CONNECT='TRUE';
    'VCCIO1_5':
      PIN_NUMBER='(0,0,0,0,M15,0,0)';
      PINUSE='POWER';
      NO_LOAD_CHECK='Both';
      NO_IO_CHECK='Both';
      NO_ASSERT_CHECK='TRUE';
      NO_DIR_CHECK='TRUE';
      ALLOW_CONNECT='TRUE';
    'VCCIO1_6':
      PIN_NUMBER='(0,0,0,0,M18,0,0)';
      PINUSE='POWER';
      NO_LOAD_CHECK='Both';
      NO_IO_CHECK='Both';
      NO_ASSERT_CHECK='TRUE';
      NO_DIR_CHECK='TRUE';
      ALLOW_CONNECT='TRUE';
    'VCCIO1_7':
      PIN_NUMBER='(0,0,0,0,N15,0,0)';
      PINUSE='POWER';
      NO_LOAD_CHECK='Both';
      NO_IO_CHECK='Both';
      NO_ASSERT_CHECK='TRUE';
      NO_DIR_CHECK='TRUE';
      ALLOW_CONNECT='TRUE';
    'VCCIO1_8':
      PIN_NUMBER='(0,0,0,0,P15,0,0)';
      PINUSE='POWER';
      NO_LOAD_CHECK='Both';
      NO_IO_CHECK='Both';
      NO_ASSERT_CHECK='TRUE';
      NO_DIR_CHECK='TRUE';
      ALLOW_CONNECT='TRUE';
    'VCCIO1_9':
      PIN_NUMBER='(0,0,0,0,V20,0,0)';
      PINUSE='POWER';
      NO_LOAD_CHECK='Both';
      NO_IO_CHECK='Both';
      NO_ASSERT_CHECK='TRUE';
      NO_DIR_CHECK='TRUE';
      ALLOW_CONNECT='TRUE';
    'VCCIO0_1':
      PIN_NUMBER='(0,0,0,0,C7,0,0)';
      PINUSE='POWER';
      NO_LOAD_CHECK='Both';
      NO_IO_CHECK='Both';
      NO_ASSERT_CHECK='TRUE';
      NO_DIR_CHECK='TRUE';
      ALLOW_CONNECT='TRUE';
    'VCCIO0_2':
      PIN_NUMBER='(0,0,0,0,C12,0,0)';
      PINUSE='POWER';
      NO_LOAD_CHECK='Both';
      NO_IO_CHECK='Both';
      NO_ASSERT_CHECK='TRUE';
      NO_DIR_CHECK='TRUE';
      ALLOW_CONNECT='TRUE';
    'VCCIO0_3':
      PIN_NUMBER='(0,0,0,0,C16,0,0)';
      PINUSE='POWER';
      NO_LOAD_CHECK='Both';
      NO_IO_CHECK='Both';
      NO_ASSERT_CHECK='TRUE';
      NO_DIR_CHECK='TRUE';
      ALLOW_CONNECT='TRUE';
    'VCCIO0_4':
      PIN_NUMBER='(0,0,0,0,G10,0,0)';
      PINUSE='POWER';
      NO_LOAD_CHECK='Both';
      NO_IO_CHECK='Both';
      NO_ASSERT_CHECK='TRUE';
      NO_DIR_CHECK='TRUE';
      ALLOW_CONNECT='TRUE';
    'VCCIO0_7':
      PIN_NUMBER='(0,0,0,0,H11,0,0)';
      PINUSE='POWER';
      NO_LOAD_CHECK='Both';
      NO_IO_CHECK='Both';
      NO_ASSERT_CHECK='TRUE';
      NO_DIR_CHECK='TRUE';
      ALLOW_CONNECT='TRUE';
    'VCCIO0_8':
      PIN_NUMBER='(0,0,0,0,H12,0,0)';
      PINUSE='POWER';
      NO_LOAD_CHECK='Both';
      NO_IO_CHECK='Both';
      NO_ASSERT_CHECK='TRUE';
      NO_DIR_CHECK='TRUE';
      ALLOW_CONNECT='TRUE';
    'VCCIO0_9':
      PIN_NUMBER='(0,0,0,0,H14,0,0)';
      PINUSE='POWER';
      NO_LOAD_CHECK='Both';
      NO_IO_CHECK='Both';
      NO_ASSERT_CHECK='TRUE';
      NO_DIR_CHECK='TRUE';
      ALLOW_CONNECT='TRUE';
    'VCCIO0_6':
      PIN_NUMBER='(0,0,0,0,H9,0,0)';
      PINUSE='POWER';
      NO_LOAD_CHECK='Both';
      NO_IO_CHECK='Both';
      NO_ASSERT_CHECK='TRUE';
      NO_DIR_CHECK='TRUE';
      ALLOW_CONNECT='TRUE';
    'VCCIO0_5':
      PIN_NUMBER='(0,0,0,0,G13,0,0)';
      PINUSE='POWER';
      NO_LOAD_CHECK='Both';
      NO_IO_CHECK='Both';
      NO_ASSERT_CHECK='TRUE';
      NO_DIR_CHECK='TRUE';
      ALLOW_CONNECT='TRUE';
    'GND1':
      PIN_NUMBER='(0,0,0,0,0,A1,0)';
      PINUSE='POWER';
      NO_LOAD_CHECK='Both';
      NO_IO_CHECK='Both';
      NO_ASSERT_CHECK='TRUE';
      NO_DIR_CHECK='TRUE';
      ALLOW_CONNECT='TRUE';
    'GND2':
      PIN_NUMBER='(0,0,0,0,0,A22,0)';
      PINUSE='POWER';
      NO_LOAD_CHECK='Both';
      NO_IO_CHECK='Both';
      NO_ASSERT_CHECK='TRUE';
      NO_DIR_CHECK='TRUE';
      ALLOW_CONNECT='TRUE';
    'GND3':
      PIN_NUMBER='(0,0,0,0,0,B7,0)';
      PINUSE='POWER';
      NO_LOAD_CHECK='Both';
      NO_IO_CHECK='Both';
      NO_ASSERT_CHECK='TRUE';
      NO_DIR_CHECK='TRUE';
      ALLOW_CONNECT='TRUE';
    'GND4':
      PIN_NUMBER='(0,0,0,0,0,B16,0)';
      PINUSE='POWER';
      NO_LOAD_CHECK='Both';
      NO_IO_CHECK='Both';
      NO_ASSERT_CHECK='TRUE';
      NO_DIR_CHECK='TRUE';
      ALLOW_CONNECT='TRUE';
    'GND5':
      PIN_NUMBER='(0,0,0,0,0,C2,0)';
      PINUSE='POWER';
      NO_LOAD_CHECK='Both';
      NO_IO_CHECK='Both';
      NO_ASSERT_CHECK='TRUE';
      NO_DIR_CHECK='TRUE';
      ALLOW_CONNECT='TRUE';
    'GND6':
      PIN_NUMBER='(0,0,0,0,0,C11,0)';
      PINUSE='POWER';
      NO_LOAD_CHECK='Both';
      NO_IO_CHECK='Both';
      NO_ASSERT_CHECK='TRUE';
      NO_DIR_CHECK='TRUE';
      ALLOW_CONNECT='TRUE';
    'GND7':
      PIN_NUMBER='(0,0,0,0,0,E5,0)';
      PINUSE='POWER';
      NO_LOAD_CHECK='Both';
      NO_IO_CHECK='Both';
      NO_ASSERT_CHECK='TRUE';
      NO_DIR_CHECK='TRUE';
      ALLOW_CONNECT='TRUE';
    'GND8':
      PIN_NUMBER='(0,0,0,0,0,E18,0)';
      PINUSE='POWER';
      NO_LOAD_CHECK='Both';
      NO_IO_CHECK='Both';
      NO_ASSERT_CHECK='TRUE';
      NO_DIR_CHECK='TRUE';
      ALLOW_CONNECT='TRUE';
    'GND9':
      PIN_NUMBER='(0,0,0,0,0,F2,0)';
      PINUSE='POWER';
      NO_LOAD_CHECK='Both';
      NO_IO_CHECK='Both';
      NO_ASSERT_CHECK='TRUE';
      NO_DIR_CHECK='TRUE';
      ALLOW_CONNECT='TRUE';
    'GND10':
      PIN_NUMBER='(0,0,0,0,0,F21,0)';
      PINUSE='POWER';
      NO_LOAD_CHECK='Both';
      NO_IO_CHECK='Both';
      NO_ASSERT_CHECK='TRUE';
      NO_DIR_CHECK='TRUE';
      ALLOW_CONNECT='TRUE';
    'GND11':
      PIN_NUMBER='(0,0,0,0,0,H8,0)';
      PINUSE='POWER';
      NO_LOAD_CHECK='Both';
      NO_IO_CHECK='Both';
      NO_ASSERT_CHECK='TRUE';
      NO_DIR_CHECK='TRUE';
      ALLOW_CONNECT='TRUE';
    'GND12':
      PIN_NUMBER='(0,0,0,0,0,H10,0)';
      PINUSE='POWER';
      NO_LOAD_CHECK='Both';
      NO_IO_CHECK='Both';
      NO_ASSERT_CHECK='TRUE';
      NO_DIR_CHECK='TRUE';
      ALLOW_CONNECT='TRUE';
    'GND13':
      PIN_NUMBER='(0,0,0,0,0,H13,0)';
      PINUSE='POWER';
      NO_LOAD_CHECK='Both';
      NO_IO_CHECK='Both';
      NO_ASSERT_CHECK='TRUE';
      NO_DIR_CHECK='TRUE';
      ALLOW_CONNECT='TRUE';
    'GND14':
      PIN_NUMBER='(0,0,0,0,0,H15,0)';
      PINUSE='POWER';
      NO_LOAD_CHECK='Both';
      NO_IO_CHECK='Both';
      NO_ASSERT_CHECK='TRUE';
      NO_DIR_CHECK='TRUE';
      ALLOW_CONNECT='TRUE';
    'GND15':
      PIN_NUMBER='(0,0,0,0,0,J9,0)';
      PINUSE='POWER';
      NO_LOAD_CHECK='Both';
      NO_IO_CHECK='Both';
      NO_ASSERT_CHECK='TRUE';
      NO_DIR_CHECK='TRUE';
      ALLOW_CONNECT='TRUE';
    'GND16':
      PIN_NUMBER='(0,0,0,0,0,J10,0)';
      PINUSE='POWER';
      NO_LOAD_CHECK='Both';
      NO_IO_CHECK='Both';
      NO_ASSERT_CHECK='TRUE';
      NO_DIR_CHECK='TRUE';
      ALLOW_CONNECT='TRUE';
    'GND17':
      PIN_NUMBER='(0,0,0,0,0,J11,0)';
      PINUSE='POWER';
      NO_LOAD_CHECK='Both';
      NO_IO_CHECK='Both';
      NO_ASSERT_CHECK='TRUE';
      NO_DIR_CHECK='TRUE';
      ALLOW_CONNECT='TRUE';
    'GND18':
      PIN_NUMBER='(0,0,0,0,0,J12,0)';
      PINUSE='POWER';
      NO_LOAD_CHECK='Both';
      NO_IO_CHECK='Both';
      NO_ASSERT_CHECK='TRUE';
      NO_DIR_CHECK='TRUE';
      ALLOW_CONNECT='TRUE';
    'GND19':
      PIN_NUMBER='(0,0,0,0,0,J13,0)';
      PINUSE='POWER';
      NO_LOAD_CHECK='Both';
      NO_IO_CHECK='Both';
      NO_ASSERT_CHECK='TRUE';
      NO_DIR_CHECK='TRUE';
      ALLOW_CONNECT='TRUE';
    'GND20':
      PIN_NUMBER='(0,0,0,0,0,J14,0)';
      PINUSE='POWER';
      NO_LOAD_CHECK='Both';
      NO_IO_CHECK='Both';
      NO_ASSERT_CHECK='TRUE';
      NO_DIR_CHECK='TRUE';
      ALLOW_CONNECT='TRUE';
    'GND21':
      PIN_NUMBER='(0,0,0,0,0,K9,0)';
      PINUSE='POWER';
      NO_LOAD_CHECK='Both';
      NO_IO_CHECK='Both';
      NO_ASSERT_CHECK='TRUE';
      NO_DIR_CHECK='TRUE';
      ALLOW_CONNECT='TRUE';
    'GND22':
      PIN_NUMBER='(0,0,0,0,0,K14,0)';
      PINUSE='POWER';
      NO_LOAD_CHECK='Both';
      NO_IO_CHECK='Both';
      NO_ASSERT_CHECK='TRUE';
      NO_DIR_CHECK='TRUE';
      ALLOW_CONNECT='TRUE';
    'GND23':
      PIN_NUMBER='(0,0,0,0,0,K21,0)';
      PINUSE='POWER';
      NO_LOAD_CHECK='Both';
      NO_IO_CHECK='Both';
      NO_ASSERT_CHECK='TRUE';
      NO_DIR_CHECK='TRUE';
      ALLOW_CONNECT='TRUE';
    'GND24':
      PIN_NUMBER='(0,0,0,0,0,L2,0)';
      PINUSE='POWER';
      NO_LOAD_CHECK='Both';
      NO_IO_CHECK='Both';
      NO_ASSERT_CHECK='TRUE';
      NO_DIR_CHECK='TRUE';
      ALLOW_CONNECT='TRUE';
    'GND25':
      PIN_NUMBER='(0,0,0,0,0,L9,0)';
      PINUSE='POWER';
      NO_LOAD_CHECK='Both';
      NO_IO_CHECK='Both';
      NO_ASSERT_CHECK='TRUE';
      NO_DIR_CHECK='TRUE';
      ALLOW_CONNECT='TRUE';
    'GND26':
      PIN_NUMBER='(0,0,0,0,0,L10,0)';
      PINUSE='POWER';
      NO_LOAD_CHECK='Both';
      NO_IO_CHECK='Both';
      NO_ASSERT_CHECK='TRUE';
      NO_DIR_CHECK='TRUE';
      ALLOW_CONNECT='TRUE';
    'GND27':
      PIN_NUMBER='(0,0,0,0,0,L13,0)';
      PINUSE='POWER';
      NO_LOAD_CHECK='Both';
      NO_IO_CHECK='Both';
      NO_ASSERT_CHECK='TRUE';
      NO_DIR_CHECK='TRUE';
      ALLOW_CONNECT='TRUE';
    'GND28':
      PIN_NUMBER='(0,0,0,0,0,L14,0)';
      PINUSE='POWER';
      NO_LOAD_CHECK='Both';
      NO_IO_CHECK='Both';
      NO_ASSERT_CHECK='TRUE';
      NO_DIR_CHECK='TRUE';
      ALLOW_CONNECT='TRUE';
    'GND29':
      PIN_NUMBER='(0,0,0,0,0,L18,0)';
      PINUSE='POWER';
      NO_LOAD_CHECK='Both';
      NO_IO_CHECK='Both';
      NO_ASSERT_CHECK='TRUE';
      NO_DIR_CHECK='TRUE';
      ALLOW_CONNECT='TRUE';
    'GND30':
      PIN_NUMBER='(0,0,0,0,0,M4,0)';
      PINUSE='POWER';
      NO_LOAD_CHECK='Both';
      NO_IO_CHECK='Both';
      NO_ASSERT_CHECK='TRUE';
      NO_DIR_CHECK='TRUE';
      ALLOW_CONNECT='TRUE';
    'GND31':
      PIN_NUMBER='(0,0,0,0,0,M9,0)';
      PINUSE='POWER';
      NO_LOAD_CHECK='Both';
      NO_IO_CHECK='Both';
      NO_ASSERT_CHECK='TRUE';
      NO_DIR_CHECK='TRUE';
      ALLOW_CONNECT='TRUE';
    'GND32':
      PIN_NUMBER='(0,0,0,0,0,M10,0)';
      PINUSE='POWER';
      NO_LOAD_CHECK='Both';
      NO_IO_CHECK='Both';
      NO_ASSERT_CHECK='TRUE';
      NO_DIR_CHECK='TRUE';
      ALLOW_CONNECT='TRUE';
    'GND33':
      PIN_NUMBER='(0,0,0,0,0,M13,0)';
      PINUSE='POWER';
      NO_LOAD_CHECK='Both';
      NO_IO_CHECK='Both';
      NO_ASSERT_CHECK='TRUE';
      NO_DIR_CHECK='TRUE';
      ALLOW_CONNECT='TRUE';
    'GND34':
      PIN_NUMBER='(0,0,0,0,0,M14,0)';
      PINUSE='POWER';
      NO_LOAD_CHECK='Both';
      NO_IO_CHECK='Both';
      NO_ASSERT_CHECK='TRUE';
      NO_DIR_CHECK='TRUE';
      ALLOW_CONNECT='TRUE';
    'GND35':
      PIN_NUMBER='(0,0,0,0,0,N9,0)';
      PINUSE='POWER';
      NO_LOAD_CHECK='Both';
      NO_IO_CHECK='Both';
      NO_ASSERT_CHECK='TRUE';
      NO_DIR_CHECK='TRUE';
      ALLOW_CONNECT='TRUE';
    'GND36':
      PIN_NUMBER='(0,0,0,0,0,N14,0)';
      PINUSE='POWER';
      NO_LOAD_CHECK='Both';
      NO_IO_CHECK='Both';
      NO_ASSERT_CHECK='TRUE';
      NO_DIR_CHECK='TRUE';
      ALLOW_CONNECT='TRUE';
    'GND37':
      PIN_NUMBER='(0,0,0,0,0,N21,0)';
      PINUSE='POWER';
      NO_LOAD_CHECK='Both';
      NO_IO_CHECK='Both';
      NO_ASSERT_CHECK='TRUE';
      NO_DIR_CHECK='TRUE';
      ALLOW_CONNECT='TRUE';
    'GND38':
      PIN_NUMBER='(0,0,0,0,0,P9,0)';
      PINUSE='POWER';
      NO_LOAD_CHECK='Both';
      NO_IO_CHECK='Both';
      NO_ASSERT_CHECK='TRUE';
      NO_DIR_CHECK='TRUE';
      ALLOW_CONNECT='TRUE';
    'GND39':
      PIN_NUMBER='(0,0,0,0,0,P10,0)';
      PINUSE='POWER';
      NO_LOAD_CHECK='Both';
      NO_IO_CHECK='Both';
      NO_ASSERT_CHECK='TRUE';
      NO_DIR_CHECK='TRUE';
      ALLOW_CONNECT='TRUE';
    'GND40':
      PIN_NUMBER='(0,0,0,0,0,P11,0)';
      PINUSE='POWER';
      NO_LOAD_CHECK='Both';
      NO_IO_CHECK='Both';
      NO_ASSERT_CHECK='TRUE';
      NO_DIR_CHECK='TRUE';
      ALLOW_CONNECT='TRUE';
    'GND41':
      PIN_NUMBER='(0,0,0,0,0,P12,0)';
      PINUSE='POWER';
      NO_LOAD_CHECK='Both';
      NO_IO_CHECK='Both';
      NO_ASSERT_CHECK='TRUE';
      NO_DIR_CHECK='TRUE';
      ALLOW_CONNECT='TRUE';
    'GND42':
      PIN_NUMBER='(0,0,0,0,0,P13,0)';
      PINUSE='POWER';
      NO_LOAD_CHECK='Both';
      NO_IO_CHECK='Both';
      NO_ASSERT_CHECK='TRUE';
      NO_DIR_CHECK='TRUE';
      ALLOW_CONNECT='TRUE';
    'GND43':
      PIN_NUMBER='(0,0,0,0,0,P14,0)';
      PINUSE='POWER';
      NO_LOAD_CHECK='Both';
      NO_IO_CHECK='Both';
      NO_ASSERT_CHECK='TRUE';
      NO_DIR_CHECK='TRUE';
      ALLOW_CONNECT='TRUE';
    'GND44':
      PIN_NUMBER='(0,0,0,0,0,R8,0)';
      PINUSE='POWER';
      NO_LOAD_CHECK='Both';
      NO_IO_CHECK='Both';
      NO_ASSERT_CHECK='TRUE';
      NO_DIR_CHECK='TRUE';
      ALLOW_CONNECT='TRUE';
    'GND45':
      PIN_NUMBER='(0,0,0,0,0,R15,0)';
      PINUSE='POWER';
      NO_LOAD_CHECK='Both';
      NO_IO_CHECK='Both';
      NO_ASSERT_CHECK='TRUE';
      NO_DIR_CHECK='TRUE';
      ALLOW_CONNECT='TRUE';
    'GND46':
      PIN_NUMBER='(0,0,0,0,0,V2,0)';
      PINUSE='POWER';
      NO_LOAD_CHECK='Both';
      NO_IO_CHECK='Both';
      NO_ASSERT_CHECK='TRUE';
      NO_DIR_CHECK='TRUE';
      ALLOW_CONNECT='TRUE';
    'GND47':
      PIN_NUMBER='(0,0,0,0,0,V21,0)';
      PINUSE='POWER';
      NO_LOAD_CHECK='Both';
      NO_IO_CHECK='Both';
      NO_ASSERT_CHECK='TRUE';
      NO_DIR_CHECK='TRUE';
      ALLOW_CONNECT='TRUE';
    'GND48':
      PIN_NUMBER='(0,0,0,0,0,W12,0)';
      PINUSE='POWER';
      NO_LOAD_CHECK='Both';
      NO_IO_CHECK='Both';
      NO_ASSERT_CHECK='TRUE';
      NO_DIR_CHECK='TRUE';
      ALLOW_CONNECT='TRUE';
    'GND50':
      PIN_NUMBER='(0,0,0,0,0,Y16,0)';
      PINUSE='POWER';
      NO_LOAD_CHECK='Both';
      NO_IO_CHECK='Both';
      NO_ASSERT_CHECK='TRUE';
      NO_DIR_CHECK='TRUE';
      ALLOW_CONNECT='TRUE';
    'GND49':
      PIN_NUMBER='(0,0,0,0,0,Y7,0)';
      PINUSE='POWER';
      NO_LOAD_CHECK='Both';
      NO_IO_CHECK='Both';
      NO_ASSERT_CHECK='TRUE';
      NO_DIR_CHECK='TRUE';
      ALLOW_CONNECT='TRUE';
    'GND51':
      PIN_NUMBER='(0,0,0,0,0,AB1,0)';
      PINUSE='POWER';
      NO_LOAD_CHECK='Both';
      NO_IO_CHECK='Both';
      NO_ASSERT_CHECK='TRUE';
      NO_DIR_CHECK='TRUE';
      ALLOW_CONNECT='TRUE';
    'GND52':
      PIN_NUMBER='(0,0,0,0,0,AB22,0)';
      PINUSE='POWER';
      NO_LOAD_CHECK='Both';
      NO_IO_CHECK='Both';
      NO_ASSERT_CHECK='TRUE';
      NO_DIR_CHECK='TRUE';
      ALLOW_CONNECT='TRUE';
    'PR30B':
      PIN_NUMBER='(0,0,0,0,0,0,W20)';
      BIDIRECTIONAL='TRUE';
      INPUT_LOAD='(-0.01,0.01)';
      OUTPUT_LOAD='(1.0,-1.0)';
      PINUSE='BI';
    'PR30A':
      PIN_NUMBER='(0,0,0,0,0,0,V18)';
      BIDIRECTIONAL='TRUE';
      INPUT_LOAD='(-0.01,0.01)';
      OUTPUT_LOAD='(1.0,-1.0)';
      PINUSE='BI';
    'PR29D':
      PIN_NUMBER='(0,0,0,0,0,0,V19)';
      BIDIRECTIONAL='TRUE';
      INPUT_LOAD='(-0.01,0.01)';
      OUTPUT_LOAD='(1.0,-1.0)';
      PINUSE='BI';
    'PR29B':
      PIN_NUMBER='(0,0,0,0,0,0,Y21)';
      BIDIRECTIONAL='TRUE';
      INPUT_LOAD='(-0.01,0.01)';
      OUTPUT_LOAD='(1.0,-1.0)';
      PINUSE='BI';
    'PR29C':
      PIN_NUMBER='(0,0,0,0,0,0,U17)';
      BIDIRECTIONAL='TRUE';
      INPUT_LOAD='(-0.01,0.01)';
      OUTPUT_LOAD='(1.0,-1.0)';
      PINUSE='BI';
    'PR29A':
      PIN_NUMBER='(0,0,0,0,0,0,AA22)';
      BIDIRECTIONAL='TRUE';
      INPUT_LOAD='(-0.01,0.01)';
      OUTPUT_LOAD='(1.0,-1.0)';
      PINUSE='BI';
    'PR25B':
      PIN_NUMBER='(0,0,0,0,0,0,W22)';
      BIDIRECTIONAL='TRUE';
      INPUT_LOAD='(-0.01,0.01)';
      OUTPUT_LOAD='(1.0,-1.0)';
      PINUSE='BI';
    'PR25A':
      PIN_NUMBER='(0,0,0,0,0,0,V22)';
      BIDIRECTIONAL='TRUE';
      INPUT_LOAD='(-0.01,0.01)';
      OUTPUT_LOAD='(1.0,-1.0)';
      PINUSE='BI';
    'PR20B':
      PIN_NUMBER='(0,0,0,0,0,0,R21)';
      BIDIRECTIONAL='TRUE';
      INPUT_LOAD='(-0.01,0.01)';
      OUTPUT_LOAD='(1.0,-1.0)';
      PINUSE='BI';
    'PR20A':
      PIN_NUMBER='(0,0,0,0,0,0,R22)';
      BIDIRECTIONAL='TRUE';
      INPUT_LOAD='(-0.01,0.01)';
      OUTPUT_LOAD='(1.0,-1.0)';
      PINUSE='BI';
    'PR19B':
      PIN_NUMBER='(0,0,0,0,0,0,P21)';
      BIDIRECTIONAL='TRUE';
      INPUT_LOAD='(-0.01,0.01)';
      OUTPUT_LOAD='(1.0,-1.0)';
      PINUSE='BI';
    'PR19A':
      PIN_NUMBER='(0,0,0,0,0,0,N22)';
      BIDIRECTIONAL='TRUE';
      INPUT_LOAD='(-0.01,0.01)';
      OUTPUT_LOAD='(1.0,-1.0)';
      PINUSE='BI';
    'PR17B||PCLKC1_0':
      PIN_NUMBER='(0,0,0,0,0,0,M21)';
      BIDIRECTIONAL='TRUE';
      INPUT_LOAD='(-0.01,0.01)';
      OUTPUT_LOAD='(1.0,-1.0)';
      PINUSE='BI';
    'PR17A||PCLKT1_0':
      PIN_NUMBER='(0,0,0,0,0,0,M22)';
      BIDIRECTIONAL='TRUE';
      INPUT_LOAD='(-0.01,0.01)';
      OUTPUT_LOAD='(1.0,-1.0)';
      PINUSE='BI';
    'PR16B':
      PIN_NUMBER='(0,0,0,0,0,0,L21)';
      BIDIRECTIONAL='TRUE';
      INPUT_LOAD='(-0.01,0.01)';
      OUTPUT_LOAD='(1.0,-1.0)';
      PINUSE='BI';
    'PR16A':
      PIN_NUMBER='(0,0,0,0,0,0,K22)';
      BIDIRECTIONAL='TRUE';
      INPUT_LOAD='(-0.01,0.01)';
      OUTPUT_LOAD='(1.0,-1.0)';
      PINUSE='BI';
    'PR14B':
      PIN_NUMBER='(0,0,0,0,0,0,L16)';
      BIDIRECTIONAL='TRUE';
      INPUT_LOAD='(-0.01,0.01)';
      OUTPUT_LOAD='(1.0,-1.0)';
      PINUSE='BI';
    'PR14A':
      PIN_NUMBER='(0,0,0,0,0,0,L17)';
      BIDIRECTIONAL='TRUE';
      INPUT_LOAD='(-0.01,0.01)';
      OUTPUT_LOAD='(1.0,-1.0)';
      PINUSE='BI';
    'PR7B':
      PIN_NUMBER='(0,0,0,0,0,0,H21)';
      BIDIRECTIONAL='TRUE';
      INPUT_LOAD='(-0.01,0.01)';
      OUTPUT_LOAD='(1.0,-1.0)';
      PINUSE='BI';
    'PR7A':
      PIN_NUMBER='(0,0,0,0,0,0,H22)';
      BIDIRECTIONAL='TRUE';
      INPUT_LOAD='(-0.01,0.01)';
      OUTPUT_LOAD='(1.0,-1.0)';
      PINUSE='BI';
    'PR3B||R_GPLLC_IN':
      PIN_NUMBER='(0,0,0,0,0,0,D21)';
      BIDIRECTIONAL='TRUE';
      INPUT_LOAD='(-0.01,0.01)';
      OUTPUT_LOAD='(1.0,-1.0)';
      PINUSE='BI';
    'PR3A||R_GPLLT_IN':
      PIN_NUMBER='(0,0,0,0,0,0,D22)';
      BIDIRECTIONAL='TRUE';
      INPUT_LOAD='(-0.01,0.01)';
      OUTPUT_LOAD='(1.0,-1.0)';
      PINUSE='BI';
    'PR2B||R_GPLLC_FB':
      PIN_NUMBER='(0,0,0,0,0,0,C22)';
      BIDIRECTIONAL='TRUE';
      INPUT_LOAD='(-0.01,0.01)';
      OUTPUT_LOAD='(1.0,-1.0)';
      PINUSE='BI';
    'PR2A||R_GPLLT_FB':
      PIN_NUMBER='(0,0,0,0,0,0,C21)';
      BIDIRECTIONAL='TRUE';
      INPUT_LOAD='(-0.01,0.01)';
      OUTPUT_LOAD='(1.0,-1.0)';
      PINUSE='BI';
    'PR2C':
      PIN_NUMBER='(0,0,0,0,0,0,F17)';
      BIDIRECTIONAL='TRUE';
      INPUT_LOAD='(-0.01,0.01)';
      OUTPUT_LOAD='(1.0,-1.0)';
      PINUSE='BI';
    'PR2D':
      PIN_NUMBER='(0,0,0,0,0,0,G16)';
      BIDIRECTIONAL='TRUE';
      INPUT_LOAD='(-0.01,0.01)';
      OUTPUT_LOAD='(1.0,-1.0)';
      PINUSE='BI';
    'PR3C':
      PIN_NUMBER='(0,0,0,0,0,0,D19)';
      BIDIRECTIONAL='TRUE';
      INPUT_LOAD='(-0.01,0.01)';
      OUTPUT_LOAD='(1.0,-1.0)';
      PINUSE='BI';
    'PR3D':
      PIN_NUMBER='(0,0,0,0,0,0,D20)';
      BIDIRECTIONAL='TRUE';
      INPUT_LOAD='(-0.01,0.01)';
      OUTPUT_LOAD='(1.0,-1.0)';
      PINUSE='BI';
    'PR4C':
      PIN_NUMBER='(0,0,0,0,0,0,E19)';
      BIDIRECTIONAL='TRUE';
      INPUT_LOAD='(-0.01,0.01)';
      OUTPUT_LOAD='(1.0,-1.0)';
      PINUSE='BI';
    'PR4D':
      PIN_NUMBER='(0,0,0,0,0,0,E20)';
      BIDIRECTIONAL='TRUE';
      INPUT_LOAD='(-0.01,0.01)';
      OUTPUT_LOAD='(1.0,-1.0)';
      PINUSE='BI';
    'PR4A':
      PIN_NUMBER='(0,0,0,0,0,0,E22)';
      BIDIRECTIONAL='TRUE';
      INPUT_LOAD='(-0.01,0.01)';
      OUTPUT_LOAD='(1.0,-1.0)';
      PINUSE='BI';
    'PR4B':
      PIN_NUMBER='(0,0,0,0,0,0,E21)';
      BIDIRECTIONAL='TRUE';
      INPUT_LOAD='(-0.01,0.01)';
      OUTPUT_LOAD='(1.0,-1.0)';
      PINUSE='BI';
    'PR5A':
      PIN_NUMBER='(0,0,0,0,0,0,F22)';
      BIDIRECTIONAL='TRUE';
      INPUT_LOAD='(-0.01,0.01)';
      OUTPUT_LOAD='(1.0,-1.0)';
      PINUSE='BI';
    'PR5B':
      PIN_NUMBER='(0,0,0,0,0,0,G22)';
      BIDIRECTIONAL='TRUE';
      INPUT_LOAD='(-0.01,0.01)';
      OUTPUT_LOAD='(1.0,-1.0)';
      PINUSE='BI';
    'PR5C':
      PIN_NUMBER='(0,0,0,0,0,0,F18)';
      BIDIRECTIONAL='TRUE';
      INPUT_LOAD='(-0.01,0.01)';
      OUTPUT_LOAD='(1.0,-1.0)';
      PINUSE='BI';
    'PR5D':
      PIN_NUMBER='(0,0,0,0,0,0,F19)';
      BIDIRECTIONAL='TRUE';
      INPUT_LOAD='(-0.01,0.01)';
      OUTPUT_LOAD='(1.0,-1.0)';
      PINUSE='BI';
    'PR6A':
      PIN_NUMBER='(0,0,0,0,0,0,G21)';
      BIDIRECTIONAL='TRUE';
      INPUT_LOAD='(-0.01,0.01)';
      OUTPUT_LOAD='(1.0,-1.0)';
      PINUSE='BI';
    'PR6B':
      PIN_NUMBER='(0,0,0,0,0,0,G20)';
      BIDIRECTIONAL='TRUE';
      INPUT_LOAD='(-0.01,0.01)';
      OUTPUT_LOAD='(1.0,-1.0)';
      PINUSE='BI';
    'PR6C':
      PIN_NUMBER='(0,0,0,0,0,0,G19)';
      BIDIRECTIONAL='TRUE';
      INPUT_LOAD='(-0.01,0.01)';
      OUTPUT_LOAD='(1.0,-1.0)';
      PINUSE='BI';
    'PR6D':
      PIN_NUMBER='(0,0,0,0,0,0,G18)';
      BIDIRECTIONAL='TRUE';
      INPUT_LOAD='(-0.01,0.01)';
      OUTPUT_LOAD='(1.0,-1.0)';
      PINUSE='BI';
    'PR7C':
      PIN_NUMBER='(0,0,0,0,0,0,G17)';
      BIDIRECTIONAL='TRUE';
      INPUT_LOAD='(-0.01,0.01)';
      OUTPUT_LOAD='(1.0,-1.0)';
      PINUSE='BI';
    'PR7D':
      PIN_NUMBER='(0,0,0,0,0,0,H20)';
      BIDIRECTIONAL='TRUE';
      INPUT_LOAD='(-0.01,0.01)';
      OUTPUT_LOAD='(1.0,-1.0)';
      PINUSE='BI';
    'PR10A':
      PIN_NUMBER='(0,0,0,0,0,0,H19)';
      BIDIRECTIONAL='TRUE';
      INPUT_LOAD='(-0.01,0.01)';
      OUTPUT_LOAD='(1.0,-1.0)';
      PINUSE='BI';
    'PR10B':
      PIN_NUMBER='(0,0,0,0,0,0,H18)';
      BIDIRECTIONAL='TRUE';
      INPUT_LOAD='(-0.01,0.01)';
      OUTPUT_LOAD='(1.0,-1.0)';
      PINUSE='BI';
    'PR10C':
      PIN_NUMBER='(0,0,0,0,0,0,H17)';
      BIDIRECTIONAL='TRUE';
      INPUT_LOAD='(-0.01,0.01)';
      OUTPUT_LOAD='(1.0,-1.0)';
      PINUSE='BI';
    'PR10D':
      PIN_NUMBER='(0,0,0,0,0,0,H16)';
      BIDIRECTIONAL='TRUE';
      INPUT_LOAD='(-0.01,0.01)';
      OUTPUT_LOAD='(1.0,-1.0)';
      PINUSE='BI';
    'PR11A':
      PIN_NUMBER='(0,0,0,0,0,0,J16)';
      BIDIRECTIONAL='TRUE';
      INPUT_LOAD='(-0.01,0.01)';
      OUTPUT_LOAD='(1.0,-1.0)';
      PINUSE='BI';
    'PR11B':
      PIN_NUMBER='(0,0,0,0,0,0,J17)';
      BIDIRECTIONAL='TRUE';
      INPUT_LOAD='(-0.01,0.01)';
      OUTPUT_LOAD='(1.0,-1.0)';
      PINUSE='BI';
    'PR11C':
      PIN_NUMBER='(0,0,0,0,0,0,J18)';
      BIDIRECTIONAL='TRUE';
      INPUT_LOAD='(-0.01,0.01)';
      OUTPUT_LOAD='(1.0,-1.0)';
      PINUSE='BI';
    'PR11D':
      PIN_NUMBER='(0,0,0,0,0,0,J19)';
      BIDIRECTIONAL='TRUE';
      INPUT_LOAD='(-0.01,0.01)';
      OUTPUT_LOAD='(1.0,-1.0)';
      PINUSE='BI';
    'PR12A':
      PIN_NUMBER='(0,0,0,0,0,0,J21)';
      BIDIRECTIONAL='TRUE';
      INPUT_LOAD='(-0.01,0.01)';
      OUTPUT_LOAD='(1.0,-1.0)';
      PINUSE='BI';
    'PR12B':
      PIN_NUMBER='(0,0,0,0,0,0,J22)';
      BIDIRECTIONAL='TRUE';
      INPUT_LOAD='(-0.01,0.01)';
      OUTPUT_LOAD='(1.0,-1.0)';
      PINUSE='BI';
    'PR12C':
      PIN_NUMBER='(0,0,0,0,0,0,J20)';
      BIDIRECTIONAL='TRUE';
      INPUT_LOAD='(-0.01,0.01)';
      OUTPUT_LOAD='(1.0,-1.0)';
      PINUSE='BI';
    'PR12D':
      PIN_NUMBER='(0,0,0,0,0,0,K20)';
      BIDIRECTIONAL='TRUE';
      INPUT_LOAD='(-0.01,0.01)';
      OUTPUT_LOAD='(1.0,-1.0)';
      PINUSE='BI';
    'PR13A':
      PIN_NUMBER='(0,0,0,0,0,0,K19)';
      BIDIRECTIONAL='TRUE';
      INPUT_LOAD='(-0.01,0.01)';
      OUTPUT_LOAD='(1.0,-1.0)';
      PINUSE='BI';
    'PR13B':
      PIN_NUMBER='(0,0,0,0,0,0,K18)';
      BIDIRECTIONAL='TRUE';
      INPUT_LOAD='(-0.01,0.01)';
      OUTPUT_LOAD='(1.0,-1.0)';
      PINUSE='BI';
    'PR13C':
      PIN_NUMBER='(0,0,0,0,0,0,K17)';
      BIDIRECTIONAL='TRUE';
      INPUT_LOAD='(-0.01,0.01)';
      OUTPUT_LOAD='(1.0,-1.0)';
      PINUSE='BI';
    'PR13D':
      PIN_NUMBER='(0,0,0,0,0,0,K16)';
      BIDIRECTIONAL='TRUE';
      INPUT_LOAD='(-0.01,0.01)';
      OUTPUT_LOAD='(1.0,-1.0)';
      PINUSE='BI';
    'PR14C':
      PIN_NUMBER='(0,0,0,0,0,0,L19)';
      BIDIRECTIONAL='TRUE';
      INPUT_LOAD='(-0.01,0.01)';
      OUTPUT_LOAD='(1.0,-1.0)';
      PINUSE='BI';
    'PR14D':
      PIN_NUMBER='(0,0,0,0,0,0,L20)';
      BIDIRECTIONAL='TRUE';
      INPUT_LOAD='(-0.01,0.01)';
      OUTPUT_LOAD='(1.0,-1.0)';
      PINUSE='BI';
    'PR16C':
      PIN_NUMBER='(0,0,0,0,0,0,L22)';
      BIDIRECTIONAL='TRUE';
      INPUT_LOAD='(-0.01,0.01)';
      OUTPUT_LOAD='(1.0,-1.0)';
      PINUSE='BI';
    'PR16D':
      PIN_NUMBER='(0,0,0,0,0,0,M17)';
      BIDIRECTIONAL='TRUE';
      INPUT_LOAD='(-0.01,0.01)';
      OUTPUT_LOAD='(1.0,-1.0)';
      PINUSE='BI';
    'PR17C':
      PIN_NUMBER='(0,0,0,0,0,0,M20)';
      BIDIRECTIONAL='TRUE';
      INPUT_LOAD='(-0.01,0.01)';
      OUTPUT_LOAD='(1.0,-1.0)';
      PINUSE='BI';
    'PR17D':
      PIN_NUMBER='(0,0,0,0,0,0,M19)';
      BIDIRECTIONAL='TRUE';
      INPUT_LOAD='(-0.01,0.01)';
      OUTPUT_LOAD='(1.0,-1.0)';
      PINUSE='BI';
    'PR18A':
      PIN_NUMBER='(0,0,0,0,0,0,M16)';
      BIDIRECTIONAL='TRUE';
      INPUT_LOAD='(-0.01,0.01)';
      OUTPUT_LOAD='(1.0,-1.0)';
      PINUSE='BI';
    'PR18B':
      PIN_NUMBER='(0,0,0,0,0,0,N16)';
      BIDIRECTIONAL='TRUE';
      INPUT_LOAD='(-0.01,0.01)';
      OUTPUT_LOAD='(1.0,-1.0)';
      PINUSE='BI';
    'PR18C':
      PIN_NUMBER='(0,0,0,0,0,0,N17)';
      BIDIRECTIONAL='TRUE';
      INPUT_LOAD='(-0.01,0.01)';
      OUTPUT_LOAD='(1.0,-1.0)';
      PINUSE='BI';
    'PR18D':
      PIN_NUMBER='(0,0,0,0,0,0,N18)';
      BIDIRECTIONAL='TRUE';
      INPUT_LOAD='(-0.01,0.01)';
      OUTPUT_LOAD='(1.0,-1.0)';
      PINUSE='BI';
    'PR19C':
      PIN_NUMBER='(0,0,0,0,0,0,N20)';
      BIDIRECTIONAL='TRUE';
      INPUT_LOAD='(-0.01,0.01)';
      OUTPUT_LOAD='(1.0,-1.0)';
      PINUSE='BI';
    'PR19D':
      PIN_NUMBER='(0,0,0,0,0,0,N19)';
      BIDIRECTIONAL='TRUE';
      INPUT_LOAD='(-0.01,0.01)';
      OUTPUT_LOAD='(1.0,-1.0)';
      PINUSE='BI';
    'PR20C':
      PIN_NUMBER='(0,0,0,0,0,0,P22)';
      BIDIRECTIONAL='TRUE';
      INPUT_LOAD='(-0.01,0.01)';
      OUTPUT_LOAD='(1.0,-1.0)';
      PINUSE='BI';
    'PR20D':
      PIN_NUMBER='(0,0,0,0,0,0,P20)';
      BIDIRECTIONAL='TRUE';
      INPUT_LOAD='(-0.01,0.01)';
      OUTPUT_LOAD='(1.0,-1.0)';
      PINUSE='BI';
    'PR21A':
      PIN_NUMBER='(0,0,0,0,0,0,T22)';
      BIDIRECTIONAL='TRUE';
      INPUT_LOAD='(-0.01,0.01)';
      OUTPUT_LOAD='(1.0,-1.0)';
      PINUSE='BI';
    'PR21B':
      PIN_NUMBER='(0,0,0,0,0,0,T21)';
      BIDIRECTIONAL='TRUE';
      INPUT_LOAD='(-0.01,0.01)';
      OUTPUT_LOAD='(1.0,-1.0)';
      PINUSE='BI';
    'PR21C':
      PIN_NUMBER='(0,0,0,0,0,0,P19)';
      BIDIRECTIONAL='TRUE';
      INPUT_LOAD='(-0.01,0.01)';
      OUTPUT_LOAD='(1.0,-1.0)';
      PINUSE='BI';
    'PR21D':
      PIN_NUMBER='(0,0,0,0,0,0,P18)';
      BIDIRECTIONAL='TRUE';
      INPUT_LOAD='(-0.01,0.01)';
      OUTPUT_LOAD='(1.0,-1.0)';
      PINUSE='BI';
    'PR24A':
      PIN_NUMBER='(0,0,0,0,0,0,P17)';
      BIDIRECTIONAL='TRUE';
      INPUT_LOAD='(-0.01,0.01)';
      OUTPUT_LOAD='(1.0,-1.0)';
      PINUSE='BI';
    'PR24B':
      PIN_NUMBER='(0,0,0,0,0,0,P16)';
      BIDIRECTIONAL='TRUE';
      INPUT_LOAD='(-0.01,0.01)';
      OUTPUT_LOAD='(1.0,-1.0)';
      PINUSE='BI';
    'PR24C':
      PIN_NUMBER='(0,0,0,0,0,0,U22)';
      BIDIRECTIONAL='TRUE';
      INPUT_LOAD='(-0.01,0.01)';
      OUTPUT_LOAD='(1.0,-1.0)';
      PINUSE='BI';
    'PR24D':
      PIN_NUMBER='(0,0,0,0,0,0,U21)';
      BIDIRECTIONAL='TRUE';
      INPUT_LOAD='(-0.01,0.01)';
      OUTPUT_LOAD='(1.0,-1.0)';
      PINUSE='BI';
    'PR25C':
      PIN_NUMBER='(0,0,0,0,0,0,R20)';
      BIDIRECTIONAL='TRUE';
      INPUT_LOAD='(-0.01,0.01)';
      OUTPUT_LOAD='(1.0,-1.0)';
      PINUSE='BI';
    'PR25D':
      PIN_NUMBER='(0,0,0,0,0,0,R19)';
      BIDIRECTIONAL='TRUE';
      INPUT_LOAD='(-0.01,0.01)';
      OUTPUT_LOAD='(1.0,-1.0)';
      PINUSE='BI';
    'PR26A':
      PIN_NUMBER='(0,0,0,0,0,0,R18)';
      BIDIRECTIONAL='TRUE';
      INPUT_LOAD='(-0.01,0.01)';
      OUTPUT_LOAD='(1.0,-1.0)';
      PINUSE='BI';
    'PR26B':
      PIN_NUMBER='(0,0,0,0,0,0,R17)';
      BIDIRECTIONAL='TRUE';
      INPUT_LOAD='(-0.01,0.01)';
      OUTPUT_LOAD='(1.0,-1.0)';
      PINUSE='BI';
    'PR26C':
      PIN_NUMBER='(0,0,0,0,0,0,R16)';
      BIDIRECTIONAL='TRUE';
      INPUT_LOAD='(-0.01,0.01)';
      OUTPUT_LOAD='(1.0,-1.0)';
      PINUSE='BI';
    'PR26D':
      PIN_NUMBER='(0,0,0,0,0,0,T20)';
      BIDIRECTIONAL='TRUE';
      INPUT_LOAD='(-0.01,0.01)';
      OUTPUT_LOAD='(1.0,-1.0)';
      PINUSE='BI';
    'PR27A':
      PIN_NUMBER='(0,0,0,0,0,0,T19)';
      BIDIRECTIONAL='TRUE';
      INPUT_LOAD='(-0.01,0.01)';
      OUTPUT_LOAD='(1.0,-1.0)';
      PINUSE='BI';
    'PR27B':
      PIN_NUMBER='(0,0,0,0,0,0,T18)';
      BIDIRECTIONAL='TRUE';
      INPUT_LOAD='(-0.01,0.01)';
      OUTPUT_LOAD='(1.0,-1.0)';
      PINUSE='BI';
    'PR27C':
      PIN_NUMBER='(0,0,0,0,0,0,T17)';
      BIDIRECTIONAL='TRUE';
      INPUT_LOAD='(-0.01,0.01)';
      OUTPUT_LOAD='(1.0,-1.0)';
      PINUSE='BI';
    'PR27D':
      PIN_NUMBER='(0,0,0,0,0,0,U20)';
      BIDIRECTIONAL='TRUE';
      INPUT_LOAD='(-0.01,0.01)';
      OUTPUT_LOAD='(1.0,-1.0)';
      PINUSE='BI';
    'PR28A':
      PIN_NUMBER='(0,0,0,0,0,0,Y22)';
      BIDIRECTIONAL='TRUE';
      INPUT_LOAD='(-0.01,0.01)';
      OUTPUT_LOAD='(1.0,-1.0)';
      PINUSE='BI';
    'PR28B':
      PIN_NUMBER='(0,0,0,0,0,0,W21)';
      BIDIRECTIONAL='TRUE';
      INPUT_LOAD='(-0.01,0.01)';
      OUTPUT_LOAD='(1.0,-1.0)';
      PINUSE='BI';
    'PR28C':
      PIN_NUMBER='(0,0,0,0,0,0,U19)';
      BIDIRECTIONAL='TRUE';
      INPUT_LOAD='(-0.01,0.01)';
      OUTPUT_LOAD='(1.0,-1.0)';
      PINUSE='BI';
    'PR28D':
      PIN_NUMBER='(0,0,0,0,0,0,U18)';
      BIDIRECTIONAL='TRUE';
      INPUT_LOAD='(-0.01,0.01)';
      OUTPUT_LOAD='(1.0,-1.0)';
      PINUSE='BI';
    'PR30C':
      PIN_NUMBER='(0,0,0,0,0,0,W19)';
      BIDIRECTIONAL='TRUE';
      INPUT_LOAD='(-0.01,0.01)';
      OUTPUT_LOAD='(1.0,-1.0)';
      PINUSE='BI';
    'PR30D':
      PIN_NUMBER='(0,0,0,0,0,0,Y20)';
      BIDIRECTIONAL='TRUE';
      INPUT_LOAD='(-0.01,0.01)';
      OUTPUT_LOAD='(1.0,-1.0)';
      PINUSE='BI';
  end_pin;
  body
      PART_NAME='LCMXO3LF9400C5BG484C';
      BODY_NAME='LCMXO3LF9400C5BG484C';
      PHYS_DES_PREFIX='U';
      CLASS='IC';
      STANDARD='';
      LIFECYCLE='';
      PART_NUMBER='AJ094000T08';
      JEDEC_TYPE='BGA484_0-8_19X19_H67';
      DESCRIPTION='IC(484P)LCMXO3LF-9400C-5BG484C(CABGA)';
      MANUFTR='LSC';
      MANUF_PN='LCMXO3LF-9400C-5BG484C';
      RD_CMPLS_LVL='EP(V1)';
      CMPLS_LVL='';
      FROM_PJ='F0T-FENTUS';
      DIP_SMD='';
      DATA='LSC_LCMXO3LF-9400C-5BG484C.pdf';
      EE_CHECK_LIST='';
      FP_ECN='';
      PSL='';
      CREATOR='';
      STATUS='';
      MSD='';
      ESD_CDM='';
      ESD_HBM='';
      ESD_MM='';
      PIN_LENGTH_SHORT_PIN='0 MILS';
      PIN_LENGTH_LONG_PIN='0 MILS';
      CREATEDAY='20210929';
      PARENT_PART_TYPE='LCMXO3LF9400C5BG484C';
      PARENT_PPT='LCMXO3LF9400C5BG484C';
      PARENT_PPT_PART='LCMXO3LF9400C5BG484C-LCMXO3LF-9400C-5BG484C,SMLF,IC,AJ094000T08';
  end_body;
end_primitive;
primitive 'LM4040AIM3X25NOPB-LM4040AIM3X-2.5/NOPB,SMLF,EMPTY,A';
  pin
    '1+':
      PIN_NUMBER='(1)';
      BIDIRECTIONAL='TRUE';
      INPUT_LOAD='(-0.01,0.01)';
      OUTPUT_LOAD='(1.0,-1.0)';
      PINUSE='BI';
    '2-':
      PIN_NUMBER='(2)';
      OUTPUT_LOAD='(1.0,-1.0)';
      PINUSE='OUT';
    '3':
      PIN_NUMBER='(3)';
      BIDIRECTIONAL='TRUE';
      INPUT_LOAD='(-0.01,0.01)';
      OUTPUT_LOAD='(1.0,-1.0)';
      PINUSE='BI';
  end_pin;
  body
      PART_NAME='LM4040AIM3X25NOPB';
      BODY_NAME='LM4040AIM3X25NOPB';
      PHYS_DES_PREFIX='U';
      CLASS='IC';
      STANDARD='';
      LIFECYCLE='';
      PART_NUMBER='AL404025013';
      JEDEC_TYPE='SOT23_123_2-92X1-3';
      DESCRIPTION='IC OTHER(3P)LM4040AIM3X-2.5/NOPB(SOT23)';
      MANUFTR='TIC';
      MANUF_PN='LM4040AIM3X-2.5/NOPB';
      RD_CMPLS_LVL='EP(V1)';
      CMPLS_LVL='';
      FROM_PJ='T6MB-JOSEPH';
      DIP_SMD='';
      DATA='TIC_LM4040-N_LM4040-N-Q1.pdf';
      EE_CHECK_LIST='';
      FP_ECN='';
      PSL='';
      CREATOR='';
      STATUS='';
      CREATEDAY='20150917';
      PARENT_PART_TYPE='LM4040AIM3X25NOPB';
      PARENT_PPT='LM4040AIM3X25NOPB';
      PARENT_PPT_PART='LM4040AIM3X25NOPB-LM4040AIM3X-2.5/NOPB,SMLF,EMPTY,AL404025013';
  end_body;
end_primitive;
primitive 'LM4040AIM3X25NOPB-LM4040AIM3X-2.5/NOPB,SMLF,IC,AL4A';
  pin
    '1+':
      PIN_NUMBER='(1)';
      BIDIRECTIONAL='TRUE';
      INPUT_LOAD='(-0.01,0.01)';
      OUTPUT_LOAD='(1.0,-1.0)';
      PINUSE='BI';
    '2-':
      PIN_NUMBER='(2)';
      OUTPUT_LOAD='(1.0,-1.0)';
      PINUSE='OUT';
    '3':
      PIN_NUMBER='(3)';
      BIDIRECTIONAL='TRUE';
      INPUT_LOAD='(-0.01,0.01)';
      OUTPUT_LOAD='(1.0,-1.0)';
      PINUSE='BI';
  end_pin;
  body
      PART_NAME='LM4040AIM3X25NOPB';
      BODY_NAME='LM4040AIM3X25NOPB';
      PHYS_DES_PREFIX='U';
      CLASS='IC';
      STANDARD='';
      LIFECYCLE='';
      PART_NUMBER='AL404025013';
      JEDEC_TYPE='SOT23_123_2-92X1-3';
      DESCRIPTION='IC OTHER(3P)LM4040AIM3X-2.5/NOPB(SOT23)';
      MANUFTR='TIC';
      MANUF_PN='LM4040AIM3X-2.5/NOPB';
      RD_CMPLS_LVL='EP(V1)';
      CMPLS_LVL='';
      FROM_PJ='T6MB-JOSEPH';
      DIP_SMD='';
      DATA='TIC_LM4040-N_LM4040-N-Q1.pdf';
      EE_CHECK_LIST='';
      FP_ECN='';
      PSL='';
      CREATOR='';
      STATUS='';
      CREATEDAY='20150917';
      PARENT_PART_TYPE='LM4040AIM3X25NOPB';
      PARENT_PPT='LM4040AIM3X25NOPB';
      PARENT_PPT_PART='LM4040AIM3X25NOPB-LM4040AIM3X-2.5/NOPB,SMLF,IC,AL404025013';
  end_body;
end_primitive;
primitive 'LM75BD-LM75BD,SMLF,IC,AL0075BD000';
  pin
    'SDA':
      PIN_NUMBER='(1)';
      BIDIRECTIONAL='TRUE';
      INPUT_LOAD='(-0.01,0.01)';
      OUTPUT_LOAD='(1.0,-1.0)';
      PINUSE='BI';
    'SCL':
      PIN_NUMBER='(2)';
      INPUT_LOAD='(-0.01,0.01)';
      PINUSE='IN';
    'OS':
      PIN_NUMBER='(3)';
      OUTPUT_LOAD='(1.0,-1.0)';
      PINUSE='OUT';
    'GND':
      PIN_NUMBER='(4)';
      PINUSE='POWER';
      NO_LOAD_CHECK='Both';
      NO_IO_CHECK='Both';
      NO_ASSERT_CHECK='TRUE';
      NO_DIR_CHECK='TRUE';
      ALLOW_CONNECT='TRUE';
    'A2':
      PIN_NUMBER='(5)';
      INPUT_LOAD='(-0.01,0.01)';
      PINUSE='IN';
    'A1':
      PIN_NUMBER='(6)';
      INPUT_LOAD='(-0.01,0.01)';
      PINUSE='IN';
    'A0':
      PIN_NUMBER='(7)';
      INPUT_LOAD='(-0.01,0.01)';
      PINUSE='IN';
    'VCC':
      PIN_NUMBER='(8)';
      PINUSE='POWER';
      NO_LOAD_CHECK='Both';
      NO_IO_CHECK='Both';
      NO_ASSERT_CHECK='TRUE';
      NO_DIR_CHECK='TRUE';
      ALLOW_CONNECT='TRUE';
  end_pin;
  body
      PART_NAME='LM75BD';
      BODY_NAME='LM75BD';
      PHYS_DES_PREFIX='U';
      CLASS='IC';
      STANDARD='';
      LIFECYCLE='';
      PART_NUMBER='AL0075BD000';
      JEDEC_TYPE='SO8_1-27_4-9X3-9';
      DESCRIPTION='IC OTHER (8P) LM75BD(SO8)';
      MANUFTR='NXP';
      MANUF_PN='LM75BD';
      RD_CMPLS_LVL='EP(V1)';
      CMPLS_LVL='EP(V1)';
      FROM_PJ='F0T-BOB-JON';
      DIP_SMD='';
      DATA='NXP_LM75BD.pdf';
      EE_CHECK_LIST='';
      FP_ECN='';
      PSL='';
      CREATOR='';
      STATUS='';
      MSD='';
      ESD_CDM='';
      ESD_HBM='';
      ESD_MM='';
      PIN_LENGTH_SHORT_PIN='0 MILS';
      PIN_LENGTH_LONG_PIN='0 MILS';
      CREATEDAY='20211112';
      PARENT_PART_TYPE='LM75BD';
      PARENT_PPT='LM75BD';
      PARENT_PPT_PART='LM75BD-LM75BD,SMLF,IC,AL0075BD000';
  end_body;
end_primitive;
primitive 'LT6700CS61TRPBF-LT6700CS6-1#TRPBF,SMLF,EMPTY,AL006A';
  pin
    'VS':
      PIN_NUMBER='(5)';
      PINUSE='POWER';
      NO_LOAD_CHECK='Both';
      NO_IO_CHECK='Both';
      NO_ASSERT_CHECK='TRUE';
      NO_DIR_CHECK='TRUE';
      ALLOW_CONNECT='TRUE';
    'INB-':
      PIN_NUMBER='(4)';
      INPUT_LOAD='(-0.01,0.01)';
      PINUSE='IN';
    'GND':
      PIN_NUMBER='(2)';
      PINUSE='POWER';
      NO_LOAD_CHECK='Both';
      NO_IO_CHECK='Both';
      NO_ASSERT_CHECK='TRUE';
      NO_DIR_CHECK='TRUE';
      ALLOW_CONNECT='TRUE';
    'OUTA':
      PIN_NUMBER='(1)';
      OUTPUT_LOAD='(1.0,-1.0)';
      PINUSE='OUT';
    'INA+':
      PIN_NUMBER='(3)';
      INPUT_LOAD='(-0.01,0.01)';
      PINUSE='IN';
    'OUTB':
      PIN_NUMBER='(6)';
      OUTPUT_LOAD='(1.0,-1.0)';
      PINUSE='OUT';
  end_pin;
  body
      PART_NAME='LT6700CS61TRPBF';
      BODY_NAME='LT6700CS61TRPBF';
      PHYS_DES_PREFIX='U';
      CLASS='IC';
      STANDARD='';
      LIFECYCLE='';
      PART_NUMBER='AL006700001';
      JEDEC_TYPE='TSOT23-6_0-95_2-9X1-625';
      DESCRIPTION='IC OTHER(6P)LT6700CS6-1#TRPBF(TSOT-23)';
      MANUFTR='LIN';
      MANUF_PN='LT6700CS6-1#TRPBF';
      RD_CMPLS_LVL='EP';
      CMPLS_LVL='';
      FROM_PJ='F0CE-GARY';
      DIP_SMD='';
      DATA='LIN_LT6700CS6-1TRPBF.pdf';
      EE_CHECK_LIST='';
      FP_ECN='';
      PSL='';
      CREATOR='';
      STATUS='';
      MSD='';
      ESD_CDM='';
      ESD_HBM='';
      ESD_MM='';
      PIN_LENGTH_SHORT_PIN='0 MILS';
      PIN_LENGTH_LONG_PIN='0 MILS';
      CREATEDAY='20210603';
      PARENT_PART_TYPE='LT6700CS61TRPBF';
      PARENT_PPT='LT6700CS61TRPBF';
      PARENT_PPT_PART='LT6700CS61TRPBF-LT6700CS6-1#TRPBF,SMLF,EMPTY,AL006700001';
  end_body;
end_primitive;
primitive 'LTC4307CMS8-LTC4307CMS8,SMLF,EMPTY,AL004307000';
  pin
    'ENABLE':
      PIN_NUMBER='(1)';
      INPUT_LOAD='(-0.01,0.01)';
      PINUSE='IN';
    'SCL_IN':
      PIN_NUMBER='(3)';
      INPUT_LOAD='(-0.01,0.01)';
      OUTPUT_LOAD='(1.0,-1.0)';
      BIDIRECTIONAL='TRUE';
      PINUSE='BI';
    'SDA_IN':
      PIN_NUMBER='(6)';
      INPUT_LOAD='(-0.01,0.01)';
      OUTPUT_LOAD='(1.0,-1.0)';
      BIDIRECTIONAL='TRUE';
      PINUSE='BI';
    'SCL_OUT':
      PIN_NUMBER='(2)';
      INPUT_LOAD='(-0.01,0.01)';
      OUTPUT_LOAD='(1.0,-1.0)';
      BIDIRECTIONAL='TRUE';
      PINUSE='BI';
    'SDA_OUT':
      PIN_NUMBER='(7)';
      INPUT_LOAD='(-0.01,0.01)';
      OUTPUT_LOAD='(1.0,-1.0)';
      BIDIRECTIONAL='TRUE';
      PINUSE='BI';
    'READY':
      PIN_NUMBER='(5)';
      OUTPUT_LOAD='(1.0,-1.0)';
      PINUSE='OUT';
    'GND':
      PIN_NUMBER='(4)';
      PINUSE='POWER';
    'VCC':
      PIN_NUMBER='(8)';
      PINUSE='POWER';
  end_pin;
  body
      CLASS='IC';
      PART_NAME='LTC4307CMS8';
      PHYS_DES_PREFIX='U';
      PART_NUMBER='AL004307000';
      JEDEC_TYPE='MSOP8';
      DESCRIPTION='IC OTHER(8P) LTC4307CMS8#TRPBF(MSOP)';
      MANUFTR='LIN';
      MANUF_PN='LTC4307CMS8#TRPBF';
      RD_CMPLS_LVL='';
      CMPLS_LVL='EP_Tmp';
      FROM_PJ='LU1-EASON';
      DIP_SMD='';
      DATA='LIN_LTC4307.pdf';
      EE_CHECK_LIST='';
      FP_ECN='';
      PSL='';
      LIFECYCLE='';
      CREATOR='';
      STANDARD='';
      CREATEDAY='20111202';
      STATUS='';
      PARENT_PART_TYPE='LTC4307CMS8';
      PARENT_PPT='LTC4307CMS8';
      PARENT_PPT_PART='LTC4307CMS8-LTC4307CMS8,SMLF,EMPTY,AL004307000';
  end_body;
end_primitive;
primitive 'LTC4307CMS8-LTC4307CMS8,SMLF,IC,AL004307000';
  pin
    'ENABLE':
      PIN_NUMBER='(1)';
      INPUT_LOAD='(-0.01,0.01)';
      PINUSE='IN';
    'SCL_IN':
      PIN_NUMBER='(3)';
      INPUT_LOAD='(-0.01,0.01)';
      OUTPUT_LOAD='(1.0,-1.0)';
      BIDIRECTIONAL='TRUE';
      PINUSE='BI';
    'SDA_IN':
      PIN_NUMBER='(6)';
      INPUT_LOAD='(-0.01,0.01)';
      OUTPUT_LOAD='(1.0,-1.0)';
      BIDIRECTIONAL='TRUE';
      PINUSE='BI';
    'SCL_OUT':
      PIN_NUMBER='(2)';
      INPUT_LOAD='(-0.01,0.01)';
      OUTPUT_LOAD='(1.0,-1.0)';
      BIDIRECTIONAL='TRUE';
      PINUSE='BI';
    'SDA_OUT':
      PIN_NUMBER='(7)';
      INPUT_LOAD='(-0.01,0.01)';
      OUTPUT_LOAD='(1.0,-1.0)';
      BIDIRECTIONAL='TRUE';
      PINUSE='BI';
    'READY':
      PIN_NUMBER='(5)';
      OUTPUT_LOAD='(1.0,-1.0)';
      PINUSE='OUT';
    'GND':
      PIN_NUMBER='(4)';
      PINUSE='POWER';
    'VCC':
      PIN_NUMBER='(8)';
      PINUSE='POWER';
  end_pin;
  body
      CLASS='IC';
      PART_NAME='LTC4307CMS8';
      PHYS_DES_PREFIX='U';
      PART_NUMBER='AL004307000';
      JEDEC_TYPE='MSOP8';
      DESCRIPTION='IC OTHER(8P) LTC4307CMS8#TRPBF(MSOP)';
      MANUFTR='LIN';
      MANUF_PN='LTC4307CMS8#TRPBF';
      RD_CMPLS_LVL='';
      CMPLS_LVL='EP_Tmp';
      FROM_PJ='LU1-EASON';
      DIP_SMD='';
      DATA='LIN_LTC4307.pdf';
      EE_CHECK_LIST='';
      FP_ECN='';
      PSL='';
      LIFECYCLE='';
      CREATOR='';
      STANDARD='';
      CREATEDAY='20111202';
      STATUS='';
      PARENT_PART_TYPE='LTC4307CMS8';
      PARENT_PPT='LTC4307CMS8';
      PARENT_PPT_PART='LTC4307CMS8-LTC4307CMS8,SMLF,IC,AL004307000';
  end_body;
end_primitive;
primitive 'M24128BWMN6TP-M24128-BWMN6TP,SMLF,IC,AKE30Z00613';
  pin
    'VCC':
      PIN_NUMBER='(8)';
      PINUSE='POWER';
      NO_LOAD_CHECK='Both';
      NO_IO_CHECK='Both';
      NO_ASSERT_CHECK='TRUE';
      NO_DIR_CHECK='TRUE';
      ALLOW_CONNECT='TRUE';
    'WC#':
      PIN_NUMBER='(7)';
      INPUT_LOAD='(-0.01,0.01)';
      PINUSE='IN';
    'SCL':
      PIN_NUMBER='(6)';
      INPUT_LOAD='(-0.01,0.01)';
      PINUSE='IN';
    'SDA':
      PIN_NUMBER='(5)';
      BIDIRECTIONAL='TRUE';
      INPUT_LOAD='(-0.01,0.01)';
      OUTPUT_LOAD='(1.0,-1.0)';
      PINUSE='BI';
    'VSS':
      PIN_NUMBER='(4)';
      PINUSE='POWER';
      NO_LOAD_CHECK='Both';
      NO_IO_CHECK='Both';
      NO_ASSERT_CHECK='TRUE';
      NO_DIR_CHECK='TRUE';
      ALLOW_CONNECT='TRUE';
    'E2':
      PIN_NUMBER='(3)';
      INPUT_LOAD='(-0.01,0.01)';
      PINUSE='IN';
    'E1':
      PIN_NUMBER='(2)';
      INPUT_LOAD='(-0.01,0.01)';
      PINUSE='IN';
    'E0':
      PIN_NUMBER='(1)';
      INPUT_LOAD='(-0.01,0.01)';
      PINUSE='IN';
  end_pin;
  body
      PART_NAME='M24128BWMN6TP';
      BODY_NAME='M24128BWMN6TP';
      PHYS_DES_PREFIX='U';
      CLASS='IC';
      STANDARD='';
      LIFECYCLE='';
      PART_NUMBER='AKE30Z00613';
      JEDEC_TYPE='SOIC8XH';
      DESCRIPTION='IC(8P) EEPROM M24128-BWMN6TP(SO8)';
      MANUFTR='SGT';
      MANUF_PN='M24128-BWMN6TP';
      RD_CMPLS_LVL='EP(V1)';
      CMPLS_LVL='EP(V1)';
      FROM_PJ='S2D-TERRY';
      DIP_SMD='';
      DATA='SGT_M24256-B_M24128-B.pdf';
      EE_CHECK_LIST='';
      FP_ECN='';
      PSL='';
      CREATOR='';
      STATUS='';
      MSD='';
      ESD_CDM='';
      ESD_HBM='';
      ESD_MM='';
      PIN_LENGTH_SHORT_PIN='';
      PIN_LENGTH_LONG_PIN='';
      CREATEDAY='20200318';
      PARENT_PART_TYPE='M24128BWMN6TP';
      PARENT_PPT='M24128BWMN6TP';
      PARENT_PPT_PART='M24128BWMN6TP-M24128-BWMN6TP,SMLF,IC,AKE30Z00613';
  end_body;
end_primitive;
primitive 'M24M02DRMN6TP-M24M02-DRMN6TP,SMLF,IC,AKE33Z00600';
  pin
    'VCC':
      PIN_NUMBER='(8)';
      PINUSE='POWER';
      NO_LOAD_CHECK='Both';
      NO_IO_CHECK='Both';
      NO_ASSERT_CHECK='TRUE';
      NO_DIR_CHECK='TRUE';
      ALLOW_CONNECT='TRUE';
    'WC_N':
      PIN_NUMBER='(7)';
      INPUT_LOAD='(-0.01,0.01)';
      PINUSE='IN';
    'SCL':
      PIN_NUMBER='(6)';
      INPUT_LOAD='(-0.01,0.01)';
      PINUSE='IN';
    'SDA':
      PIN_NUMBER='(5)';
      BIDIRECTIONAL='TRUE';
      INPUT_LOAD='(-0.01,0.01)';
      OUTPUT_LOAD='(1.0,-1.0)';
      PINUSE='BI';
    'VSS':
      PIN_NUMBER='(4)';
      PINUSE='POWER';
      NO_LOAD_CHECK='Both';
      NO_IO_CHECK='Both';
      NO_ASSERT_CHECK='TRUE';
      NO_DIR_CHECK='TRUE';
      ALLOW_CONNECT='TRUE';
    'E2':
      PIN_NUMBER='(3)';
      INPUT_LOAD='(-0.01,0.01)';
      PINUSE='IN';
    'DU2':
      PIN_NUMBER='(2)';
      INPUT_LOAD='(-0.01,0.01)';
      PINUSE='IN';
    'DU1':
      PIN_NUMBER='(1)';
      INPUT_LOAD='(-0.01,0.01)';
      PINUSE='IN';
  end_pin;
  body
      PART_NAME='M24M02DRMN6TP';
      BODY_NAME='M24M02DRMN6TP';
      PHYS_DES_PREFIX='U';
      CLASS='IC';
      STANDARD='';
      LIFECYCLE='';
      PART_NUMBER='AKE33Z00600';
      JEDEC_TYPE='SOIC8XH';
      DESCRIPTION='IC EEPROM(8P)M24M02-DRMN6TP(SO)';
      MANUFTR='SGT';
      MANUF_PN='M24M02-DRMN6TP';
      RD_CMPLS_LVL='EP(V1)';
      CMPLS_LVL='';
      FROM_PJ='S5S-YVETTE';
      DIP_SMD='';
      DATA='SGT_M24M02-DRMN6TP_v7.pdf';
      EE_CHECK_LIST='';
      FP_ECN='M24M02-DRMN6TP.pdf';
      PSL='';
      CREATOR='';
      STATUS='';
      MSD='';
      ESD_CDM='';
      ESD_HBM='';
      ESD_MM='';
      PIN_LENGTH_SHORT_PIN='';
      PIN_LENGTH_LONG_PIN='';
      CREATEDAY='20161220';
      PARENT_PART_TYPE='M24M02DRMN6TP';
      PARENT_PPT='M24M02DRMN6TP';
      PARENT_PPT_PART='M24M02DRMN6TP-M24M02-DRMN6TP,SMLF,IC,AKE33Z00600';
  end_body;
end_primitive;
primitive 'MAX11617EEET-MAX11617EEE+T,SMLF,EMPTY,AL011617W00';
  pin
    'AIN11||REF':
      PIN_NUMBER='(1)';
      BIDIRECTIONAL='TRUE';
      INPUT_LOAD='(-0.01,0.01)';
      OUTPUT_LOAD='(1.0,-1.0)';
      PINUSE='BI';
    'AIN10':
      PIN_NUMBER='(2)';
      BIDIRECTIONAL='TRUE';
      INPUT_LOAD='(-0.01,0.01)';
      OUTPUT_LOAD='(1.0,-1.0)';
      PINUSE='BI';
    'AIN9':
      PIN_NUMBER='(3)';
      BIDIRECTIONAL='TRUE';
      INPUT_LOAD='(-0.01,0.01)';
      OUTPUT_LOAD='(1.0,-1.0)';
      PINUSE='BI';
    'AIN8':
      PIN_NUMBER='(4)';
      BIDIRECTIONAL='TRUE';
      INPUT_LOAD='(-0.01,0.01)';
      OUTPUT_LOAD='(1.0,-1.0)';
      PINUSE='BI';
    'AIN0':
      PIN_NUMBER='(5)';
      BIDIRECTIONAL='TRUE';
      INPUT_LOAD='(-0.01,0.01)';
      OUTPUT_LOAD='(1.0,-1.0)';
      PINUSE='BI';
    'AIN1':
      PIN_NUMBER='(6)';
      BIDIRECTIONAL='TRUE';
      INPUT_LOAD='(-0.01,0.01)';
      OUTPUT_LOAD='(1.0,-1.0)';
      PINUSE='BI';
    'AIN2':
      PIN_NUMBER='(7)';
      BIDIRECTIONAL='TRUE';
      INPUT_LOAD='(-0.01,0.01)';
      OUTPUT_LOAD='(1.0,-1.0)';
      PINUSE='BI';
    'AIN3':
      PIN_NUMBER='(8)';
      BIDIRECTIONAL='TRUE';
      INPUT_LOAD='(-0.01,0.01)';
      OUTPUT_LOAD='(1.0,-1.0)';
      PINUSE='BI';
    'AIN4':
      PIN_NUMBER='(9)';
      BIDIRECTIONAL='TRUE';
      INPUT_LOAD='(-0.01,0.01)';
      OUTPUT_LOAD='(1.0,-1.0)';
      PINUSE='BI';
    'AIN5':
      PIN_NUMBER='(10)';
      BIDIRECTIONAL='TRUE';
      INPUT_LOAD='(-0.01,0.01)';
      OUTPUT_LOAD='(1.0,-1.0)';
      PINUSE='BI';
    'AIN6':
      PIN_NUMBER='(11)';
      BIDIRECTIONAL='TRUE';
      INPUT_LOAD='(-0.01,0.01)';
      OUTPUT_LOAD='(1.0,-1.0)';
      PINUSE='BI';
    'AIN7':
      PIN_NUMBER='(12)';
      BIDIRECTIONAL='TRUE';
      INPUT_LOAD='(-0.01,0.01)';
      OUTPUT_LOAD='(1.0,-1.0)';
      PINUSE='BI';
    'SCL':
      PIN_NUMBER='(13)';
      BIDIRECTIONAL='TRUE';
      INPUT_LOAD='(-0.01,0.01)';
      OUTPUT_LOAD='(1.0,-1.0)';
      PINUSE='BI';
    'SDA':
      PIN_NUMBER='(14)';
      BIDIRECTIONAL='TRUE';
      INPUT_LOAD='(-0.01,0.01)';
      OUTPUT_LOAD='(1.0,-1.0)';
      PINUSE='BI';
    'GND':
      PIN_NUMBER='(15)';
      PINUSE='POWER';
      NO_LOAD_CHECK='Both';
      NO_IO_CHECK='Both';
      NO_ASSERT_CHECK='TRUE';
      NO_DIR_CHECK='TRUE';
      ALLOW_CONNECT='TRUE';
    'VDD':
      PIN_NUMBER='(16)';
      PINUSE='POWER';
      NO_LOAD_CHECK='Both';
      NO_IO_CHECK='Both';
      NO_ASSERT_CHECK='TRUE';
      NO_DIR_CHECK='TRUE';
      ALLOW_CONNECT='TRUE';
  end_pin;
  body
      PART_NAME='MAX11617EEET';
      BODY_NAME='MAX11617EEET';
      PHYS_DES_PREFIX='U';
      CLASS='IC';
      STANDARD='';
      LIFECYCLE='';
      PART_NUMBER='AL011617W00';
      JEDEC_TYPE='QSOP16_0-635_4-9X3-89';
      DESCRIPTION='IC CTRL(16P)MAX11617EEE+T QSOP';
      MANUFTR='MAM';
      MANUF_PN='MAX11617EEE+T';
      RD_CMPLS_LVL='EP(V1)';
      CMPLS_LVL='EP(V1)';
      FROM_PJ='F0CE-JAMES';
      DIP_SMD='';
      DATA='MAM_MAX11617EEE+T.pdf';
      EE_CHECK_LIST='';
      FP_ECN='MAX11617EEE+T.msg';
      PSL='';
      CREATOR='';
      STATUS='';
      MSD='';
      ESD_CDM='';
      ESD_HBM='';
      ESD_MM='';
      PIN_LENGTH_SHORT_PIN='0 MILS';
      PIN_LENGTH_LONG_PIN='0 MILS';
      CREATEDAY='20210528';
      PARENT_PART_TYPE='MAX11617EEET';
      PARENT_PPT='MAX11617EEET';
      PARENT_PPT_PART='MAX11617EEET-MAX11617EEE+T,SMLF,EMPTY,AL011617W00';
  end_body;
end_primitive;
primitive 'MAX15090BEWIT-MAX15090BEWI+T,SMLF,IC,AL015080B00';
  pin
    'VCC':
      PIN_NUMBER='(A2)';
      PINUSE='POWER';
      NO_LOAD_CHECK='Both';
      NO_IO_CHECK='Both';
      NO_ASSERT_CHECK='TRUE';
      NO_DIR_CHECK='TRUE';
      ALLOW_CONNECT='TRUE';
    'IN_A3':
      PIN_NUMBER='(A3)';
      INPUT_LOAD='(-0.01,0.01)';
      PINUSE='IN';
    'IN_A5':
      PIN_NUMBER='(A5)';
      INPUT_LOAD='(-0.01,0.01)';
      PINUSE='IN';
    'IN_B3':
      PIN_NUMBER='(B3)';
      INPUT_LOAD='(-0.01,0.01)';
      PINUSE='IN';
    'IN_B5':
      PIN_NUMBER='(B5)';
      INPUT_LOAD='(-0.01,0.01)';
      PINUSE='IN';
    'IN_C3':
      PIN_NUMBER='(C3)';
      INPUT_LOAD='(-0.01,0.01)';
      PINUSE='IN';
    'IN_C5':
      PIN_NUMBER='(C5)';
      INPUT_LOAD='(-0.01,0.01)';
      PINUSE='IN';
    'IN_D5':
      PIN_NUMBER='(D5)';
      INPUT_LOAD='(-0.01,0.01)';
      PINUSE='IN';
    'CB':
      PIN_NUMBER='(B1)';
      BIDIRECTIONAL='TRUE';
      INPUT_LOAD='(-0.01,0.01)';
      OUTPUT_LOAD='(1.0,-1.0)';
      PINUSE='BI';
    'EN#':
      PIN_NUMBER='(B7)';
      INPUT_LOAD='(-0.01,0.01)';
      PINUSE='IN';
    'REG':
      PIN_NUMBER='(D1)';
      OUTPUT_LOAD='(1.0,-1.0)';
      PINUSE='OUT';
    'UV':
      PIN_NUMBER='(D2)';
      INPUT_LOAD='(-0.01,0.01)';
      PINUSE='IN';
    'OV':
      PIN_NUMBER='(D3)';
      INPUT_LOAD='(-0.01,0.01)';
      PINUSE='IN';
    'ISENSE':
      PIN_NUMBER='(A1)';
      OUTPUT_LOAD='(1.0,-1.0)';
      PINUSE='OUT';
    'OUT_A4':
      PIN_NUMBER='(A4)';
      OUTPUT_LOAD='(1.0,-1.0)';
      PINUSE='OUT';
    'OUT_B4':
      PIN_NUMBER='(B4)';
      OUTPUT_LOAD='(1.0,-1.0)';
      PINUSE='OUT';
    'OUT_B6':
      PIN_NUMBER='(B6)';
      OUTPUT_LOAD='(1.0,-1.0)';
      PINUSE='OUT';
    'OUT_C4':
      PIN_NUMBER='(C4)';
      OUTPUT_LOAD='(1.0,-1.0)';
      PINUSE='OUT';
    'OUT_C6':
      PIN_NUMBER='(C6)';
      OUTPUT_LOAD='(1.0,-1.0)';
      PINUSE='OUT';
    'OUT_D4':
      PIN_NUMBER='(D4)';
      OUTPUT_LOAD='(1.0,-1.0)';
      PINUSE='OUT';
    'OUT_D6':
      PIN_NUMBER='(D6)';
      OUTPUT_LOAD='(1.0,-1.0)';
      PINUSE='OUT';
    'GATE':
      PIN_NUMBER='(A6)';
      BIDIRECTIONAL='TRUE';
      INPUT_LOAD='(-0.01,0.01)';
      OUTPUT_LOAD='(1.0,-1.0)';
      PINUSE='BI';
    'CDLY':
      PIN_NUMBER='(A7)';
      INPUT_LOAD='(-0.01,0.01)';
      PINUSE='IN';
    'GND_B2':
      PIN_NUMBER='(B2)';
      PINUSE='POWER';
      NO_LOAD_CHECK='Both';
      NO_IO_CHECK='Both';
      NO_ASSERT_CHECK='TRUE';
      NO_DIR_CHECK='TRUE';
      ALLOW_CONNECT='TRUE';
    'GND_C1':
      PIN_NUMBER='(C1)';
      PINUSE='POWER';
      NO_LOAD_CHECK='Both';
      NO_IO_CHECK='Both';
      NO_ASSERT_CHECK='TRUE';
      NO_DIR_CHECK='TRUE';
      ALLOW_CONNECT='TRUE';
    'GND_C2':
      PIN_NUMBER='(C2)';
      PINUSE='POWER';
      NO_LOAD_CHECK='Both';
      NO_IO_CHECK='Both';
      NO_ASSERT_CHECK='TRUE';
      NO_DIR_CHECK='TRUE';
      ALLOW_CONNECT='TRUE';
    'FAULT#':
      PIN_NUMBER='(C7)';
      OUTPUT_LOAD='(1.0,-1.0)';
      PINUSE='OUT';
    'PG':
      PIN_NUMBER='(D7)';
      OUTPUT_LOAD='(1.0,-1.0)';
      PINUSE='OUT';
  end_pin;
  body
      PART_NAME='MAX15090BEWIT';
      BODY_NAME='MAX15090BEWIT';
      PHYS_DES_PREFIX='U';
      CLASS='IC';
      STANDARD='';
      LIFECYCLE='';
      PART_NUMBER='AL015080B00';
      JEDEC_TYPE='BGA28_0-5_3-525X2-065';
      DESCRIPTION='IC OTHER(28P)MAX15090BEWI+T(WLP)';
      MANUFTR='MAM';
      MANUF_PN='MAX15090BEWI+T';
      RD_CMPLS_LVL='EP(V1)';
      CMPLS_LVL='';
      FROM_PJ='UH3M-KEVIN';
      DIP_SMD='';
      DATA='MAM_MAX15090BEWI+T.pdf';
      EE_CHECK_LIST='';
      FP_ECN='';
      PSL='';
      CREATOR='';
      STATUS='';
      MSD='';
      ESD_CDM='';
      ESD_HBM='';
      ESD_MM='';
      PIN_LENGTH_SHORT_PIN='';
      PIN_LENGTH_LONG_PIN='';
      CREATEDAY='20160324';
      PARENT_PART_TYPE='MAX15090BEWIT';
      PARENT_PPT='MAX15090BEWIT';
      PARENT_PPT_PART='MAX15090BEWIT-MAX15090BEWI+T,SMLF,IC,AL015080B00';
  end_body;
end_primitive;
primitive 'METR3904G-METR3904-G,SMLF,IC,BA039040020';
  pin
    '1':
      PIN_NUMBER='(B)';
      INPUT_LOAD='(-0.01,0.01)';
      PINUSE='IN';
    '2':
      PIN_NUMBER='(E)';
      INPUT_LOAD='(-0.01,0.01)';
      OUTPUT_LOAD='(1.0,-1.0)';
      BIDIRECTIONAL='TRUE';
      PINUSE='BI';
    '3':
      PIN_NUMBER='(C)';
      INPUT_LOAD='(-0.01,0.01)';
      OUTPUT_LOAD='(1.0,-1.0)';
      BIDIRECTIONAL='TRUE';
      PINUSE='BI';
  end_pin;
  body
      CLASS='IC';
      PART_NAME='METR3904G';
      PHYS_DES_PREFIX='Q';
      PART_NUMBER='BA039040020';
      JEDEC_TYPE='SOT23_BEC';
      DESCRIPTION='TRANS SMD METR3904-G(40V,200MA,0.225W)';
      MANUFTR='MKP';
      MANUF_PN='METR3904-G';
      RD_CMPLS_LVL='EP(V1)';
      CMPLS_LVL='EP(V1)';
      DIP_SMD='';
      FP_ECN='';
      FROM_PJ='TU1D-MICHAEL';
      DATA='METR3904-G.pdf';
      EE_CHECK_LIST='';
      STANDARD='';
      PSL='';
      PREFERENCE='';
      LIFECYCLE='';
      CREATOR='';
      CREATEDAY='20111020';
      STATUS='';
      PARENT_PART_TYPE='METR3904G';
      PARENT_PPT='METR3904G';
      PARENT_PPT_PART='METR3904G-METR3904-G,SMLF,IC,BA039040020';
  end_body;
end_primitive;
primitive 'MOSFET_DUAL_6P-2N7002KDW,SMLF,IC,BAM70020047';
  pin
    'G1':
      PIN_NUMBER='(2)';
      BIDIRECTIONAL='TRUE';
      INPUT_LOAD='(-0.01,0.01)';
      OUTPUT_LOAD='(1.0,-1.0)';
      PINUSE='BI';
    'G2':
      PIN_NUMBER='(5)';
      BIDIRECTIONAL='TRUE';
      INPUT_LOAD='(-0.01,0.01)';
      OUTPUT_LOAD='(1.0,-1.0)';
      PINUSE='BI';
    'S1':
      PIN_NUMBER='(1)';
      BIDIRECTIONAL='TRUE';
      INPUT_LOAD='(-0.01,0.01)';
      OUTPUT_LOAD='(1.0,-1.0)';
      PINUSE='BI';
    'S2':
      PIN_NUMBER='(4)';
      BIDIRECTIONAL='TRUE';
      INPUT_LOAD='(-0.01,0.01)';
      OUTPUT_LOAD='(1.0,-1.0)';
      PINUSE='BI';
    'D1':
      PIN_NUMBER='(6)';
      BIDIRECTIONAL='TRUE';
      INPUT_LOAD='(-0.01,0.01)';
      OUTPUT_LOAD='(1.0,-1.0)';
      PINUSE='BI';
    'D2':
      PIN_NUMBER='(3)';
      BIDIRECTIONAL='TRUE';
      INPUT_LOAD='(-0.01,0.01)';
      OUTPUT_LOAD='(1.0,-1.0)';
      PINUSE='BI';
  end_pin;
  body
      PART_NAME='MOSFET_DUAL_6P';
      BODY_NAME='MOSFET_DUAL_6P';
      PHYS_DES_PREFIX='Q';
      CLASS='IC';
      STANDARD='';
      LIFECYCLE='';
      PART_NUMBER='BAM70020047';
      JEDEC_TYPE='SOT363XD';
      DESCRIPTION='TRANS MOS 2N7002KDW(60V115MA,0.2W)SOT363';
      MANUFTR='PJT';
      MANUF_PN='2N7002KDW';
      RD_CMPLS_LVL='EP(V1)';
      CMPLS_LVL='EP(V1)';
      DIP_SMD='';
      FP_ECN='';
      FROM_PJ='F06S-KENG-YU';
      DATA='PJT_2N7002KDW.pdf';
      EE_CHECK_LIST='';
      STATUS='';
      PSL='';
      PREFERENCE='';
      CREATOR='';
      CREATEDAY='20140113';
      PARENT_PART_TYPE='MOSFET_DUAL_6P';
      PARENT_PPT='MOSFET_DUAL_6P';
      PARENT_PPT_PART='MOSFET_DUAL_6P-2N7002KDW,SMLF,IC,BAM70020047';
  end_body;
end_primitive;
primitive 'MOSFET_NCH_1D3S-PSMNR58-30YLH,SMLF,EMPTY,BAMNR5800A';
  pin
    '3':
      PIN_NUMBER='(3)';
      BIDIRECTIONAL='TRUE';
      INPUT_LOAD='(-0.01,0.01)';
      OUTPUT_LOAD='(1.0,-1.0)';
      PINUSE='BI';
    '5':
      PIN_NUMBER='(5)';
      BIDIRECTIONAL='TRUE';
      INPUT_LOAD='(-0.01,0.01)';
      OUTPUT_LOAD='(1.0,-1.0)';
      PINUSE='BI';
    '2':
      PIN_NUMBER='(2)';
      BIDIRECTIONAL='TRUE';
      INPUT_LOAD='(-0.01,0.01)';
      OUTPUT_LOAD='(1.0,-1.0)';
      PINUSE='BI';
    '4':
      PIN_NUMBER='(4)';
      INPUT_LOAD='(-0.01,0.01)';
      PINUSE='IN';
    '1':
      PIN_NUMBER='(1)';
      BIDIRECTIONAL='TRUE';
      INPUT_LOAD='(-0.01,0.01)';
      OUTPUT_LOAD='(1.0,-1.0)';
      PINUSE='BI';
  end_pin;
  body
      PART_NAME='MOSFET_NCH_1D3S';
      BODY_NAME='MOSFET_NCH_1D3S';
      JEDEC_TYPE='SOT1023';
      PHYS_DES_PREFIX='PQ';
      CLASS='IC';
      STANDARD='';
      LIFECYCLE='';
      PART_NUMBER='BAMNR580000';
      DESCRIPTION='TRANS MOS PSMNR58-30YLH(30V,380A,333W)';
      MANUFTR='NXE';
      MANUF_PN='PSMNR58-30YLH';
      RD_CMPLS_LVL='EP(V1)';
      CMPLS_LVL='';
      DIP_SMD='';
      FP_ECN='';
      FROM_PJ='S5Z-MIKE';
      DATA='NXE_PSMNR58-30YLH.pdf';
      EE_CHECK_LIST='';
      STATUS='';
      PSL='';
      PREFERENCE='';
      CREATOR='';
      CREATEDAY='20190423';
      PARENT_PART_TYPE='MOSFET_NCH_1D3S';
      PARENT_PPT='MOSFET_NCH_1D3S';
      PARENT_PPT_PART='MOSFET_NCH_1D3S-PSMNR58-30YLH,SMLF,EMPTY,BAMNR580000';
  end_body;
end_primitive;
primitive 'MOSFET_NCH_1D3S-PSMNR58-30YLH,SMLF,IC,BAMNR580000';
  pin
    '3':
      PIN_NUMBER='(3)';
      BIDIRECTIONAL='TRUE';
      INPUT_LOAD='(-0.01,0.01)';
      OUTPUT_LOAD='(1.0,-1.0)';
      PINUSE='BI';
    '5':
      PIN_NUMBER='(5)';
      BIDIRECTIONAL='TRUE';
      INPUT_LOAD='(-0.01,0.01)';
      OUTPUT_LOAD='(1.0,-1.0)';
      PINUSE='BI';
    '2':
      PIN_NUMBER='(2)';
      BIDIRECTIONAL='TRUE';
      INPUT_LOAD='(-0.01,0.01)';
      OUTPUT_LOAD='(1.0,-1.0)';
      PINUSE='BI';
    '4':
      PIN_NUMBER='(4)';
      INPUT_LOAD='(-0.01,0.01)';
      PINUSE='IN';
    '1':
      PIN_NUMBER='(1)';
      BIDIRECTIONAL='TRUE';
      INPUT_LOAD='(-0.01,0.01)';
      OUTPUT_LOAD='(1.0,-1.0)';
      PINUSE='BI';
  end_pin;
  body
      PART_NAME='MOSFET_NCH_1D3S';
      BODY_NAME='MOSFET_NCH_1D3S';
      JEDEC_TYPE='SOT1023';
      PHYS_DES_PREFIX='PQ';
      CLASS='IC';
      STANDARD='';
      LIFECYCLE='';
      PART_NUMBER='BAMNR580000';
      DESCRIPTION='TRANS MOS PSMNR58-30YLH(30V,380A,333W)';
      MANUFTR='NXE';
      MANUF_PN='PSMNR58-30YLH';
      RD_CMPLS_LVL='EP(V1)';
      CMPLS_LVL='';
      DIP_SMD='';
      FP_ECN='';
      FROM_PJ='S5Z-MIKE';
      DATA='NXE_PSMNR58-30YLH.pdf';
      EE_CHECK_LIST='';
      STATUS='';
      PSL='';
      PREFERENCE='';
      CREATOR='';
      CREATEDAY='20190423';
      PARENT_PART_TYPE='MOSFET_NCH_1D3S';
      PARENT_PPT='MOSFET_NCH_1D3S';
      PARENT_PPT_PART='MOSFET_NCH_1D3S-PSMNR58-30YLH,SMLF,IC,BAMNR580000';
  end_body;
end_primitive;
primitive 'MOSFET_NCH_DUAL-PJT138K,SMLF,IC,BAM138K0003';
  pin
    'S1':
      PIN_NUMBER='(1,0)';
      BIDIRECTIONAL='TRUE';
      INPUT_LOAD='(-0.01,0.01)';
      OUTPUT_LOAD='(1.0,-1.0)';
      PINUSE='BI';
    'G1':
      PIN_NUMBER='(2,0)';
      BIDIRECTIONAL='TRUE';
      INPUT_LOAD='(-0.01,0.01)';
      OUTPUT_LOAD='(1.0,-1.0)';
      PINUSE='BI';
    'D1':
      PIN_NUMBER='(6,0)';
      BIDIRECTIONAL='TRUE';
      INPUT_LOAD='(-0.01,0.01)';
      OUTPUT_LOAD='(1.0,-1.0)';
      PINUSE='BI';
    'D2':
      PIN_NUMBER='(0,3)';
      BIDIRECTIONAL='TRUE';
      INPUT_LOAD='(-0.01,0.01)';
      OUTPUT_LOAD='(1.0,-1.0)';
      PINUSE='BI';
    'G2':
      PIN_NUMBER='(0,5)';
      BIDIRECTIONAL='TRUE';
      INPUT_LOAD='(-0.01,0.01)';
      OUTPUT_LOAD='(1.0,-1.0)';
      PINUSE='BI';
    'S2':
      PIN_NUMBER='(0,4)';
      BIDIRECTIONAL='TRUE';
      INPUT_LOAD='(-0.01,0.01)';
      OUTPUT_LOAD='(1.0,-1.0)';
      PINUSE='BI';
  end_pin;
  body
      PART_NAME='MOSFET_NCH_DUAL';
      BODY_NAME='MOSFET_NCH_DUAL';
      PHYS_DES_PREFIX='Q';
      CLASS='IC';
      STANDARD='';
      LIFECYCLE='';
      PART_NUMBER='BAM138K0003';
      JEDEC_TYPE='SOT363XD';
      DESCRIPTION='TRANS MOSFET PJT138K(50V,0.36A,0.236W)';
      MANUFTR='PJT';
      MANUF_PN='PJT138K';
      RD_CMPLS_LVL='EP(V1)';
      CMPLS_LVL='EP(V1)';
      DIP_SMD='';
      FP_ECN='';
      FROM_PJ='F09-MARK';
      DATA='PJT_PJT138K_revJULY-25-2013.pdf';
      EE_CHECK_LIST='';
      PSL='';
      PREFERENCE='';
      CREATOR='';
      CREATEDAY='20160617';
      STATUS='';
      PARENT_PART_TYPE='MOSFET_NCH_DUAL';
      PARENT_PPT='MOSFET_NCH_DUAL';
      PARENT_PPT_PART='MOSFET_NCH_DUAL-PJT138K,SMLF,IC,BAM138K0003';
  end_body;
end_primitive;
primitive 'MOSFET_NCH_GDS_ESD_PROTECTED-2N7002K,SMLF,EMPTY,BAA';
  pin
    'D':
      PIN_NUMBER='(D)';
      BIDIRECTIONAL='TRUE';
      INPUT_LOAD='(-0.01,0.01)';
      OUTPUT_LOAD='(1.0,-1.0)';
      PINUSE='BI';
    'G':
      PIN_NUMBER='(G)';
      INPUT_LOAD='(-0.01,0.01)';
      PINUSE='IN';
    'S':
      PIN_NUMBER='(S)';
      BIDIRECTIONAL='TRUE';
      INPUT_LOAD='(-0.01,0.01)';
      OUTPUT_LOAD='(1.0,-1.0)';
      PINUSE='BI';
  end_pin;
  body
      PART_NAME='MOSFET_NCH_GDS_ESD_PROTECTED';
      BODY_NAME='MOSFET_NCH_GDS_ESD_PROTECTED';
      PHYS_DES_PREFIX='U';
      CLASS='IC';
      STANDARD='';
      LIFECYCLE='';
      PART_NUMBER='BAM70020002';
      JEDEC_TYPE='SOT23_GDSXC';
      DESCRIPTION='TR MOSFET 2N7002K(60V,300MA,0.35W)SOT-23';
      MANUFTR='PJT';
      MANUF_PN='2N7002K';
      RD_CMPLS_LVL='EP(V1)';
      CMPLS_LVL='EP(V1)';
      DIP_SMD='';
      FP_ECN='';
      FROM_PJ='S1F-TONY';
      DATA='PJT_2N7002K.pdf';
      EE_CHECK_LIST='';
      STATUS='';
      PSL='';
      PREFERENCE='';
      CREATOR='';
      CREATEDAY='20140122';
      PARENT_PART_TYPE='MOSFET_NCH_GDS_ESD_PROTECTED';
      PARENT_PPT='MOSFET_NCH_GDS_ESD_PROTECTED';
      PARENT_PPT_PART='MOSFET_NCH_GDS_ESD_PROTECTED-2N7002K,SMLF,EMPTY,BAM70020002';
  end_body;
end_primitive;
primitive 'MOSFET_NCH_GDS_ESD_PROTECTED-2N7002K,SMLF,IC,BAM70A';
  pin
    'D':
      PIN_NUMBER='(D)';
      BIDIRECTIONAL='TRUE';
      INPUT_LOAD='(-0.01,0.01)';
      OUTPUT_LOAD='(1.0,-1.0)';
      PINUSE='BI';
    'G':
      PIN_NUMBER='(G)';
      INPUT_LOAD='(-0.01,0.01)';
      PINUSE='IN';
    'S':
      PIN_NUMBER='(S)';
      BIDIRECTIONAL='TRUE';
      INPUT_LOAD='(-0.01,0.01)';
      OUTPUT_LOAD='(1.0,-1.0)';
      PINUSE='BI';
  end_pin;
  body
      PART_NAME='MOSFET_NCH_GDS_ESD_PROTECTED';
      BODY_NAME='MOSFET_NCH_GDS_ESD_PROTECTED';
      PHYS_DES_PREFIX='U';
      CLASS='IC';
      STANDARD='';
      LIFECYCLE='';
      PART_NUMBER='BAM70020002';
      JEDEC_TYPE='SOT23_GDSXC';
      DESCRIPTION='TR MOSFET 2N7002K(60V,300MA,0.35W)SOT-23';
      MANUFTR='PJT';
      MANUF_PN='2N7002K';
      RD_CMPLS_LVL='EP(V1)';
      CMPLS_LVL='EP(V1)';
      DIP_SMD='';
      FP_ECN='';
      FROM_PJ='S1F-TONY';
      DATA='PJT_2N7002K.pdf';
      EE_CHECK_LIST='';
      STATUS='';
      PSL='';
      PREFERENCE='';
      CREATOR='';
      CREATEDAY='20140122';
      PARENT_PART_TYPE='MOSFET_NCH_GDS_ESD_PROTECTED';
      PARENT_PPT='MOSFET_NCH_GDS_ESD_PROTECTED';
      PARENT_PPT_PART='MOSFET_NCH_GDS_ESD_PROTECTED-2N7002K,SMLF,IC,BAM70020002';
  end_body;
end_primitive;
primitive 'MOSFET_N_GSD-NX138BK,SMLF,IC,BAM01380023';
  pin
    'GATE':
      PIN_NUMBER='(G)';
      INPUT_LOAD='(-0.01,0.01)';
      PINUSE='IN';
    'SOURCE':
      PIN_NUMBER='(S)';
      BIDIRECTIONAL='TRUE';
      INPUT_LOAD='(-0.01,0.01)';
      OUTPUT_LOAD='(1.0,-1.0)';
      PINUSE='BI';
    'DRAIN':
      PIN_NUMBER='(D)';
      BIDIRECTIONAL='TRUE';
      INPUT_LOAD='(-0.01,0.01)';
      OUTPUT_LOAD='(1.0,-1.0)';
      PINUSE='BI';
  end_pin;
  body
      PART_NAME='MOSFET_N_GSD';
      BODY_NAME='MOSFET_N_GSD';
      PHYS_DES_PREFIX='Q';
      CLASS='IC';
      STANDARD='';
      LIFECYCLE='';
      PART_NUMBER='BAM01380023';
      JEDEC_TYPE='SOT23_GDSXE';
      DESCRIPTION='TRANS MOS NX138BK(60V,265MA,310MW)';
      MANUFTR='NXP';
      MANUF_PN='NX138BK';
      RD_CMPLS_LVL='EP(V1)';
      CMPLS_LVL='';
      DIP_SMD='';
      FP_ECN='';
      FROM_PJ='T2H-CF';
      DATA='NXP_NX138BK.pdf';
      EE_CHECK_LIST='';
      PSL='';
      PREFERENCE='';
      CREATOR='';
      CREATEDAY='20160322';
      STATUS='';
      PARENT_PART_TYPE='MOSFET_N_GSD';
      PARENT_PPT='MOSFET_N_GSD';
      PARENT_PPT_PART='MOSFET_N_GSD-NX138BK,SMLF,IC,BAM01380023';
  end_body;
end_primitive;
primitive 'MOSFET_N_SMLF-BSS138K,BSS138K,EMPTY,BAM138K0000';
  pin
    'GATE':
      PIN_NUMBER='(G)';
      INPUT_LOAD='(-0.01,0.01)';
      PINUSE='IN';
    'DRAIN':
      PIN_NUMBER='(D)';
      OUTPUT_LOAD='(1.0,-1.0)';
      PINUSE='OUT';
    'SOURCE':
      PIN_NUMBER='(S)';
      INPUT_LOAD='(-0.01,0.01)';
      OUTPUT_LOAD='(1.0,-1.0)';
      BIDIRECTIONAL='TRUE';
      PINUSE='BI';
  end_pin;
  body
      PHYS_DES_PREFIX='U';
      CLASS='IO';
      PART_NAME='MOSFET_N';
      BODY_NAME='MOSFET_N';
      STANDARD='End of Design';
      LIFECYCLE='Comp-Approve';
      PART_NUMBER='BAM138K0000';
      JEDEC_TYPE='SOT23_GDSXD';
      DESCRIPTION='TRANS MOS BSS138K(50V,0.22A,0.35W)';
      COMPONENT_TYPE='SMALLSMT';
      LEAD_LENGTH='';
      LPID='';
      DAY='20150826';
      PARENT_PART_TYPE='MOSFET_N';
      PARENT_PPT='MOSFET_N';
      PARENT_PPT_PART='MOSFET_N_SMLF-BSS138K,BSS138K,EMPTY,BAM138K0000';
  end_body;
end_primitive;
primitive 'MOSFET_N_SMLF-BSS138K,BSS138K,IC,BAM138K0000';
  pin
    'GATE':
      PIN_NUMBER='(G)';
      INPUT_LOAD='(-0.01,0.01)';
      PINUSE='IN';
    'DRAIN':
      PIN_NUMBER='(D)';
      OUTPUT_LOAD='(1.0,-1.0)';
      PINUSE='OUT';
    'SOURCE':
      PIN_NUMBER='(S)';
      INPUT_LOAD='(-0.01,0.01)';
      OUTPUT_LOAD='(1.0,-1.0)';
      BIDIRECTIONAL='TRUE';
      PINUSE='BI';
  end_pin;
  body
      PHYS_DES_PREFIX='U';
      CLASS='IC';
      PART_NAME='MOSFET_N';
      BODY_NAME='MOSFET_N';
      STANDARD='End of Design';
      LIFECYCLE='Comp-Approve';
      PART_NUMBER='BAM138K0000';
      JEDEC_TYPE='SOT23_GDSXD';
      DESCRIPTION='TRANS MOS BSS138K(50V,0.22A,0.35W)';
      COMPONENT_TYPE='SMALLSMT';
      LEAD_LENGTH='';
      LPID='';
      DAY='20150826';
      PARENT_PART_TYPE='MOSFET_N';
      PARENT_PPT='MOSFET_N';
      PARENT_PPT_PART='MOSFET_N_SMLF-BSS138K,BSS138K,IC,BAM138K0000';
  end_body;
end_primitive;
primitive 'MOSFET_PCH_GDS_ESD_PROTECTED-DMP2035U-7,SMLF,EMPTYA';
  pin
    'D':
      PIN_NUMBER='(D)';
      BIDIRECTIONAL='TRUE';
      INPUT_LOAD='(-0.01,0.01)';
      OUTPUT_LOAD='(1.0,-1.0)';
      PINUSE='BI';
    'G':
      PIN_NUMBER='(G)';
      INPUT_LOAD='(-0.01,0.01)';
      PINUSE='IN';
    'S':
      PIN_NUMBER='(S)';
      BIDIRECTIONAL='TRUE';
      INPUT_LOAD='(-0.01,0.01)';
      OUTPUT_LOAD='(1.0,-1.0)';
      PINUSE='BI';
  end_pin;
  body
      PART_NAME='MOSFET_PCH_GDS_ESD_PROTECTED';
      BODY_NAME='MOSFET_PCH_GDS_ESD_PROTECTED';
      PHYS_DES_PREFIX='Q';
      CLASS='IC';
      STANDARD='';
      LIFECYCLE='';
      PART_NUMBER='BAM20350002';
      JEDEC_TYPE='SOT23_GDSXC';
      DESCRIPTION='TRANS MOS DMP2035U-7(-20V,-4.9A,0.81W)';
      MANUFTR='DDS';
      MANUF_PN='DMP2035U-7';
      RD_CMPLS_LVL='EP(V1)';
      CMPLS_LVL='';
      DIP_SMD='';
      FP_ECN='';
      FROM_PJ='JG7-ALLEN';
      DATA='DDS_DMP2045U-7.pdf';
      EE_CHECK_LIST='';
      STATUS='';
      PSL='';
      PREFERENCE='';
      CREATOR='';
      CREATEDAY='20200902';
      PARENT_PART_TYPE='MOSFET_PCH_GDS_ESD_PROTECTED';
      PARENT_PPT='MOSFET_PCH_GDS_ESD_PROTECTED';
      PARENT_PPT_PART='MOSFET_PCH_GDS_ESD_PROTECTED-DMP2035U-7,SMLF,EMPTY,BAM20350002';
  end_body;
end_primitive;
primitive 'MOSFET_PCH_GDS_ESD_PROTECTED-PJA3415AE,SMLF,IC,BAMA';
  pin
    'D':
      PIN_NUMBER='(D)';
      BIDIRECTIONAL='TRUE';
      INPUT_LOAD='(-0.01,0.01)';
      OUTPUT_LOAD='(1.0,-1.0)';
      PINUSE='BI';
    'G':
      PIN_NUMBER='(G)';
      INPUT_LOAD='(-0.01,0.01)';
      PINUSE='IN';
    'S':
      PIN_NUMBER='(S)';
      BIDIRECTIONAL='TRUE';
      INPUT_LOAD='(-0.01,0.01)';
      OUTPUT_LOAD='(1.0,-1.0)';
      PINUSE='BI';
  end_pin;
  body
      PART_NAME='MOSFET_PCH_GDS_ESD_PROTECTED';
      BODY_NAME='MOSFET_PCH_GDS_ESD_PROTECTED';
      PHYS_DES_PREFIX='Q';
      CLASS='IC';
      STANDARD='';
      LIFECYCLE='';
      PART_NUMBER='BAM34150008';
      JEDEC_TYPE='SOT23_GDSXC';
      DESCRIPTION='TRANS MOS PJA3415AE(-20V,-4.3A,1.25W)';
      MANUFTR='PJT';
      MANUF_PN='PJA3415AE';
      RD_CMPLS_LVL='EP(V1)';
      CMPLS_LVL='EP(V1)';
      DIP_SMD='';
      FP_ECN='';
      FROM_PJ='S5X-BRIAN';
      DATA='PJT_PJA3415AE.pdf';
      EE_CHECK_LIST='';
      STATUS='';
      PSL='';
      PREFERENCE='';
      CREATOR='';
      CREATEDAY='20190314';
      PARENT_PART_TYPE='MOSFET_PCH_GDS_ESD_PROTECTED';
      PARENT_PPT='MOSFET_PCH_GDS_ESD_PROTECTED';
      PARENT_PPT_PART='MOSFET_PCH_GDS_ESD_PROTECTED-PJA3415AE,SMLF,IC,BAM34150008';
  end_body;
end_primitive;
primitive 'MP5016GQHLZ-MP5016GQH-L-Z,SMLF,IC,AL005016007';
  pin
    'EN':
      PIN_NUMBER='(9)';
      INPUT_LOAD='(-0.01,0.01)';
      PINUSE='IN';
    'MODE':
      PIN_NUMBER='(5)';
      INPUT_LOAD='(-0.01,0.01)';
      PINUSE='IN';
    'ILIMIT':
      PIN_NUMBER='(4)';
      OUTPUT_LOAD='(1.0,-1.0)';
      PINUSE='OUT';
    'GND':
      PIN_NUMBER='(3)';
      PINUSE='POWER';
      NO_LOAD_CHECK='Both';
      NO_IO_CHECK='Both';
      NO_ASSERT_CHECK='TRUE';
      NO_DIR_CHECK='TRUE';
      ALLOW_CONNECT='TRUE';
    'VCC':
      PIN_NUMBER='(1_2)';
      PINUSE='POWER';
      NO_LOAD_CHECK='Both';
      NO_IO_CHECK='Both';
      NO_ASSERT_CHECK='TRUE';
      NO_DIR_CHECK='TRUE';
      ALLOW_CONNECT='TRUE';
    'DV_DT':
      PIN_NUMBER='(10)';
      OUTPUT_LOAD='(1.0,-1.0)';
      PINUSE='OUT';
    'GATE':
      PIN_NUMBER='(8)';
      OUTPUT_LOAD='(1.0,-1.0)';
      PINUSE='OUT';
    'SOURCE':
      PIN_NUMBER='(6_7)';
      OUTPUT_LOAD='(1.0,-1.0)';
      PINUSE='OUT';
  end_pin;
  body
      PART_NAME='MP5016GQHLZ';
      BODY_NAME='MP5016GQHLZ';
      PHYS_DES_PREFIX='U';
      CLASS='IC';
      STANDARD='';
      LIFECYCLE='';
      PART_NUMBER='AL005016007';
      JEDEC_TYPE='QFN8_2X1-5';
      DESCRIPTION='IC (10P) MP5016GQH-L-Z(QFN)';
      MANUFTR='MPS';
      MANUF_PN='MP5016GQH-L-Z';
      RD_CMPLS_LVL='EP(V1)';
      CMPLS_LVL='EP(V1)';
      FROM_PJ='F0CE-SAM';
      DIP_SMD='';
      DATA='MPS_MP5016GQH-L-Z.pdf';
      EE_CHECK_LIST='';
      FP_ECN='';
      PSL='';
      CREATOR='';
      STATUS='';
      MSD='';
      ESD_CDM='';
      ESD_HBM='';
      ESD_MM='';
      PIN_LENGTH_SHORT_PIN='0 MILS';
      PIN_LENGTH_LONG_PIN='0 MILS';
      CREATEDAY='20210519';
      PARENT_PART_TYPE='MP5016GQHLZ';
      PARENT_PPT='MP5016GQHLZ';
      PARENT_PPT_PART='MP5016GQHLZ-MP5016GQH-L-Z,SMLF,IC,AL005016007';
  end_body;
end_primitive;
primitive 'MP5990GMA1111Z-MP5990GMA-1111-Z,SMLF,IC,AR0F0TP4023';
  pin
    'VOUT3':
      PIN_NUMBER='(29)';
      OUTPUT_LOAD='(1.0,-1.0)';
      PINUSE='OUT';
    'VOUT2':
      PIN_NUMBER='(28)';
      OUTPUT_LOAD='(1.0,-1.0)';
      PINUSE='OUT';
    'VOUT1':
      PIN_NUMBER='(27)';
      OUTPUT_LOAD='(1.0,-1.0)';
      PINUSE='OUT';
    'VIN2':
      PIN_NUMBER='(2)';
      INPUT_LOAD='(-0.01,0.01)';
      PINUSE='IN';
    'EN':
      PIN_NUMBER='(26)';
      INPUT_LOAD='(-0.01,0.01)';
      PINUSE='IN';
    'VIN3':
      PIN_NUMBER='(3)';
      INPUT_LOAD='(-0.01,0.01)';
      PINUSE='IN';
    'VIN4':
      PIN_NUMBER='(4)';
      INPUT_LOAD='(-0.01,0.01)';
      PINUSE='IN';
    'GND1':
      PIN_NUMBER='(18)';
      PINUSE='POWER';
      NO_LOAD_CHECK='Both';
      NO_IO_CHECK='Both';
      NO_ASSERT_CHECK='TRUE';
      NO_DIR_CHECK='TRUE';
      ALLOW_CONNECT='TRUE';
    'SDA':
      PIN_NUMBER='(12)';
      BIDIRECTIONAL='TRUE';
      INPUT_LOAD='(-0.01,0.01)';
      OUTPUT_LOAD='(1.0,-1.0)';
      PINUSE='BI';
    'VIN_UVW#':
      PIN_NUMBER='(14)';
      OUTPUT_LOAD='(1.0,-1.0)';
      PINUSE='OUT';
    'SCL':
      PIN_NUMBER='(11)';
      INPUT_LOAD='(-0.01,0.01)';
      PINUSE='IN';
    'D_OC':
      PIN_NUMBER='(37)';
      OUTPUT_LOAD='(1.0,-1.0)';
      PINUSE='OUT';
    'VOUT5':
      PIN_NUMBER='(31)';
      OUTPUT_LOAD='(1.0,-1.0)';
      PINUSE='OUT';
    'VOUT9':
      PIN_NUMBER='(35)';
      OUTPUT_LOAD='(1.0,-1.0)';
      PINUSE='OUT';
    'ALT#':
      PIN_NUMBER='(10)';
      OUTPUT_LOAD='(1.0,-1.0)';
      PINUSE='OUT';
    'GOK':
      PIN_NUMBER='(39)';
      BIDIRECTIONAL='TRUE';
      INPUT_LOAD='(-0.01,0.01)';
      OUTPUT_LOAD='(1.0,-1.0)';
      PINUSE='BI';
    'VIN7':
      PIN_NUMBER='(7)';
      INPUT_LOAD='(-0.01,0.01)';
      PINUSE='IN';
    'VOUT7':
      PIN_NUMBER='(33)';
      OUTPUT_LOAD='(1.0,-1.0)';
      PINUSE='OUT';
    'MODE':
      PIN_NUMBER='(41)';
      INPUT_LOAD='(-0.01,0.01)';
      PINUSE='IN';
    'VIN8':
      PIN_NUMBER='(8)';
      INPUT_LOAD='(-0.01,0.01)';
      PINUSE='IN';
    'PG||OCW#':
      PIN_NUMBER='(13)';
      OUTPUT_LOAD='(1.0,-1.0)';
      PINUSE='OUT';
    'VOUT8':
      PIN_NUMBER='(34)';
      OUTPUT_LOAD='(1.0,-1.0)';
      PINUSE='OUT';
    'ON':
      PIN_NUMBER='(38)';
      OUTPUT_LOAD='(1.0,-1.0)';
      PINUSE='OUT';
    'VIN5':
      PIN_NUMBER='(5)';
      INPUT_LOAD='(-0.01,0.01)';
      PINUSE='IN';
    'VIN6':
      PIN_NUMBER='(6)';
      INPUT_LOAD='(-0.01,0.01)';
      PINUSE='IN';
    'VTEMP':
      PIN_NUMBER='(15)';
      INPUT_LOAD='(-0.01,0.01)';
      PINUSE='IN';
    'OCREF':
      PIN_NUMBER='(22)';
      OUTPUT_LOAD='(1.0,-1.0)';
      PINUSE='OUT';
    'SCREF_OCWREF':
      PIN_NUMBER='(25)';
      OUTPUT_LOAD='(1.0,-1.0)';
      PINUSE='OUT';
    'SS':
      PIN_NUMBER='(16)';
      OUTPUT_LOAD='(1.0,-1.0)';
      PINUSE='OUT';
    'VOUT6':
      PIN_NUMBER='(32)';
      OUTPUT_LOAD='(1.0,-1.0)';
      PINUSE='OUT';
    'IMON':
      PIN_NUMBER='(21)';
      BIDIRECTIONAL='TRUE';
      INPUT_LOAD='(-0.01,0.01)';
      OUTPUT_LOAD='(1.0,-1.0)';
      PINUSE='BI';
    'CS':
      PIN_NUMBER='(20)';
      OUTPUT_LOAD='(1.0,-1.0)';
      PINUSE='OUT';
    'VIN9':
      PIN_NUMBER='(42)';
      INPUT_LOAD='(-0.01,0.01)';
      PINUSE='IN';
    'VOUT10':
      PIN_NUMBER='(36)';
      OUTPUT_LOAD='(1.0,-1.0)';
      PINUSE='OUT';
    'VOSEN':
      PIN_NUMBER='(24)';
      INPUT_LOAD='(-0.01,0.01)';
      PINUSE='IN';
    'VOUT4':
      PIN_NUMBER='(30)';
      OUTPUT_LOAD='(1.0,-1.0)';
      PINUSE='OUT';
    'VIN1':
      PIN_NUMBER='(1)';
      INPUT_LOAD='(-0.01,0.01)';
      PINUSE='IN';
    'GND2':
      PIN_NUMBER='(44)';
      PINUSE='POWER';
      NO_LOAD_CHECK='Both';
      NO_IO_CHECK='Both';
      NO_ASSERT_CHECK='TRUE';
      NO_DIR_CHECK='TRUE';
      ALLOW_CONNECT='TRUE';
    'FLT_TYPE':
      PIN_NUMBER='(40)';
      INPUT_LOAD='(-0.01,0.01)';
      PINUSE='IN';
    'VIN10':
      PIN_NUMBER='(43)';
      INPUT_LOAD='(-0.01,0.01)';
      PINUSE='IN';
    'VINSEN':
      PIN_NUMBER='(9)';
      INPUT_LOAD='(-0.01,0.01)';
      PINUSE='IN';
    'VDD33_1':
      PIN_NUMBER='(17)';
      PINUSE='POWER';
      NO_LOAD_CHECK='Both';
      NO_IO_CHECK='Both';
      NO_ASSERT_CHECK='TRUE';
      NO_DIR_CHECK='TRUE';
      ALLOW_CONNECT='TRUE';
    'VDD33_2':
      PIN_NUMBER='(45)';
      PINUSE='POWER';
      NO_LOAD_CHECK='Both';
      NO_IO_CHECK='Both';
      NO_ASSERT_CHECK='TRUE';
      NO_DIR_CHECK='TRUE';
      ALLOW_CONNECT='TRUE';
    'VDD18':
      PIN_NUMBER='(19)';
      PINUSE='POWER';
      NO_LOAD_CHECK='Both';
      NO_IO_CHECK='Both';
      NO_ASSERT_CHECK='TRUE';
      NO_DIR_CHECK='TRUE';
      ALLOW_CONNECT='TRUE';
    'ADDR':
      PIN_NUMBER='(23)';
      INPUT_LOAD='(-0.01,0.01)';
      PINUSE='IN';
  end_pin;
  body
      PART_NAME='MP5990GMA1111Z';
      BODY_NAME='MP5990GMA1111Z';
      PHYS_DES_PREFIX='U';
      CLASS='IC';
      STANDARD='';
      LIFECYCLE='';
      PART_NUMBER='AR0F0TP4023';
      JEDEC_TYPE='LGA45_TH_0-45_7X5';
      DESCRIPTION='PROG IC(45P)MP5990GMA-1111-Z(F9C2)(LGA)';
      MANUFTR='MPS';
      MANUF_PN='MP5990GMA-1111-Z';
      RD_CMPLS_LVL='EP(V1)';
      CMPLS_LVL='EP(V1)';
      FROM_PJ='F0TG-CART';
      DIP_SMD='';
      DATA='MPS_MP5990GMA-1111-Z_F9C2.pdf';
      EE_CHECK_LIST='';
      FP_ECN='';
      PSL='';
      CREATOR='';
      STATUS='';
      MSD='';
      ESD_CDM='';
      ESD_HBM='';
      ESD_MM='';
      PIN_LENGTH_SHORT_PIN='0 MILS';
      PIN_LENGTH_LONG_PIN='0 MILS';
      CREATEDAY='20221011';
      PARENT_PART_TYPE='MP5990GMA1111Z';
      PARENT_PPT='MP5990GMA1111Z';
      PARENT_PPT_PART='MP5990GMA1111Z-MP5990GMA-1111-Z,SMLF,IC,AR0F0TP4023';
  end_body;
end_primitive;
primitive 'MP5991GLUZ-MP5991GLU-Z,SMLF,IC,AL005991A00';
  pin
    'VIN1':
      PIN_NUMBER='(9)';
      INPUT_LOAD='(-0.01,0.01)';
      PINUSE='IN';
    'VIN2':
      PIN_NUMBER='(10)';
      INPUT_LOAD='(-0.01,0.01)';
      PINUSE='IN';
    'VIN3':
      PIN_NUMBER='(11)';
      INPUT_LOAD='(-0.01,0.01)';
      PINUSE='IN';
    'VIN4':
      PIN_NUMBER='(12)';
      INPUT_LOAD='(-0.01,0.01)';
      PINUSE='IN';
    'VIN5':
      PIN_NUMBER='(13)';
      INPUT_LOAD='(-0.01,0.01)';
      PINUSE='IN';
    'ON':
      PIN_NUMBER='(4)';
      INPUT_LOAD='(-0.01,0.01)';
      PINUSE='IN';
    'OCREF':
      PIN_NUMBER='(24)';
      OUTPUT_LOAD='(1.0,-1.0)';
      PINUSE='OUT';
    'CS':
      PIN_NUMBER='(23)';
      OUTPUT_LOAD='(1.0,-1.0)';
      PINUSE='OUT';
    'IMON':
      PIN_NUMBER='(22)';
      OUTPUT_LOAD='(1.0,-1.0)';
      PINUSE='OUT';
    'VDD33':
      PIN_NUMBER='(21)';
      PINUSE='POWER';
      NO_LOAD_CHECK='Both';
      NO_IO_CHECK='Both';
      NO_ASSERT_CHECK='TRUE';
      NO_DIR_CHECK='TRUE';
      ALLOW_CONNECT='TRUE';
    'GND':
      PIN_NUMBER='(20)';
      PINUSE='POWER';
      NO_LOAD_CHECK='Both';
      NO_IO_CHECK='Both';
      NO_ASSERT_CHECK='TRUE';
      NO_DIR_CHECK='TRUE';
      ALLOW_CONNECT='TRUE';
    'SS':
      PIN_NUMBER='(19)';
      INPUT_LOAD='(-0.01,0.01)';
      PINUSE='IN';
    'GOK':
      PIN_NUMBER='(5)';
      OUTPUT_LOAD='(1.0,-1.0)';
      PINUSE='OUT';
    'VTEMP':
      PIN_NUMBER='(18)';
      OUTPUT_LOAD='(1.0,-1.0)';
      PINUSE='OUT';
    'VOUT1':
      PIN_NUMBER='(1)';
      OUTPUT_LOAD='(1.0,-1.0)';
      PINUSE='OUT';
    'VOUT2':
      PIN_NUMBER='(2)';
      OUTPUT_LOAD='(1.0,-1.0)';
      PINUSE='OUT';
    'VOUT3':
      PIN_NUMBER='(25)';
      OUTPUT_LOAD='(1.0,-1.0)';
      PINUSE='OUT';
    'VOUT4':
      PIN_NUMBER='(26)';
      OUTPUT_LOAD='(1.0,-1.0)';
      PINUSE='OUT';
    'D_OC':
      PIN_NUMBER='(3)';
      OUTPUT_LOAD='(1.0,-1.0)';
      PINUSE='OUT';
    'VIN6':
      PIN_NUMBER='(14)';
      INPUT_LOAD='(-0.01,0.01)';
      PINUSE='IN';
    'VIN7':
      PIN_NUMBER='(15)';
      INPUT_LOAD='(-0.01,0.01)';
      PINUSE='IN';
    'VIN8':
      PIN_NUMBER='(16)';
      INPUT_LOAD='(-0.01,0.01)';
      PINUSE='IN';
    'VIN9':
      PIN_NUMBER='(33)';
      INPUT_LOAD='(-0.01,0.01)';
      PINUSE='IN';
    'VOUT5':
      PIN_NUMBER='(27)';
      OUTPUT_LOAD='(1.0,-1.0)';
      PINUSE='OUT';
    'VOUT6':
      PIN_NUMBER='(28)';
      OUTPUT_LOAD='(1.0,-1.0)';
      PINUSE='OUT';
    'VOUT7':
      PIN_NUMBER='(29)';
      OUTPUT_LOAD='(1.0,-1.0)';
      PINUSE='OUT';
    'VOUT8':
      PIN_NUMBER='(30)';
      OUTPUT_LOAD='(1.0,-1.0)';
      PINUSE='OUT';
    'VOUT9':
      PIN_NUMBER='(31)';
      OUTPUT_LOAD='(1.0,-1.0)';
      PINUSE='OUT';
    'VOUT10':
      PIN_NUMBER='(32)';
      OUTPUT_LOAD='(1.0,-1.0)';
      PINUSE='OUT';
    'MODE':
      PIN_NUMBER='(8)';
      INPUT_LOAD='(-0.01,0.01)';
      PINUSE='IN';
    'SCREF_OCWREF':
      PIN_NUMBER='(17)';
      INPUT_LOAD='(-0.01,0.01)';
      PINUSE='IN';
    'FLT_TYPE':
      PIN_NUMBER='(6)';
      INPUT_LOAD='(-0.01,0.01)';
      PINUSE='IN';
    'NC1':
      PIN_NUMBER='(7)';
      OUTPUT_TYPE='(TS,TS)';
      INPUT_LOAD='(-0.01,0.01)';
      OUTPUT_LOAD='(1.0,-1.0)';
      PINUSE='TRI';
  end_pin;
  body
      PART_NAME='MP5991GLUZ';
      BODY_NAME='MP5991GLUZ';
      PHYS_DES_PREFIX='U';
      CLASS='IC';
      STANDARD='';
      LIFECYCLE='';
      PART_NUMBER='AL005991A00';
      JEDEC_TYPE='LGA32_TH_0-5_5X5';
      DESCRIPTION='IC(32P)MP5991GLU-Z(LGA)';
      MANUFTR='MPS';
      MANUF_PN='MP5991GLU-Z';
      RD_CMPLS_LVL='EP(V1)';
      CMPLS_LVL='';
      FROM_PJ='F0E-GREG';
      DIP_SMD='';
      DATA='MPS_MP5991GLU-Z.pdf';
      EE_CHECK_LIST='';
      FP_ECN='';
      PSL='';
      CREATOR='';
      STATUS='';
      MSD='';
      ESD_CDM='';
      ESD_HBM='';
      ESD_MM='';
      PIN_LENGTH_SHORT_PIN='0 MILS';
      PIN_LENGTH_LONG_PIN='0 MILS';
      CREATEDAY='20211019';
      PARENT_PART_TYPE='MP5991GLUZ';
      PARENT_PPT='MP5991GLUZ';
      PARENT_PPT_PART='MP5991GLUZ-MP5991GLU-Z,SMLF,IC,AL005991A00';
  end_body;
end_primitive;
primitive 'MPQ8626GDZ-MPQ8626GD-Z,SMLF,IC,AL008626000';
  pin
    'VIN':
      PIN_NUMBER='(3)';
      INPUT_LOAD='(-0.01,0.01)';
      PINUSE='IN';
    'PGOOD':
      PIN_NUMBER='(9)';
      OUTPUT_LOAD='(1.0,-1.0)';
      PINUSE='OUT';
    'PGND2':
      PIN_NUMBER='(14)';
      PINUSE='POWER';
      NO_LOAD_CHECK='Both';
      NO_IO_CHECK='Both';
      NO_ASSERT_CHECK='TRUE';
      NO_DIR_CHECK='TRUE';
      ALLOW_CONNECT='TRUE';
    'EN':
      PIN_NUMBER='(5)';
      INPUT_LOAD='(-0.01,0.01)';
      PINUSE='IN';
    'BST':
      PIN_NUMBER='(10)';
      INPUT_LOAD='(-0.01,0.01)';
      PINUSE='IN';
    'FB':
      PIN_NUMBER='(6)';
      INPUT_LOAD='(-0.01,0.01)';
      PINUSE='IN';
    'AGND':
      PIN_NUMBER='(7)';
      PINUSE='POWER';
      NO_LOAD_CHECK='Both';
      NO_IO_CHECK='Both';
      NO_ASSERT_CHECK='TRUE';
      NO_DIR_CHECK='TRUE';
      ALLOW_CONNECT='TRUE';
    'VCC':
      PIN_NUMBER='(13)';
      OUTPUT_LOAD='(1.0,-1.0)';
      PINUSE='OUT';
    'PGND1':
      PIN_NUMBER='(1)';
      PINUSE='POWER';
      NO_LOAD_CHECK='Both';
      NO_IO_CHECK='Both';
      NO_ASSERT_CHECK='TRUE';
      NO_DIR_CHECK='TRUE';
      ALLOW_CONNECT='TRUE';
    'SW2':
      PIN_NUMBER='(11)';
      OUTPUT_LOAD='(1.0,-1.0)';
      PINUSE='OUT';
    'TRK_REF':
      PIN_NUMBER='(8)';
      INPUT_LOAD='(-0.01,0.01)';
      PINUSE='IN';
    'MODE':
      PIN_NUMBER='(12)';
      INPUT_LOAD='(-0.01,0.01)';
      PINUSE='IN';
    'CS':
      PIN_NUMBER='(4)';
      INPUT_LOAD='(-0.01,0.01)';
      PINUSE='IN';
    'SW1':
      PIN_NUMBER='(2)';
      OUTPUT_LOAD='(1.0,-1.0)';
      PINUSE='OUT';
  end_pin;
  body
      PART_NAME='MPQ8626GDZ';
      BODY_NAME='MPQ8626GDZ';
      PHYS_DES_PREFIX='U';
      CLASS='IC';
      STANDARD='';
      LIFECYCLE='';
      PART_NUMBER='AL008626000';
      JEDEC_TYPE='QFN14_0-5_3X2XA';
      DESCRIPTION='IC CTRL(14P)MPQ8626GD-Z(QFN)';
      MANUFTR='MPS';
      MANUF_PN='MPQ8626GD-Z';
      RD_CMPLS_LVL='EP(V1)';
      CMPLS_LVL='';
      FROM_PJ='F09A-BEN';
      DIP_SMD='';
      DATA='MPS_MPQ8626GD-Z.pdf';
      EE_CHECK_LIST='';
      FP_ECN='';
      PSL='';
      CREATOR='';
      STATUS='';
      MSD='NA';
      ESD_CDM='NA';
      ESD_HBM='NA';
      ESD_MM='NA';
      PIN_LENGTH_SHORT_PIN='0 MILS';
      PIN_LENGTH_LONG_PIN='0 MILS';
      CREATEDAY='20171225';
      PARENT_PART_TYPE='MPQ8626GDZ';
      PARENT_PPT='MPQ8626GDZ';
      PARENT_PPT_PART='MPQ8626GDZ-MPQ8626GD-Z,SMLF,IC,AL008626000';
  end_body;
end_primitive;
primitive 'MPQ8633AGLEC807Z-MPQ8633AGLE-C807-Z,SMLF,IC,AL0086A';
  pin
    'VIN1':
      PIN_NUMBER='(10)';
      INPUT_LOAD='(-0.01,0.01)';
      PINUSE='IN';
    'PGOOD':
      PIN_NUMBER='(9)';
      OUTPUT_LOAD='(1.0,-1.0)';
      PINUSE='OUT';
    'PGND':
      PIN_NUMBER='(11_18)';
      PINUSE='POWER';
      NO_LOAD_CHECK='Both';
      NO_IO_CHECK='Both';
      NO_ASSERT_CHECK='TRUE';
      NO_DIR_CHECK='TRUE';
      ALLOW_CONNECT='TRUE';
    'EN':
      PIN_NUMBER='(8)';
      INPUT_LOAD='(-0.01,0.01)';
      PINUSE='IN';
    'BST':
      PIN_NUMBER='(1)';
      INPUT_LOAD='(-0.01,0.01)';
      PINUSE='IN';
    'FB':
      PIN_NUMBER='(7)';
      INPUT_LOAD='(-0.01,0.01)';
      PINUSE='IN';
    'AGND':
      PIN_NUMBER='(2)';
      PINUSE='POWER';
      NO_LOAD_CHECK='Both';
      NO_IO_CHECK='Both';
      NO_ASSERT_CHECK='TRUE';
      NO_DIR_CHECK='TRUE';
      ALLOW_CONNECT='TRUE';
    'VCC':
      PIN_NUMBER='(19)';
      PINUSE='POWER';
      NO_LOAD_CHECK='Both';
      NO_IO_CHECK='Both';
      NO_ASSERT_CHECK='TRUE';
      NO_DIR_CHECK='TRUE';
      ALLOW_CONNECT='TRUE';
    'RGND':
      PIN_NUMBER='(6)';
      PINUSE='POWER';
      NO_LOAD_CHECK='Both';
      NO_IO_CHECK='Both';
      NO_ASSERT_CHECK='TRUE';
      NO_DIR_CHECK='TRUE';
      ALLOW_CONNECT='TRUE';
    'SW':
      PIN_NUMBER='(20)';
      OUTPUT_LOAD='(1.0,-1.0)';
      PINUSE='OUT';
    'TRK_REF':
      PIN_NUMBER='(5)';
      INPUT_LOAD='(-0.01,0.01)';
      PINUSE='IN';
    'MODE':
      PIN_NUMBER='(4)';
      INPUT_LOAD='(-0.01,0.01)';
      PINUSE='IN';
    'CS':
      PIN_NUMBER='(3)';
      INPUT_LOAD='(-0.01,0.01)';
      PINUSE='IN';
    'VIN2':
      PIN_NUMBER='(21)';
      INPUT_LOAD='(-0.01,0.01)';
      PINUSE='IN';
  end_pin;
  body
      PART_NAME='MPQ8633AGLEC807Z';
      BODY_NAME='MPQ8633AGLEC807Z';
      PHYS_DES_PREFIX='U';
      CLASS='IC';
      STANDARD='';
      LIFECYCLE='';
      PART_NUMBER='AL008633007';
      JEDEC_TYPE='QFN14_4X3';
      DESCRIPTION='IC CTRL(21P)MPQ8633AGLE-C807-Z(QFN)';
      MANUFTR='MPS';
      MANUF_PN='MPQ8633AGLE-C807-Z';
      RD_CMPLS_LVL='EP(V1)';
      CMPLS_LVL='';
      FROM_PJ='F0B-HANK';
      DIP_SMD='';
      DATA='MPS_MPQ8633AGLE-C807-Z.pdf';
      EE_CHECK_LIST='';
      FP_ECN='';
      PSL='';
      CREATOR='';
      STATUS='';
      MSD='Level-2';
      ESD_CDM='0';
      ESD_HBM='0';
      ESD_MM='00';
      PIN_LENGTH_SHORT_PIN='0 MILS';
      PIN_LENGTH_LONG_PIN='0 MILS';
      CREATEDAY='20180613';
      PARENT_PART_TYPE='MPQ8633AGLEC807Z';
      PARENT_PPT='MPQ8633AGLEC807Z';
      PARENT_PPT_PART='MPQ8633AGLEC807Z-MPQ8633AGLE-C807-Z,SMLF,IC,AL008633007';
  end_body;
end_primitive;
primitive 'MPQ8633BGLEC838Z-MPQ8633BGLE-C838-Z,SMLF,IC,AL0086A';
  pin
    'VIN1':
      PIN_NUMBER='(10)';
      INPUT_LOAD='(-0.01,0.01)';
      PINUSE='IN';
    'PGOOD':
      PIN_NUMBER='(9)';
      OUTPUT_LOAD='(1.0,-1.0)';
      PINUSE='OUT';
    'PGND':
      PIN_NUMBER='(11_18)';
      PINUSE='POWER';
      NO_LOAD_CHECK='Both';
      NO_IO_CHECK='Both';
      NO_ASSERT_CHECK='TRUE';
      NO_DIR_CHECK='TRUE';
      ALLOW_CONNECT='TRUE';
    'EN':
      PIN_NUMBER='(8)';
      INPUT_LOAD='(-0.01,0.01)';
      PINUSE='IN';
    'BST':
      PIN_NUMBER='(1)';
      INPUT_LOAD='(-0.01,0.01)';
      PINUSE='IN';
    'FB':
      PIN_NUMBER='(7)';
      INPUT_LOAD='(-0.01,0.01)';
      PINUSE='IN';
    'AGND':
      PIN_NUMBER='(2)';
      PINUSE='POWER';
      NO_LOAD_CHECK='Both';
      NO_IO_CHECK='Both';
      NO_ASSERT_CHECK='TRUE';
      NO_DIR_CHECK='TRUE';
      ALLOW_CONNECT='TRUE';
    'VCC':
      PIN_NUMBER='(19)';
      INPUT_LOAD='(-0.01,0.01)';
      PINUSE='IN';
    'RGND':
      PIN_NUMBER='(6)';
      PINUSE='POWER';
      NO_LOAD_CHECK='Both';
      NO_IO_CHECK='Both';
      NO_ASSERT_CHECK='TRUE';
      NO_DIR_CHECK='TRUE';
      ALLOW_CONNECT='TRUE';
    'SW':
      PIN_NUMBER='(20)';
      OUTPUT_LOAD='(1.0,-1.0)';
      PINUSE='OUT';
    'TRK_REF':
      PIN_NUMBER='(5)';
      INPUT_LOAD='(-0.01,0.01)';
      PINUSE='IN';
    'MODE':
      PIN_NUMBER='(4)';
      INPUT_LOAD='(-0.01,0.01)';
      PINUSE='IN';
    'CS':
      PIN_NUMBER='(3)';
      INPUT_LOAD='(-0.01,0.01)';
      PINUSE='IN';
    'VIN2':
      PIN_NUMBER='(21)';
      INPUT_LOAD='(-0.01,0.01)';
      PINUSE='IN';
  end_pin;
  body
      PART_NAME='MPQ8633BGLEC838Z';
      BODY_NAME='MPQ8633BGLEC838Z';
      PHYS_DES_PREFIX='U';
      CLASS='IC';
      STANDARD='';
      LIFECYCLE='';
      PART_NUMBER='AL008633005';
      JEDEC_TYPE='QFN14_4X3';
      DESCRIPTION='IC CTRL(21P) MPQ8633BGLE-C838-Z(QFN)';
      MANUFTR='MPS';
      MANUF_PN='MPQ8633BGLE-C838-Z';
      RD_CMPLS_LVL='EP(V1)';
      CMPLS_LVL='';
      FROM_PJ='F09-ABER';
      DIP_SMD='';
      DATA='MPS_MPQ8633BGLE-C838-Z.pdf';
      EE_CHECK_LIST='';
      FP_ECN='';
      PSL='';
      CREATOR='';
      STATUS='';
      MSD='NA';
      ESD_CDM='NA';
      ESD_HBM='NA';
      ESD_MM='NA';
      PIN_LENGTH_SHORT_PIN='0 MILS';
      PIN_LENGTH_LONG_PIN='0 MILS';
      CREATEDAY='20171113';
      PARENT_PART_TYPE='MPQ8633BGLEC838Z';
      PARENT_PPT='MPQ8633BGLEC838Z';
      PARENT_PPT_PART='MPQ8633BGLEC838Z-MPQ8633BGLE-C838-Z,SMLF,IC,AL008633005';
  end_body;
end_primitive;
primitive 'NC7SB3157P6X-NC7SB3157P6X,SMLF,IC,ALSB3157000';
  pin
    'B1':
      PIN_NUMBER='(1)';
      BIDIRECTIONAL='TRUE';
      INPUT_LOAD='(-0.01,0.01)';
      OUTPUT_LOAD='(1.0,-1.0)';
      PINUSE='BI';
    'GND':
      PIN_NUMBER='(2)';
      PINUSE='POWER';
      NO_LOAD_CHECK='Both';
      NO_IO_CHECK='Both';
      NO_ASSERT_CHECK='TRUE';
      NO_DIR_CHECK='TRUE';
      ALLOW_CONNECT='TRUE';
    'B0':
      PIN_NUMBER='(3)';
      BIDIRECTIONAL='TRUE';
      INPUT_LOAD='(-0.01,0.01)';
      OUTPUT_LOAD='(1.0,-1.0)';
      PINUSE='BI';
    'S':
      PIN_NUMBER='(6)';
      INPUT_LOAD='(-0.01,0.01)';
      PINUSE='IN';
    'VCC':
      PIN_NUMBER='(5)';
      PINUSE='POWER';
      NO_LOAD_CHECK='Both';
      NO_IO_CHECK='Both';
      NO_ASSERT_CHECK='TRUE';
      NO_DIR_CHECK='TRUE';
      ALLOW_CONNECT='TRUE';
    'A':
      PIN_NUMBER='(4)';
      BIDIRECTIONAL='TRUE';
      INPUT_LOAD='(-0.01,0.01)';
      OUTPUT_LOAD='(1.0,-1.0)';
      PINUSE='BI';
  end_pin;
  body
      PART_NAME='NC7SB3157P6X';
      BODY_NAME='NC7SB3157P6X';
      PHYS_DES_PREFIX='U';
      CLASS='IC';
      STANDARD='End of Design';
      LIFECYCLE='Comp-Approve';
      PART_NUMBER='ALSB3157000';
      JEDEC_TYPE='SC70-6XA';
      DESCRIPTION='IC OTHER(6P)NC7SB3157P6X(SC70-6)';
      MANUFTR='FAC';
      MANUF_PN='NC7SB3157P6X';
      RD_CMPLS_LVL='EP(V1)';
      CMPLS_LVL='EP(V1)';
      FROM_PJ='T52-NICK';
      DIP_SMD='';
      DATA='FAC_NC7SB3157P6X.pdf';
      EE_CHECK_LIST='';
      FP_ECN='';
      PSL='';
      CREATOR='';
      STATUS='';
      MSD='';
      ESD_CDM='';
      ESD_HBM='';
      ESD_MM='';
      PIN_LENGTH_SHORT_PIN='0 MILS';
      PIN_LENGTH_LONG_PIN='0 MILS';
      CREATEDAY='20210604';
      PARENT_PART_TYPE='NC7SB3157P6X';
      PARENT_PPT='NC7SB3157P6X';
      PARENT_PPT_PART='NC7SB3157P6X-NC7SB3157P6X,SMLF,IC,ALSB3157000';
  end_body;
end_primitive;
primitive 'NC7SB3157_SMLF-NC7SB3157P6X,NC7SB3157P6X,EMPTY,ALSA';
  pin
    'B1':
      PIN_NUMBER='(1)';
      INPUT_LOAD='(-0.01,0.01)';
      OUTPUT_LOAD='(1.0,-1.0)';
      BIDIRECTIONAL='TRUE';
      PINUSE='BI';
    'GND':
      PIN_NUMBER='(2)';
      PINUSE='POWER';
    'B0':
      PIN_NUMBER='(3)';
      INPUT_LOAD='(-0.01,0.01)';
      OUTPUT_LOAD='(1.0,-1.0)';
      BIDIRECTIONAL='TRUE';
      PINUSE='BI';
    'S':
      PIN_NUMBER='(6)';
      INPUT_LOAD='(-0.01,0.01)';
      PINUSE='IN';
    'VCC':
      PIN_NUMBER='(5)';
      PINUSE='POWER';
    'A':
      PIN_NUMBER='(4)';
      INPUT_LOAD='(-0.01,0.01)';
      OUTPUT_LOAD='(1.0,-1.0)';
      BIDIRECTIONAL='TRUE';
      PINUSE='BI';
  end_pin;
  body
      PHYS_DES_PREFIX='U';
      CLASS='IO';
      PART_NAME='NC7SB3157';
      BODY_NAME='NC7SB3157';
      STANDARD='End of Design';
      LIFECYCLE='Comp-Approve';
      ENVCOMP='YES';
      PART_NUMBER='ALSB3157000';
      JEDEC_TYPE='SC70-6';
      DESCRIPTION='IC(6P) NC7SB3157P6X(SC70-6)';
      HEIGHT='.044IN';
      COMPONENT_TYPE='SMALLSMT';
      LEAD_LENGTH='';
      LPID='';
      DAY='20100709';
      PARENT_PART_TYPE='NC7SB3157';
      PARENT_PPT='NC7SB3157';
      PARENT_PPT_PART='NC7SB3157_SMLF-NC7SB3157P6X,NC7SB3157P6X,EMPTY,ALSB3157000';
  end_body;
end_primitive;
primitive 'NCP3284AMNTXG-NCP3284AMNTXG,SMLF,IC,AL003284002';
  pin
    'NC2':
      PIN_NUMBER='(34)';
      OUTPUT_TYPE='(TS,TS)';
      INPUT_LOAD='(-0.01,0.01)';
      OUTPUT_LOAD='(1.0,-1.0)';
      PINUSE='TRI';
    'MODE||FSET':
      PIN_NUMBER='(36)';
      INPUT_LOAD='(-0.01,0.01)';
      PINUSE='IN';
    'VIN':
      PIN_NUMBER='(3)';
      PINUSE='POWER';
      NO_LOAD_CHECK='Both';
      NO_IO_CHECK='Both';
      NO_ASSERT_CHECK='TRUE';
      NO_DIR_CHECK='TRUE';
      ALLOW_CONNECT='TRUE';
    'FB':
      PIN_NUMBER='(30)';
      INPUT_LOAD='(-0.01,0.01)';
      PINUSE='IN';
    'BOOT':
      PIN_NUMBER='(26)';
      BIDIRECTIONAL='TRUE';
      INPUT_LOAD='(-0.01,0.01)';
      OUTPUT_LOAD='(1.0,-1.0)';
      PINUSE='BI';
    'ILIM':
      PIN_NUMBER='(1)';
      OUTPUT_LOAD='(1.0,-1.0)';
      PINUSE='OUT';
    'PHASE':
      PIN_NUMBER='(25)';
      INPUT_LOAD='(-0.01,0.01)';
      PINUSE='IN';
    'VCC':
      PIN_NUMBER='(4)';
      PINUSE='POWER';
      NO_LOAD_CHECK='Both';
      NO_IO_CHECK='Both';
      NO_ASSERT_CHECK='TRUE';
      NO_DIR_CHECK='TRUE';
      ALLOW_CONNECT='TRUE';
    'VSNS-':
      PIN_NUMBER='(31)';
      INPUT_LOAD='(-0.01,0.01)';
      PINUSE='IN';
    'HICCUP#':
      PIN_NUMBER='(35)';
      INPUT_LOAD='(-0.01,0.01)';
      PINUSE='IN';
    'PGND':
      PIN_NUMBER='(7_10-19)';
      PINUSE='POWER';
      NO_LOAD_CHECK='Both';
      NO_IO_CHECK='Both';
      NO_ASSERT_CHECK='TRUE';
      NO_DIR_CHECK='TRUE';
      ALLOW_CONNECT='TRUE';
    'NC1':
      PIN_NUMBER='(33)';
      OUTPUT_TYPE='(TS,TS)';
      INPUT_LOAD='(-0.01,0.01)';
      OUTPUT_LOAD='(1.0,-1.0)';
      PINUSE='TRI';
    'SW':
      PIN_NUMBER='(11_18)';
      BIDIRECTIONAL='TRUE';
      INPUT_LOAD='(-0.01,0.01)';
      OUTPUT_LOAD='(1.0,-1.0)';
      PINUSE='BI';
    'PVIN':
      PIN_NUMBER='(20_24)';
      PINUSE='POWER';
      NO_LOAD_CHECK='Both';
      NO_IO_CHECK='Both';
      NO_ASSERT_CHECK='TRUE';
      NO_DIR_CHECK='TRUE';
      ALLOW_CONNECT='TRUE';
    'PGOOD':
      PIN_NUMBER='(2)';
      OUTPUT_LOAD='(1.0,-1.0)';
      PINUSE='OUT';
    'VOS':
      PIN_NUMBER='(28)';
      INPUT_LOAD='(-0.01,0.01)';
      PINUSE='IN';
    'AGND':
      PIN_NUMBER='(32)';
      PINUSE='POWER';
      NO_LOAD_CHECK='Both';
      NO_IO_CHECK='Both';
      NO_ASSERT_CHECK='TRUE';
      NO_DIR_CHECK='TRUE';
      ALLOW_CONNECT='TRUE';
    'EN':
      PIN_NUMBER='(27)';
      INPUT_LOAD='(-0.01,0.01)';
      PINUSE='IN';
    'VDRV':
      PIN_NUMBER='(5)';
      PINUSE='POWER';
      NO_LOAD_CHECK='Both';
      NO_IO_CHECK='Both';
      NO_ASSERT_CHECK='TRUE';
      NO_DIR_CHECK='TRUE';
      ALLOW_CONNECT='TRUE';
    'GL1':
      PIN_NUMBER='(6)';
      OUTPUT_LOAD='(1.0,-1.0)';
      PINUSE='OUT';
    'SS':
      PIN_NUMBER='(29)';
      INPUT_LOAD='(-0.01,0.01)';
      PINUSE='IN';
    'GL2':
      PIN_NUMBER='(37)';
      OUTPUT_LOAD='(1.0,-1.0)';
      PINUSE='OUT';
  end_pin;
  body
      PART_NAME='NCP3284AMNTXG';
      BODY_NAME='NCP3284AMNTXG';
      PHYS_DES_PREFIX='U';
      CLASS='IC';
      STANDARD='';
      LIFECYCLE='';
      PART_NUMBER='AL003284002';
      JEDEC_TYPE='PQFN22_6X5';
      DESCRIPTION='IC (37P)NCP3284AMNTXG(PQFN)';
      MANUFTR='ONS';
      MANUF_PN='NCP3284AMNTXG';
      RD_CMPLS_LVL='EP(V1)';
      CMPLS_LVL='';
      FROM_PJ='S6X-KIMI';
      DIP_SMD='';
      DATA='ONS_NCP3284AMNTXG.pdf';
      EE_CHECK_LIST='';
      FP_ECN='NCP3284AMNTXG.msg';
      PSL='';
      CREATOR='';
      STATUS='';
      MSD='NA';
      ESD_CDM='na';
      ESD_HBM='na';
      ESD_MM='na';
      PIN_LENGTH_SHORT_PIN='0 MILS';
      PIN_LENGTH_LONG_PIN='0 MILS';
      CREATEDAY='20201130';
      PARENT_PART_TYPE='NCP3284AMNTXG';
      PARENT_PPT='NCP3284AMNTXG';
      PARENT_PPT_PART='NCP3284AMNTXG-NCP3284AMNTXG,SMLF,IC,AL003284002';
  end_body;
end_primitive;
primitive 'NCP698SQ15T1G-NCP698SQ15T1G,SMLF,EMPTY,AL000698000';
  pin
    'GND':
      PIN_NUMBER='(1)';
      PINUSE='POWER';
      NO_LOAD_CHECK='Both';
      NO_IO_CHECK='Both';
      NO_ASSERT_CHECK='TRUE';
      NO_DIR_CHECK='TRUE';
      ALLOW_CONNECT='TRUE';
    'VOUT':
      PIN_NUMBER='(3)';
      OUTPUT_LOAD='(1.0,-1.0)';
      PINUSE='OUT';
    'VIN':
      PIN_NUMBER='(2)';
      INPUT_LOAD='(-0.01,0.01)';
      PINUSE='IN';
    'EN':
      PIN_NUMBER='(4)';
      INPUT_LOAD='(-0.01,0.01)';
      PINUSE='IN';
  end_pin;
  body
      PART_NAME='NCP698SQ15T1G';
      BODY_NAME='NCP698SQ15T1G';
      PHYS_DES_PREFIX='U';
      CLASS='IC';
      STANDARD='End of Design';
      LIFECYCLE='Comp-Approve';
      PART_NUMBER='AL000698000';
      JEDEC_TYPE='SC82-AB-4_1-3_2X1-25';
      DESCRIPTION='IC OTHER(4P) NCP698SQ15T1G(SC82-AB)';
      MANUFTR='ONS';
      MANUF_PN='NCP698SQ15T1G';
      RD_CMPLS_LVL='EP(V1)';
      CMPLS_LVL='EP(V1)';
      FROM_PJ='T7A-JOSEPH';
      DIP_SMD='';
      DATA='ONS_NCP698SQ15T1G.pdf';
      EE_CHECK_LIST='';
      FP_ECN='';
      PSL='';
      CREATOR='';
      STATUS='';
      MSD='NA';
      ESD_CDM='NA';
      ESD_HBM='NA';
      ESD_MM='NA';
      PIN_LENGTH_SHORT_PIN='0 MILS';
      PIN_LENGTH_LONG_PIN='0 MILS';
      CREATEDAY='20160920';
      PARENT_PART_TYPE='NCP698SQ15T1G';
      PARENT_PPT='NCP698SQ15T1G';
      PARENT_PPT_PART='NCP698SQ15T1G-NCP698SQ15T1G,SMLF,EMPTY,AL000698000';
  end_body;
end_primitive;
primitive 'NCT7718W-NCT7718W,SMLF,IC,AL007718001';
  pin
    'VDD':
      PIN_NUMBER='(1)';
      PINUSE='POWER';
      NO_LOAD_CHECK='Both';
      NO_IO_CHECK='Both';
      NO_ASSERT_CHECK='TRUE';
      NO_DIR_CHECK='TRUE';
      ALLOW_CONNECT='TRUE';
    'D+':
      PIN_NUMBER='(2)';
      INPUT_LOAD='(-0.01,0.01)';
      PINUSE='IN';
    'D-':
      PIN_NUMBER='(3)';
      INPUT_LOAD='(-0.01,0.01)';
      PINUSE='IN';
    'T_CRIT#':
      PIN_NUMBER='(4)';
      OUTPUT_TYPE='(OC,AND)';
      OUTPUT_LOAD='(1.0,*)';
      PINUSE='OCA';
    'GND':
      PIN_NUMBER='(5)';
      PINUSE='POWER';
      NO_LOAD_CHECK='Both';
      NO_IO_CHECK='Both';
      NO_ASSERT_CHECK='TRUE';
      NO_DIR_CHECK='TRUE';
      ALLOW_CONNECT='TRUE';
    'ALERT#':
      PIN_NUMBER='(6)';
      OUTPUT_TYPE='(OC,AND)';
      OUTPUT_LOAD='(1.0,*)';
      PINUSE='OCA';
    'SDA':
      PIN_NUMBER='(7)';
      BIDIRECTIONAL='TRUE';
      INPUT_LOAD='(-0.01,0.01)';
      OUTPUT_LOAD='(1.0,-1.0)';
      PINUSE='BI';
    'SCL':
      PIN_NUMBER='(8)';
      INPUT_LOAD='(-0.01,0.01)';
      PINUSE='IN';
  end_pin;
  body
      PART_NAME='NCT7718W';
      BODY_NAME='NCT7718W';
      PHYS_DES_PREFIX='U';
      CLASS='IC';
      STANDARD='';
      LIFECYCLE='';
      PART_NUMBER='AL007718001';
      JEDEC_TYPE='MSOP8_0-65_3X3XE';
      DESCRIPTION='IC OTHER(8P) NCT7718W(MSOP)';
      MANUFTR='NVT';
      MANUF_PN='NCT7718W';
      RD_CMPLS_LVL='EP(V1)';
      CMPLS_LVL='EP(V1)';
      FROM_PJ='F0EG-RAY';
      DIP_SMD='';
      DATA='NVT_NCT7718W.pdf';
      EE_CHECK_LIST='';
      FP_ECN='NCT7718W.msg';
      PSL='';
      CREATOR='';
      STATUS='';
      MSD='';
      ESD_CDM='';
      ESD_HBM='';
      ESD_MM='';
      PIN_LENGTH_SHORT_PIN='0 MILS';
      PIN_LENGTH_LONG_PIN='0 MILS';
      CREATEDAY='20220317';
      PARENT_PART_TYPE='NCT7718W';
      PARENT_PPT='NCT7718W';
      PARENT_PPT_PART='NCT7718W-NCT7718W,SMLF,IC,AL007718001';
  end_body;
end_primitive;
primitive 'PCA9306DP1-PCA9306DP1,SMLF,IC,AL009306K04';
  pin
    'VREF1':
      PIN_NUMBER='(2)';
      PINUSE='POWER';
      NO_LOAD_CHECK='Both';
      NO_IO_CHECK='Both';
      NO_ASSERT_CHECK='TRUE';
      NO_DIR_CHECK='TRUE';
      ALLOW_CONNECT='TRUE';
    'SCL1':
      PIN_NUMBER='(3)';
      BIDIRECTIONAL='TRUE';
      INPUT_LOAD='(-0.01,0.01)';
      OUTPUT_LOAD='(1.0,-1.0)';
      PINUSE='BI';
    'SDA1':
      PIN_NUMBER='(4)';
      BIDIRECTIONAL='TRUE';
      INPUT_LOAD='(-0.01,0.01)';
      OUTPUT_LOAD='(1.0,-1.0)';
      PINUSE='BI';
    'SDA2':
      PIN_NUMBER='(5)';
      BIDIRECTIONAL='TRUE';
      INPUT_LOAD='(-0.01,0.01)';
      OUTPUT_LOAD='(1.0,-1.0)';
      PINUSE='BI';
    'SCL2':
      PIN_NUMBER='(6)';
      BIDIRECTIONAL='TRUE';
      INPUT_LOAD='(-0.01,0.01)';
      OUTPUT_LOAD='(1.0,-1.0)';
      PINUSE='BI';
    'VREF2':
      PIN_NUMBER='(7)';
      PINUSE='POWER';
      NO_LOAD_CHECK='Both';
      NO_IO_CHECK='Both';
      NO_ASSERT_CHECK='TRUE';
      NO_DIR_CHECK='TRUE';
      ALLOW_CONNECT='TRUE';
    'EN':
      PIN_NUMBER='(8)';
      INPUT_LOAD='(-0.01,0.01)';
      PINUSE='IN';
    'GND':
      PIN_NUMBER='(1)';
      PINUSE='POWER';
      NO_LOAD_CHECK='Both';
      NO_IO_CHECK='Both';
      NO_ASSERT_CHECK='TRUE';
      NO_DIR_CHECK='TRUE';
      ALLOW_CONNECT='TRUE';
  end_pin;
  body
      PART_NAME='PCA9306DP1';
      BODY_NAME='PCA9306DP1';
      PHYS_DES_PREFIX='U';
      CLASS='IC';
      PART_NUMBER='AL009306K04';
      JEDEC_TYPE='TSSOP8_3';
      DESCRIPTION='IC OTHER(8P)PCA9306DP1(TSSOP)';
      MANUFTR='NXP';
      MANUF_PN='PCA9306DP1';
      RD_CMPLS_LVL='EP(V1)';
      CMPLS_LVL='';
      FROM_PJ='T2L-MARK';
      DIP_SMD='';
      DATA='NXP_PCA9306.pdf';
      EE_CHECK_LIST='';
      FP_ECN='';
      PSL='';
      LIFECYCLE='';
      CREATOR='';
      STANDARD='';
      CREATEDAY='20120224';
      STATUS='';
      PARENT_PART_TYPE='PCA9306DP1';
      PARENT_PPT='PCA9306DP1';
      PARENT_PPT_PART='PCA9306DP1-PCA9306DP1,SMLF,IC,AL009306K04';
  end_body;
end_primitive;
primitive 'PCA9539RPW-PCA9539RPW,SMLF,IC,AL009539K07';
  pin
    'INT':
      PIN_NUMBER='(1)';
      BIDIRECTIONAL='TRUE';
      INPUT_LOAD='(-0.01,0.01)';
      OUTPUT_LOAD='(1.0,-1.0)';
      PINUSE='BI';
    'A1':
      PIN_NUMBER='(2)';
      INPUT_LOAD='(-0.01,0.01)';
      PINUSE='IN';
    'RESET':
      PIN_NUMBER='(3)';
      BIDIRECTIONAL='TRUE';
      INPUT_LOAD='(-0.01,0.01)';
      OUTPUT_LOAD='(1.0,-1.0)';
      PINUSE='BI';
    'IO0_0':
      PIN_NUMBER='(4)';
      BIDIRECTIONAL='TRUE';
      INPUT_LOAD='(-0.01,0.01)';
      OUTPUT_LOAD='(1.0,-1.0)';
      PINUSE='BI';
    'IO0_1':
      PIN_NUMBER='(5)';
      BIDIRECTIONAL='TRUE';
      INPUT_LOAD='(-0.01,0.01)';
      OUTPUT_LOAD='(1.0,-1.0)';
      PINUSE='BI';
    'IO0_2':
      PIN_NUMBER='(6)';
      BIDIRECTIONAL='TRUE';
      INPUT_LOAD='(-0.01,0.01)';
      OUTPUT_LOAD='(1.0,-1.0)';
      PINUSE='BI';
    'IO0_3':
      PIN_NUMBER='(7)';
      BIDIRECTIONAL='TRUE';
      INPUT_LOAD='(-0.01,0.01)';
      OUTPUT_LOAD='(1.0,-1.0)';
      PINUSE='BI';
    'IO0_4':
      PIN_NUMBER='(8)';
      BIDIRECTIONAL='TRUE';
      INPUT_LOAD='(-0.01,0.01)';
      OUTPUT_LOAD='(1.0,-1.0)';
      PINUSE='BI';
    'IO0_5':
      PIN_NUMBER='(9)';
      BIDIRECTIONAL='TRUE';
      INPUT_LOAD='(-0.01,0.01)';
      OUTPUT_LOAD='(1.0,-1.0)';
      PINUSE='BI';
    'IO0_6':
      PIN_NUMBER='(10)';
      BIDIRECTIONAL='TRUE';
      INPUT_LOAD='(-0.01,0.01)';
      OUTPUT_LOAD='(1.0,-1.0)';
      PINUSE='BI';
    'IO0_7':
      PIN_NUMBER='(11)';
      BIDIRECTIONAL='TRUE';
      INPUT_LOAD='(-0.01,0.01)';
      OUTPUT_LOAD='(1.0,-1.0)';
      PINUSE='BI';
    'VSS':
      PIN_NUMBER='(12)';
      PINUSE='POWER';
      NO_LOAD_CHECK='Both';
      NO_IO_CHECK='Both';
      NO_ASSERT_CHECK='TRUE';
      NO_DIR_CHECK='TRUE';
      ALLOW_CONNECT='TRUE';
    'IO1_0':
      PIN_NUMBER='(13)';
      BIDIRECTIONAL='TRUE';
      INPUT_LOAD='(-0.01,0.01)';
      OUTPUT_LOAD='(1.0,-1.0)';
      PINUSE='BI';
    'IO1_1':
      PIN_NUMBER='(14)';
      BIDIRECTIONAL='TRUE';
      INPUT_LOAD='(-0.01,0.01)';
      OUTPUT_LOAD='(1.0,-1.0)';
      PINUSE='BI';
    'IO1_2':
      PIN_NUMBER='(15)';
      BIDIRECTIONAL='TRUE';
      INPUT_LOAD='(-0.01,0.01)';
      OUTPUT_LOAD='(1.0,-1.0)';
      PINUSE='BI';
    'IO1_3':
      PIN_NUMBER='(16)';
      BIDIRECTIONAL='TRUE';
      INPUT_LOAD='(-0.01,0.01)';
      OUTPUT_LOAD='(1.0,-1.0)';
      PINUSE='BI';
    'IO1_4':
      PIN_NUMBER='(17)';
      BIDIRECTIONAL='TRUE';
      INPUT_LOAD='(-0.01,0.01)';
      OUTPUT_LOAD='(1.0,-1.0)';
      PINUSE='BI';
    'IO1_5':
      PIN_NUMBER='(18)';
      BIDIRECTIONAL='TRUE';
      INPUT_LOAD='(-0.01,0.01)';
      OUTPUT_LOAD='(1.0,-1.0)';
      PINUSE='BI';
    'IO1_6':
      PIN_NUMBER='(19)';
      BIDIRECTIONAL='TRUE';
      INPUT_LOAD='(-0.01,0.01)';
      OUTPUT_LOAD='(1.0,-1.0)';
      PINUSE='BI';
    'IO1_7':
      PIN_NUMBER='(20)';
      BIDIRECTIONAL='TRUE';
      INPUT_LOAD='(-0.01,0.01)';
      OUTPUT_LOAD='(1.0,-1.0)';
      PINUSE='BI';
    'A0':
      PIN_NUMBER='(21)';
      INPUT_LOAD='(-0.01,0.01)';
      PINUSE='IN';
    'SCL':
      PIN_NUMBER='(22)';
      BIDIRECTIONAL='TRUE';
      INPUT_LOAD='(-0.01,0.01)';
      OUTPUT_LOAD='(1.0,-1.0)';
      PINUSE='BI';
    'SDA':
      PIN_NUMBER='(23)';
      BIDIRECTIONAL='TRUE';
      INPUT_LOAD='(-0.01,0.01)';
      OUTPUT_LOAD='(1.0,-1.0)';
      PINUSE='BI';
    'VDD':
      PIN_NUMBER='(24)';
      PINUSE='POWER';
      NO_LOAD_CHECK='Both';
      NO_IO_CHECK='Both';
      NO_ASSERT_CHECK='TRUE';
      NO_DIR_CHECK='TRUE';
      ALLOW_CONNECT='TRUE';
  end_pin;
  body
      PART_NAME='PCA9539RPW';
      BODY_NAME='PCA9539RPW';
      PHYS_DES_PREFIX='U';
      CLASS='IC';
      STANDARD='';
      LIFECYCLE='';
      PART_NUMBER='AL009539K07';
      JEDEC_TYPE='TSSOP24XB';
      DESCRIPTION='IC OTHER(24P)PCA9539RPW(TSSOP)';
      MANUFTR='NXP';
      MANUF_PN='PCA9539RPW';
      RD_CMPLS_LVL='EP(V1)';
      CMPLS_LVL='EP(V1)';
      FROM_PJ='S5C-KEVIN';
      DIP_SMD='';
      DATA='NXP_PCA9539RPW.pdf';
      EE_CHECK_LIST='';
      FP_ECN='';
      PSL='';
      CREATOR='';
      STATUS='';
      MSD='NA';
      ESD_CDM='NA';
      ESD_HBM='NA';
      ESD_MM='NA';
      PIN_LENGTH_SHORT_PIN='0 MILS';
      PIN_LENGTH_LONG_PIN='0 MILS';
      CREATEDAY='20180717';
      PARENT_PART_TYPE='PCA9539RPW';
      PARENT_PPT='PCA9539RPW';
      PARENT_PPT_PART='PCA9539RPW-PCA9539RPW,SMLF,IC,AL009539K07';
  end_body;
end_primitive;
primitive 'PCA9617ADP-PCA9617ADP,SMLF,EMPTY,AL009617K02';
  pin
    'EN':
      PIN_NUMBER='(5)';
      INPUT_LOAD='(-0.01,0.01)';
      PINUSE='IN';
    'VCCA':
      PIN_NUMBER='(1)';
      PINUSE='POWER';
      NO_LOAD_CHECK='Both';
      NO_IO_CHECK='Both';
      NO_ASSERT_CHECK='TRUE';
      NO_DIR_CHECK='TRUE';
      ALLOW_CONNECT='TRUE';
    'VCCB':
      PIN_NUMBER='(8)';
      PINUSE='POWER';
      NO_LOAD_CHECK='Both';
      NO_IO_CHECK='Both';
      NO_ASSERT_CHECK='TRUE';
      NO_DIR_CHECK='TRUE';
      ALLOW_CONNECT='TRUE';
    'SCLA':
      PIN_NUMBER='(2)';
      BIDIRECTIONAL='TRUE';
      INPUT_LOAD='(-0.01,0.01)';
      OUTPUT_LOAD='(1.0,-1.0)';
      PINUSE='BI';
    'SDAA':
      PIN_NUMBER='(3)';
      BIDIRECTIONAL='TRUE';
      INPUT_LOAD='(-0.01,0.01)';
      OUTPUT_LOAD='(1.0,-1.0)';
      PINUSE='BI';
    'SDAB':
      PIN_NUMBER='(6)';
      BIDIRECTIONAL='TRUE';
      INPUT_LOAD='(-0.01,0.01)';
      OUTPUT_LOAD='(1.0,-1.0)';
      PINUSE='BI';
    'SCLB':
      PIN_NUMBER='(7)';
      BIDIRECTIONAL='TRUE';
      INPUT_LOAD='(-0.01,0.01)';
      OUTPUT_LOAD='(1.0,-1.0)';
      PINUSE='BI';
    'GND':
      PIN_NUMBER='(4)';
      PINUSE='POWER';
      NO_LOAD_CHECK='Both';
      NO_IO_CHECK='Both';
      NO_ASSERT_CHECK='TRUE';
      NO_DIR_CHECK='TRUE';
      ALLOW_CONNECT='TRUE';
  end_pin;
  body
      PART_NAME='PCA9617ADP';
      BODY_NAME='PCA9617ADP';
      PHYS_DES_PREFIX='U';
      CLASS='IC';
      STANDARD='';
      LIFECYCLE='';
      PART_NUMBER='AL009617K02';
      JEDEC_TYPE='TSSOP8_3XB';
      DESCRIPTION='IC OTHER(8P) PCA9617ADP(TSSOP)';
      MANUFTR='NXP';
      MANUF_PN='PCA9617ADP';
      RD_CMPLS_LVL='EP(V1)';
      CMPLS_LVL='';
      FROM_PJ='S1U-OWEN';
      DIP_SMD='';
      DATA='NXP_PCA9617A.pdf';
      EE_CHECK_LIST='';
      FP_ECN='';
      PSL='';
      CREATOR='';
      STATUS='';
      CREATEDAY='20140410';
      PARENT_PART_TYPE='PCA9617ADP';
      PARENT_PPT='PCA9617ADP';
      PARENT_PPT_PART='PCA9617ADP-PCA9617ADP,SMLF,EMPTY,AL009617K02';
  end_body;
end_primitive;
primitive 'PCA9617ADP-PCA9617ADP,SMLF,IC,AL009617K02';
  pin
    'EN':
      PIN_NUMBER='(5)';
      INPUT_LOAD='(-0.01,0.01)';
      PINUSE='IN';
    'VCCA':
      PIN_NUMBER='(1)';
      PINUSE='POWER';
      NO_LOAD_CHECK='Both';
      NO_IO_CHECK='Both';
      NO_ASSERT_CHECK='TRUE';
      NO_DIR_CHECK='TRUE';
      ALLOW_CONNECT='TRUE';
    'VCCB':
      PIN_NUMBER='(8)';
      PINUSE='POWER';
      NO_LOAD_CHECK='Both';
      NO_IO_CHECK='Both';
      NO_ASSERT_CHECK='TRUE';
      NO_DIR_CHECK='TRUE';
      ALLOW_CONNECT='TRUE';
    'SCLA':
      PIN_NUMBER='(2)';
      BIDIRECTIONAL='TRUE';
      INPUT_LOAD='(-0.01,0.01)';
      OUTPUT_LOAD='(1.0,-1.0)';
      PINUSE='BI';
    'SDAA':
      PIN_NUMBER='(3)';
      BIDIRECTIONAL='TRUE';
      INPUT_LOAD='(-0.01,0.01)';
      OUTPUT_LOAD='(1.0,-1.0)';
      PINUSE='BI';
    'SDAB':
      PIN_NUMBER='(6)';
      BIDIRECTIONAL='TRUE';
      INPUT_LOAD='(-0.01,0.01)';
      OUTPUT_LOAD='(1.0,-1.0)';
      PINUSE='BI';
    'SCLB':
      PIN_NUMBER='(7)';
      BIDIRECTIONAL='TRUE';
      INPUT_LOAD='(-0.01,0.01)';
      OUTPUT_LOAD='(1.0,-1.0)';
      PINUSE='BI';
    'GND':
      PIN_NUMBER='(4)';
      PINUSE='POWER';
      NO_LOAD_CHECK='Both';
      NO_IO_CHECK='Both';
      NO_ASSERT_CHECK='TRUE';
      NO_DIR_CHECK='TRUE';
      ALLOW_CONNECT='TRUE';
  end_pin;
  body
      PART_NAME='PCA9617ADP';
      BODY_NAME='PCA9617ADP';
      PHYS_DES_PREFIX='U';
      CLASS='IC';
      STANDARD='';
      LIFECYCLE='';
      PART_NUMBER='AL009617K02';
      JEDEC_TYPE='TSSOP8_3XB';
      DESCRIPTION='IC OTHER(8P) PCA9617ADP(TSSOP)';
      MANUFTR='NXP';
      MANUF_PN='PCA9617ADP';
      RD_CMPLS_LVL='EP(V1)';
      CMPLS_LVL='';
      FROM_PJ='S1U-OWEN';
      DIP_SMD='';
      DATA='NXP_PCA9617A.pdf';
      EE_CHECK_LIST='';
      FP_ECN='';
      PSL='';
      CREATOR='';
      STATUS='';
      CREATEDAY='20140410';
      PARENT_PART_TYPE='PCA9617ADP';
      PARENT_PPT='PCA9617ADP';
      PARENT_PPT_PART='PCA9617ADP-PCA9617ADP,SMLF,IC,AL009617K02';
  end_body;
end_primitive;
primitive 'PI3CSW12ZUAEX-PI3CSW12ZUAEX,SMLF,IC,AL3CSW12000';
  pin
    '1D+':
      PIN_NUMBER='(1)';
      BIDIRECTIONAL='TRUE';
      INPUT_LOAD='(-0.01,0.01)';
      OUTPUT_LOAD='(1.0,-1.0)';
      PINUSE='BI';
    '2D+':
      PIN_NUMBER='(3)';
      BIDIRECTIONAL='TRUE';
      INPUT_LOAD='(-0.01,0.01)';
      OUTPUT_LOAD='(1.0,-1.0)';
      PINUSE='BI';
    '2D-':
      PIN_NUMBER='(4)';
      BIDIRECTIONAL='TRUE';
      INPUT_LOAD='(-0.01,0.01)';
      OUTPUT_LOAD='(1.0,-1.0)';
      PINUSE='BI';
    'D-':
      PIN_NUMBER='(7)';
      BIDIRECTIONAL='TRUE';
      INPUT_LOAD='(-0.01,0.01)';
      OUTPUT_LOAD='(1.0,-1.0)';
      PINUSE='BI';
    'OE#':
      PIN_NUMBER='(6)';
      INPUT_LOAD='(-0.01,0.01)';
      PINUSE='IN';
    'S':
      PIN_NUMBER='(9)';
      INPUT_LOAD='(-0.01,0.01)';
      PINUSE='IN';
    'VDD':
      PIN_NUMBER='(10)';
      PINUSE='POWER';
      NO_LOAD_CHECK='Both';
      NO_IO_CHECK='Both';
      NO_ASSERT_CHECK='TRUE';
      NO_DIR_CHECK='TRUE';
      ALLOW_CONNECT='TRUE';
    '1D-':
      PIN_NUMBER='(2)';
      BIDIRECTIONAL='TRUE';
      INPUT_LOAD='(-0.01,0.01)';
      OUTPUT_LOAD='(1.0,-1.0)';
      PINUSE='BI';
    'GND':
      PIN_NUMBER='(5)';
      PINUSE='POWER';
      NO_LOAD_CHECK='Both';
      NO_IO_CHECK='Both';
      NO_ASSERT_CHECK='TRUE';
      NO_DIR_CHECK='TRUE';
      ALLOW_CONNECT='TRUE';
    'D+':
      PIN_NUMBER='(8)';
      BIDIRECTIONAL='TRUE';
      INPUT_LOAD='(-0.01,0.01)';
      OUTPUT_LOAD='(1.0,-1.0)';
      PINUSE='BI';
  end_pin;
  body
      PART_NAME='PI3CSW12ZUAEX';
      BODY_NAME='PI3CSW12ZUAEX';
      PHYS_DES_PREFIX='U';
      CLASS='IC';
      STANDARD='';
      LIFECYCLE='';
      PART_NUMBER='AL3CSW12000';
      JEDEC_TYPE='UQFN10_0-5_2X1-5';
      DESCRIPTION='IC(10P)PI3CSW12ZUAEX(UQFN)';
      MANUFTR='DDS';
      MANUF_PN='PI3CSW12ZUAEX';
      RD_CMPLS_LVL='EP(V1)';
      CMPLS_LVL='';
      FROM_PJ='S6Z-TOM';
      DIP_SMD='';
      DATA='DDS_PI3CSW12ZUAEX.pdf';
      EE_CHECK_LIST='';
      FP_ECN='';
      PSL='';
      CREATOR='';
      STATUS='';
      MSD='';
      ESD_CDM='';
      ESD_HBM='';
      ESD_MM='';
      PIN_LENGTH_SHORT_PIN='0 MILS';
      PIN_LENGTH_LONG_PIN='0 MILS';
      CREATEDAY='20210331';
      PARENT_PART_TYPE='PI3CSW12ZUAEX';
      PARENT_PPT='PI3CSW12ZUAEX';
      PARENT_PPT_PART='PI3CSW12ZUAEX-PI3CSW12ZUAEX,SMLF,IC,AL3CSW12000';
  end_body;
end_primitive;
primitive 'PI3EQX12902AZLEX-PI3EQX12902AZLEX,SMLF,IC,AL012902A';
  pin
    'VDD1':
      PIN_NUMBER='(1)';
      PINUSE='POWER';
      NO_LOAD_CHECK='Both';
      NO_IO_CHECK='Both';
      NO_ASSERT_CHECK='TRUE';
      NO_DIR_CHECK='TRUE';
      ALLOW_CONNECT='TRUE';
    'AIP':
      PIN_NUMBER='(2)';
      INPUT_LOAD='(-0.01,0.01)';
      PINUSE='IN';
    'AIN':
      PIN_NUMBER='(3)';
      INPUT_LOAD='(-0.01,0.01)';
      PINUSE='IN';
    'GND1':
      PIN_NUMBER='(4)';
      PINUSE='POWER';
      NO_LOAD_CHECK='Both';
      NO_IO_CHECK='Both';
      NO_ASSERT_CHECK='TRUE';
      NO_DIR_CHECK='TRUE';
      ALLOW_CONNECT='TRUE';
    'TEST#':
      PIN_NUMBER='(5)';
      INPUT_LOAD='(-0.01,0.01)';
      PINUSE='IN';
    'GND2':
      PIN_NUMBER='(6)';
      PINUSE='POWER';
      NO_LOAD_CHECK='Both';
      NO_IO_CHECK='Both';
      NO_ASSERT_CHECK='TRUE';
      NO_DIR_CHECK='TRUE';
      ALLOW_CONNECT='TRUE';
    'GND3':
      PIN_NUMBER='(7)';
      PINUSE='POWER';
      NO_LOAD_CHECK='Both';
      NO_IO_CHECK='Both';
      NO_ASSERT_CHECK='TRUE';
      NO_DIR_CHECK='TRUE';
      ALLOW_CONNECT='TRUE';
    'BON':
      PIN_NUMBER='(8)';
      OUTPUT_LOAD='(1.0,-1.0)';
      PINUSE='OUT';
    'BOP':
      PIN_NUMBER='(9)';
      OUTPUT_LOAD='(1.0,-1.0)';
      PINUSE='OUT';
    'VDD2':
      PIN_NUMBER='(10)';
      PINUSE='POWER';
      NO_LOAD_CHECK='Both';
      NO_IO_CHECK='Both';
      NO_ASSERT_CHECK='TRUE';
      NO_DIR_CHECK='TRUE';
      ALLOW_CONNECT='TRUE';
    'EN#':
      PIN_NUMBER='(11)';
      INPUT_LOAD='(-0.01,0.01)';
      PINUSE='IN';
    'SWB':
      PIN_NUMBER='(12)';
      INPUT_LOAD='(-0.01,0.01)';
      PINUSE='IN';
    'GND4':
      PIN_NUMBER='(13)';
      PINUSE='POWER';
      NO_LOAD_CHECK='Both';
      NO_IO_CHECK='Both';
      NO_ASSERT_CHECK='TRUE';
      NO_DIR_CHECK='TRUE';
      ALLOW_CONNECT='TRUE';
    'FGB':
      PIN_NUMBER='(14)';
      INPUT_LOAD='(-0.01,0.01)';
      PINUSE='IN';
    'EQB1':
      PIN_NUMBER='(15)';
      INPUT_LOAD='(-0.01,0.01)';
      PINUSE='IN';
    'VDD3':
      PIN_NUMBER='(16)';
      PINUSE='POWER';
      NO_LOAD_CHECK='Both';
      NO_IO_CHECK='Both';
      NO_ASSERT_CHECK='TRUE';
      NO_DIR_CHECK='TRUE';
      ALLOW_CONNECT='TRUE';
    'BIP':
      PIN_NUMBER='(17)';
      INPUT_LOAD='(-0.01,0.01)';
      PINUSE='IN';
    'BIN':
      PIN_NUMBER='(18)';
      INPUT_LOAD='(-0.01,0.01)';
      PINUSE='IN';
    'GND5':
      PIN_NUMBER='(19)';
      PINUSE='POWER';
      NO_LOAD_CHECK='Both';
      NO_IO_CHECK='Both';
      NO_ASSERT_CHECK='TRUE';
      NO_DIR_CHECK='TRUE';
      ALLOW_CONNECT='TRUE';
    'EQB0':
      PIN_NUMBER='(20)';
      INPUT_LOAD='(-0.01,0.01)';
      PINUSE='IN';
    'EQA0':
      PIN_NUMBER='(21)';
      INPUT_LOAD='(-0.01,0.01)';
      PINUSE='IN';
    'GND6':
      PIN_NUMBER='(22)';
      PINUSE='POWER';
      NO_LOAD_CHECK='Both';
      NO_IO_CHECK='Both';
      NO_ASSERT_CHECK='TRUE';
      NO_DIR_CHECK='TRUE';
      ALLOW_CONNECT='TRUE';
    'AON':
      PIN_NUMBER='(23)';
      OUTPUT_LOAD='(1.0,-1.0)';
      PINUSE='OUT';
    'AOP':
      PIN_NUMBER='(24)';
      OUTPUT_LOAD='(1.0,-1.0)';
      PINUSE='OUT';
    'VDD4':
      PIN_NUMBER='(25)';
      PINUSE='POWER';
      NO_LOAD_CHECK='Both';
      NO_IO_CHECK='Both';
      NO_ASSERT_CHECK='TRUE';
      NO_DIR_CHECK='TRUE';
      ALLOW_CONNECT='TRUE';
    'EQA1':
      PIN_NUMBER='(26)';
      INPUT_LOAD='(-0.01,0.01)';
      PINUSE='IN';
    'FGA':
      PIN_NUMBER='(27)';
      INPUT_LOAD='(-0.01,0.01)';
      PINUSE='IN';
    'GND7':
      PIN_NUMBER='(28)';
      PINUSE='POWER';
      NO_LOAD_CHECK='Both';
      NO_IO_CHECK='Both';
      NO_ASSERT_CHECK='TRUE';
      NO_DIR_CHECK='TRUE';
      ALLOW_CONNECT='TRUE';
    'SWA':
      PIN_NUMBER='(29)';
      INPUT_LOAD='(-0.01,0.01)';
      PINUSE='IN';
    'MODE':
      PIN_NUMBER='(30)';
      INPUT_LOAD='(-0.01,0.01)';
      PINUSE='IN';
    'GND_TH':
      PIN_NUMBER='(TH)';
      PINUSE='POWER';
      NO_LOAD_CHECK='Both';
      NO_IO_CHECK='Both';
      NO_ASSERT_CHECK='TRUE';
      NO_DIR_CHECK='TRUE';
      ALLOW_CONNECT='TRUE';
  end_pin;
  body
      PART_NAME='PI3EQX12902AZLEX';
      BODY_NAME='PI3EQX12902AZLEX';
      PHYS_DES_PREFIX='U';
      CLASS='IC';
      STANDARD='';
      LIFECYCLE='';
      PART_NUMBER='AL012902001';
      JEDEC_TYPE='TQFN30_TH_0-4_4-5X2-5';
      DESCRIPTION='IC OTHER(30P)PI3EQX12902AZLEX(TQFN)';
      MANUFTR='PIM';
      MANUF_PN='PI3EQX12902AZLEX';
      RD_CMPLS_LVL='EP(V1)';
      CMPLS_LVL='';
      FROM_PJ='MF5-KYLE';
      DIP_SMD='';
      DATA='PIM_PI3EQX12902AZLEX.pdf';
      EE_CHECK_LIST='';
      FP_ECN='';
      PSL='';
      CREATOR='';
      STATUS='';
      MSD='NA';
      ESD_CDM='+-500V';
      ESD_HBM='+-2kV';
      ESD_MM='NA';
      PIN_LENGTH_SHORT_PIN='0 MILS';
      PIN_LENGTH_LONG_PIN='0 MILS';
      CREATEDAY='20170824';
      PARENT_PART_TYPE='PI3EQX12902AZLEX';
      PARENT_PPT='PI3EQX12902AZLEX';
      PARENT_PPT_PART='PI3EQX12902AZLEX-PI3EQX12902AZLEX,SMLF,IC,AL012902001';
  end_body;
end_primitive;
primitive 'PI4ULS3V304AZMAEX-PI4ULS3V304AZMAEX,SMLF,IC,AL0003A';
  pin
    'A1':
      PIN_NUMBER='(2)';
      BIDIRECTIONAL='TRUE';
      INPUT_LOAD='(-0.01,0.01)';
      OUTPUT_LOAD='(1.0,-1.0)';
      PINUSE='BI';
    'A2':
      PIN_NUMBER='(3)';
      BIDIRECTIONAL='TRUE';
      INPUT_LOAD='(-0.01,0.01)';
      OUTPUT_LOAD='(1.0,-1.0)';
      PINUSE='BI';
    'A3':
      PIN_NUMBER='(4)';
      BIDIRECTIONAL='TRUE';
      INPUT_LOAD='(-0.01,0.01)';
      OUTPUT_LOAD='(1.0,-1.0)';
      PINUSE='BI';
    'VCCB':
      PIN_NUMBER='(11)';
      PINUSE='POWER';
      NO_LOAD_CHECK='Both';
      NO_IO_CHECK='Both';
      NO_ASSERT_CHECK='TRUE';
      NO_DIR_CHECK='TRUE';
      ALLOW_CONNECT='TRUE';
    'EN':
      PIN_NUMBER='(12)';
      INPUT_LOAD='(-0.01,0.01)';
      PINUSE='IN';
    'A4':
      PIN_NUMBER='(5)';
      BIDIRECTIONAL='TRUE';
      INPUT_LOAD='(-0.01,0.01)';
      OUTPUT_LOAD='(1.0,-1.0)';
      PINUSE='BI';
    'VCCA':
      PIN_NUMBER='(1)';
      PINUSE='POWER';
      NO_LOAD_CHECK='Both';
      NO_IO_CHECK='Both';
      NO_ASSERT_CHECK='TRUE';
      NO_DIR_CHECK='TRUE';
      ALLOW_CONNECT='TRUE';
    'B1':
      PIN_NUMBER='(10)';
      BIDIRECTIONAL='TRUE';
      INPUT_LOAD='(-0.01,0.01)';
      OUTPUT_LOAD='(1.0,-1.0)';
      PINUSE='BI';
    'B2':
      PIN_NUMBER='(9)';
      BIDIRECTIONAL='TRUE';
      INPUT_LOAD='(-0.01,0.01)';
      OUTPUT_LOAD='(1.0,-1.0)';
      PINUSE='BI';
    'B3':
      PIN_NUMBER='(8)';
      BIDIRECTIONAL='TRUE';
      INPUT_LOAD='(-0.01,0.01)';
      OUTPUT_LOAD='(1.0,-1.0)';
      PINUSE='BI';
    'B4':
      PIN_NUMBER='(7)';
      BIDIRECTIONAL='TRUE';
      INPUT_LOAD='(-0.01,0.01)';
      OUTPUT_LOAD='(1.0,-1.0)';
      PINUSE='BI';
    'GND':
      PIN_NUMBER='(6)';
      PINUSE='POWER';
      NO_LOAD_CHECK='Both';
      NO_IO_CHECK='Both';
      NO_ASSERT_CHECK='TRUE';
      NO_DIR_CHECK='TRUE';
      ALLOW_CONNECT='TRUE';
  end_pin;
  body
      PART_NAME='PI4ULS3V304AZMAEX';
      BODY_NAME='PI4ULS3V304AZMAEX';
      PHYS_DES_PREFIX='U';
      CLASS='IC';
      STANDARD='';
      LIFECYCLE='';
      PART_NUMBER='AL000304005';
      JEDEC_TYPE='UQFN12_0-4_2X1-7';
      DESCRIPTION='IC(12P)PI4ULS3V304AZMAEX(UQFN)';
      MANUFTR='DDS';
      MANUF_PN='PI4ULS3V304AZMAEX';
      RD_CMPLS_LVL='EP(V1)';
      CMPLS_LVL='';
      FROM_PJ='T6G-JOHN';
      DIP_SMD='';
      DATA='DDS_PI4ULS3V304AZMAEX.pdf';
      EE_CHECK_LIST='';
      FP_ECN='';
      PSL='';
      CREATOR='';
      STATUS='';
      MSD='';
      ESD_CDM='';
      ESD_HBM='';
      ESD_MM='';
      PIN_LENGTH_SHORT_PIN='0 MILS';
      PIN_LENGTH_LONG_PIN='0 MILS';
      CREATEDAY='20211004';
      PARENT_PART_TYPE='PI4ULS3V304AZMAEX';
      PARENT_PPT='PI4ULS3V304AZMAEX';
      PARENT_PPT_PART='PI4ULS3V304AZMAEX-PI4ULS3V304AZMAEX,SMLF,IC,AL000304005';
  end_body;
end_primitive;
primitive 'PI6CV304LE-PI6CV304LE,SMLF,IC,AL000304K01';
  pin
    'CLK_IN':
      PIN_NUMBER='(1)';
      INPUT_LOAD='(-0.01,0.01)';
      PINUSE='IN';
    'OE':
      PIN_NUMBER='(2)';
      INPUT_LOAD='(-0.01,0.01)';
      PINUSE='IN';
    'Y0':
      PIN_NUMBER='(3)';
      OUTPUT_LOAD='(1.0,-1.0)';
      PINUSE='OUT';
    'Y1':
      PIN_NUMBER='(5)';
      OUTPUT_LOAD='(1.0,-1.0)';
      PINUSE='OUT';
    'Y2':
      PIN_NUMBER='(7)';
      OUTPUT_LOAD='(1.0,-1.0)';
      PINUSE='OUT';
    'Y3':
      PIN_NUMBER='(8)';
      OUTPUT_LOAD='(1.0,-1.0)';
      PINUSE='OUT';
    'VDD':
      PIN_NUMBER='(6)';
      PINUSE='POWER';
      NO_LOAD_CHECK='Both';
      NO_IO_CHECK='Both';
      NO_ASSERT_CHECK='TRUE';
      NO_DIR_CHECK='TRUE';
      ALLOW_CONNECT='TRUE';
    'GND':
      PIN_NUMBER='(4)';
      PINUSE='POWER';
      NO_LOAD_CHECK='Both';
      NO_IO_CHECK='Both';
      NO_ASSERT_CHECK='TRUE';
      NO_DIR_CHECK='TRUE';
      ALLOW_CONNECT='TRUE';
  end_pin;
  body
      PART_NAME='PI6CV304LE';
      BODY_NAME='PI6CV304LE';
      PHYS_DES_PREFIX='U';
      CLASS='IC';
      PART_NUMBER='AL000304K01';
      JEDEC_TYPE='TSSOP8';
      DESCRIPTION='IC OTHER(8P) PI6CV304LE(TSSOP)';
      MANUFTR='PIM';
      MANUF_PN='PI6CV304LE';
      RD_CMPLS_LVL='EP';
      CMPLS_LVL='EP';
      FROM_PJ='S4E-JAMES';
      DIP_SMD='';
      DATA='PI6CV304_PI6CV2304.pdf';
      EE_CHECK_LIST='';
      FP_ECN='';
      PSL='';
      LIFECYCLE='';
      CREATOR='';
      STANDARD='';
      CREATEDAY='20111206';
      STATUS='';
      PARENT_PART_TYPE='PI6CV304LE';
      PARENT_PPT='PI6CV304LE';
      PARENT_PPT_PART='PI6CV304LE-PI6CV304LE,SMLF,IC,AL000304K01';
  end_body;
end_primitive;
primitive 'PICOPROBE_BXA-DELTA-L 4.0,SMLF,EMPTY,TP33';
  pin
    '2_N':
      PIN_NUMBER='(2)';
      PINUSE='POWER';
      NO_LOAD_CHECK='Both';
      NO_IO_CHECK='Both';
      NO_ASSERT_CHECK='TRUE';
      NO_DIR_CHECK='TRUE';
      ALLOW_CONNECT='TRUE';
    '3_G':
      PIN_NUMBER='(3)';
      PINUSE='POWER';
      NO_LOAD_CHECK='Both';
      NO_IO_CHECK='Both';
      NO_ASSERT_CHECK='TRUE';
      NO_DIR_CHECK='TRUE';
      ALLOW_CONNECT='TRUE';
    '1_P':
      PIN_NUMBER='(1)';
      PINUSE='POWER';
      NO_LOAD_CHECK='Both';
      NO_IO_CHECK='Both';
      NO_ASSERT_CHECK='TRUE';
      NO_DIR_CHECK='TRUE';
      ALLOW_CONNECT='TRUE';
  end_pin;
  body
      PART_NAME='PICOPROBE_BXA';
      BODY_NAME='PICOPROBE_BXA';
      PHYS_DES_PREFIX='J';
      CLASS='IO';
      STANDARD='';
      LIFECYCLE='';
      PART_NUMBER='TP33';
      JEDEC_TYPE='TRIANG_LAUNCH_3PXB';
      ALT_SYMBOLS='';
      DESCRIPTION='Probe for DELTA-L 4.0 measurement';
      MANUFTR='';
      MANUF_PN='';
      RD_CMPLS_LVL='';
      CMPLS_LVL='';
      DIP_SMD='';
      FROM_PJ='';
      DATA='TRIANG_LAUNCH_3PXB.pdf';
      FP_ECN='TRIANG_LAUNCH_3PXB.xlsx';
      EE_CHECK_LIST='';
      STATUS='';
      PSL='';
      PREFERENCE='';
      CREATOR='';
      CREATEDAY='20200107';
      ESD_CDM='';
      ESD_HBM='';
      ESD_MM='';
      MSD='';
      PIN_LENGTH_LONG_PIN='';
      PIN_LENGTH_SHORT_PIN='';
      PARENT_PART_TYPE='PICOPROBE_BXA';
      PARENT_PPT='PICOPROBE_BXA';
      PARENT_PPT_PART='PICOPROBE_BXA-DELTA-L 4.0,SMLF,EMPTY,TP33';
  end_body;
end_primitive;
primitive 'PT5161LRS-PT5161LRS,SMLF,IC,AJ051610U03';
  pin
    'A_PERP0':
      PIN_NUMBER='(R1,0,0,0,0,0,0,0,0,0,0)';
      INPUT_LOAD='(-0.01,0.01)';
      PINUSE='IN';
    'A_PERN0':
      PIN_NUMBER='(N2,0,0,0,0,0,0,0,0,0,0)';
      INPUT_LOAD='(-0.01,0.01)';
      PINUSE='IN';
    'A_PERP1':
      PIN_NUMBER='(AB1,0,0,0,0,0,0,0,0,0,0)';
      INPUT_LOAD='(-0.01,0.01)';
      PINUSE='IN';
    'A_PERN1':
      PIN_NUMBER='(Y2,0,0,0,0,0,0,0,0,0,0)';
      INPUT_LOAD='(-0.01,0.01)';
      PINUSE='IN';
    'A_PERP2':
      PIN_NUMBER='(AJ1,0,0,0,0,0,0,0,0,0,0)';
      INPUT_LOAD='(-0.01,0.01)';
      PINUSE='IN';
    'A_PERN2':
      PIN_NUMBER='(AG2,0,0,0,0,0,0,0,0,0,0)';
      INPUT_LOAD='(-0.01,0.01)';
      PINUSE='IN';
    'A_PERP3':
      PIN_NUMBER='(AT1,0,0,0,0,0,0,0,0,0,0)';
      INPUT_LOAD='(-0.01,0.01)';
      PINUSE='IN';
    'A_PERN3':
      PIN_NUMBER='(AP2,0,0,0,0,0,0,0,0,0,0)';
      INPUT_LOAD='(-0.01,0.01)';
      PINUSE='IN';
    'A_PERP4':
      PIN_NUMBER='(BC1,0,0,0,0,0,0,0,0,0,0)';
      INPUT_LOAD='(-0.01,0.01)';
      PINUSE='IN';
    'A_PERN4':
      PIN_NUMBER='(BA2,0,0,0,0,0,0,0,0,0,0)';
      INPUT_LOAD='(-0.01,0.01)';
      PINUSE='IN';
    'A_PERP5':
      PIN_NUMBER='(BK1,0,0,0,0,0,0,0,0,0,0)';
      INPUT_LOAD='(-0.01,0.01)';
      PINUSE='IN';
    'A_PERN5':
      PIN_NUMBER='(BH2,0,0,0,0,0,0,0,0,0,0)';
      INPUT_LOAD='(-0.01,0.01)';
      PINUSE='IN';
    'A_PERP6':
      PIN_NUMBER='(BU1,0,0,0,0,0,0,0,0,0,0)';
      INPUT_LOAD='(-0.01,0.01)';
      PINUSE='IN';
    'A_PERN6':
      PIN_NUMBER='(BR2,0,0,0,0,0,0,0,0,0,0)';
      INPUT_LOAD='(-0.01,0.01)';
      PINUSE='IN';
    'A_PERP7':
      PIN_NUMBER='(CD1,0,0,0,0,0,0,0,0,0,0)';
      INPUT_LOAD='(-0.01,0.01)';
      PINUSE='IN';
    'A_PERN7':
      PIN_NUMBER='(CB2,0,0,0,0,0,0,0,0,0,0)';
      INPUT_LOAD='(-0.01,0.01)';
      PINUSE='IN';
    'A_PERP8':
      PIN_NUMBER='(0,CL1,0,0,0,0,0,0,0,0,0)';
      INPUT_LOAD='(-0.01,0.01)';
      PINUSE='IN';
    'A_PERN8':
      PIN_NUMBER='(0,CJ2,0,0,0,0,0,0,0,0,0)';
      INPUT_LOAD='(-0.01,0.01)';
      PINUSE='IN';
    'A_PERP9':
      PIN_NUMBER='(0,CV1,0,0,0,0,0,0,0,0,0)';
      INPUT_LOAD='(-0.01,0.01)';
      PINUSE='IN';
    'A_PERN9':
      PIN_NUMBER='(0,CT2,0,0,0,0,0,0,0,0,0)';
      INPUT_LOAD='(-0.01,0.01)';
      PINUSE='IN';
    'A_PERP10':
      PIN_NUMBER='(0,DE1,0,0,0,0,0,0,0,0,0)';
      INPUT_LOAD='(-0.01,0.01)';
      PINUSE='IN';
    'A_PERN10':
      PIN_NUMBER='(0,DC2,0,0,0,0,0,0,0,0,0)';
      INPUT_LOAD='(-0.01,0.01)';
      PINUSE='IN';
    'A_PERP11':
      PIN_NUMBER='(0,DM1,0,0,0,0,0,0,0,0,0)';
      INPUT_LOAD='(-0.01,0.01)';
      PINUSE='IN';
    'A_PERN11':
      PIN_NUMBER='(0,DK2,0,0,0,0,0,0,0,0,0)';
      INPUT_LOAD='(-0.01,0.01)';
      PINUSE='IN';
    'A_PERP12':
      PIN_NUMBER='(0,DW1,0,0,0,0,0,0,0,0,0)';
      INPUT_LOAD='(-0.01,0.01)';
      PINUSE='IN';
    'A_PERN12':
      PIN_NUMBER='(0,DU2,0,0,0,0,0,0,0,0,0)';
      INPUT_LOAD='(-0.01,0.01)';
      PINUSE='IN';
    'A_PERP13':
      PIN_NUMBER='(0,EF1,0,0,0,0,0,0,0,0,0)';
      INPUT_LOAD='(-0.01,0.01)';
      PINUSE='IN';
    'A_PERN13':
      PIN_NUMBER='(0,ED2,0,0,0,0,0,0,0,0,0)';
      INPUT_LOAD='(-0.01,0.01)';
      PINUSE='IN';
    'A_PERP14':
      PIN_NUMBER='(0,EN1,0,0,0,0,0,0,0,0,0)';
      INPUT_LOAD='(-0.01,0.01)';
      PINUSE='IN';
    'A_PERN14':
      PIN_NUMBER='(0,EL2,0,0,0,0,0,0,0,0,0)';
      INPUT_LOAD='(-0.01,0.01)';
      PINUSE='IN';
    'A_PERP15':
      PIN_NUMBER='(0,EY1,0,0,0,0,0,0,0,0,0)';
      INPUT_LOAD='(-0.01,0.01)';
      PINUSE='IN';
    'A_PERN15':
      PIN_NUMBER='(0,EV2,0,0,0,0,0,0,0,0,0)';
      INPUT_LOAD='(-0.01,0.01)';
      PINUSE='IN';
    'GPIO0':
      PIN_NUMBER='(0,0,FJ6,0,0,0,0,0,0,0,0)';
      BIDIRECTIONAL='TRUE';
      INPUT_LOAD='(-0.01,0.01)';
      OUTPUT_LOAD='(1.0,-1.0)';
      PINUSE='BI';
    'GPIO1':
      PIN_NUMBER='(0,0,FJ23,0,0,0,0,0,0,0,0)';
      BIDIRECTIONAL='TRUE';
      INPUT_LOAD='(-0.01,0.01)';
      OUTPUT_LOAD='(1.0,-1.0)';
      PINUSE='BI';
    'GPIO2':
      PIN_NUMBER='(0,0,FJ25,0,0,0,0,0,0,0,0)';
      BIDIRECTIONAL='TRUE';
      INPUT_LOAD='(-0.01,0.01)';
      OUTPUT_LOAD='(1.0,-1.0)';
      PINUSE='BI';
    'GPIO3':
      PIN_NUMBER='(0,0,FJ28,0,0,0,0,0,0,0,0)';
      BIDIRECTIONAL='TRUE';
      INPUT_LOAD='(-0.01,0.01)';
      OUTPUT_LOAD='(1.0,-1.0)';
      PINUSE='BI';
    'INT_N':
      PIN_NUMBER='(0,0,FJ31,0,0,0,0,0,0,0,0)';
      OUTPUT_LOAD='(1.0,-1.0)';
      PINUSE='OUT';
    'JTAG_TCK':
      PIN_NUMBER='(0,0,B3,0,0,0,0,0,0,0,0)';
      INPUT_LOAD='(-0.01,0.01)';
      PINUSE='IN';
    'JTAG_TDI':
      PIN_NUMBER='(0,0,B6,0,0,0,0,0,0,0,0)';
      INPUT_LOAD='(-0.01,0.01)';
      PINUSE='IN';
    'JTAG_TDO':
      PIN_NUMBER='(0,0,B9,0,0,0,0,0,0,0,0)';
      OUTPUT_LOAD='(1.0,-1.0)';
      PINUSE='OUT';
    'JTAG_TEST_MODE':
      PIN_NUMBER='(0,0,FF8,0,0,0,0,0,0,0,0)';
      INPUT_LOAD='(-0.01,0.01)';
      PINUSE='IN';
    'JTAG_TMS':
      PIN_NUMBER='(0,0,B12,0,0,0,0,0,0,0,0)';
      INPUT_LOAD='(-0.01,0.01)';
      PINUSE='IN';
    'JTAG_TRST_N':
      PIN_NUMBER='(0,0,E8,0,0,0,0,0,0,0,0)';
      INPUT_LOAD='(-0.01,0.01)';
      PINUSE='IN';
    'MODE':
      PIN_NUMBER='(0,0,FJ9,0,0,0,0,0,0,0,0)';
      INPUT_LOAD='(-0.01,0.01)';
      PINUSE='IN';
    'PERST_N':
      PIN_NUMBER='(0,0,F2,0,0,0,0,0,0,0,0)';
      INPUT_LOAD='(-0.01,0.01)';
      PINUSE='IN';
    'REFCLK_OUTN':
      PIN_NUMBER='(0,0,E18,0,0,0,0,0,0,0,0)';
      OUTPUT_LOAD='(1.0,-1.0)';
      PINUSE='OUT';
    'REFCLK_OUTP':
      PIN_NUMBER='(0,0,B16,0,0,0,0,0,0,0,0)';
      OUTPUT_LOAD='(1.0,-1.0)';
      PINUSE='OUT';
    'REFCLKN':
      PIN_NUMBER='(0,0,FF18,0,0,0,0,0,0,0,0)';
      INPUT_LOAD='(-0.01,0.01)';
      PINUSE='IN';
    'REFCLKP':
      PIN_NUMBER='(0,0,FJ16,0,0,0,0,0,0,0,0)';
      INPUT_LOAD='(-0.01,0.01)';
      PINUSE='IN';
    'RESET_N':
      PIN_NUMBER='(0,0,FF11,0,0,0,0,0,0,0,0)';
      INPUT_LOAD='(-0.01,0.01)';
      PINUSE='IN';
    'RXDET_BYP':
      PIN_NUMBER='(0,0,E11,0,0,0,0,0,0,0,0)';
      INPUT_LOAD='(-0.01,0.01)';
      PINUSE='IN';
    'SCAN_MODE':
      PIN_NUMBER='(0,0,FF33,0,0,0,0,0,0,0,0)';
      INPUT_LOAD='(-0.01,0.01)';
      PINUSE='IN';
    'SMB_ADDR1':
      PIN_NUMBER='(0,0,F34,0,0,0,0,0,0,0,0)';
      INPUT_LOAD='(-0.01,0.01)';
      PINUSE='IN';
    'SMB_ADDR2':
      PIN_NUMBER='(0,0,B23,0,0,0,0,0,0,0,0)';
      INPUT_LOAD='(-0.01,0.01)';
      PINUSE='IN';
    'SMB_ADDR3':
      PIN_NUMBER='(0,0,B25,0,0,0,0,0,0,0,0)';
      INPUT_LOAD='(-0.01,0.01)';
      PINUSE='IN';
    'SMBCLK':
      PIN_NUMBER='(0,0,B31,0,0,0,0,0,0,0,0)';
      BIDIRECTIONAL='TRUE';
      INPUT_LOAD='(-0.01,0.01)';
      OUTPUT_LOAD='(1.0,-1.0)';
      PINUSE='BI';
    'SMBDAT':
      PIN_NUMBER='(0,0,B28,0,0,0,0,0,0,0,0)';
      BIDIRECTIONAL='TRUE';
      INPUT_LOAD='(-0.01,0.01)';
      OUTPUT_LOAD='(1.0,-1.0)';
      PINUSE='BI';
    'T_SENSE':
      PIN_NUMBER='(0,0,E30,0,0,0,0,0,0,0,0)';
      OUTPUT_LOAD='(1.0,-1.0)';
      PINUSE='OUT';
    'TEST0':
      PIN_NUMBER='(0,0,FF24,0,0,0,0,0,0,0,0)';
      BIDIRECTIONAL='TRUE';
      INPUT_LOAD='(-0.01,0.01)';
      OUTPUT_LOAD='(1.0,-1.0)';
      PINUSE='BI';
    'TEST1':
      PIN_NUMBER='(0,0,FF27,0,0,0,0,0,0,0,0)';
      BIDIRECTIONAL='TRUE';
      INPUT_LOAD='(-0.01,0.01)';
      OUTPUT_LOAD='(1.0,-1.0)';
      PINUSE='BI';
    'TEST2':
      PIN_NUMBER='(0,0,FF30,0,0,0,0,0,0,0,0)';
      BIDIRECTIONAL='TRUE';
      INPUT_LOAD='(-0.01,0.01)';
      OUTPUT_LOAD='(1.0,-1.0)';
      PINUSE='BI';
    'CLKREQ_N':
      PIN_NUMBER='(0,0,G35,0,0,0,0,0,0,0,0)';
      INPUT_LOAD='(-0.01,0.01)';
      PINUSE='IN';
    'EE_CLK':
      PIN_NUMBER='(0,0,FF5,0,0,0,0,0,0,0,0)';
      BIDIRECTIONAL='TRUE';
      INPUT_LOAD='(-0.01,0.01)';
      OUTPUT_LOAD='(1.0,-1.0)';
      PINUSE='BI';
    'EE_DAT':
      PIN_NUMBER='(0,0,FJ3,0,0,0,0,0,0,0,0)';
      BIDIRECTIONAL='TRUE';
      INPUT_LOAD='(-0.01,0.01)';
      OUTPUT_LOAD='(1.0,-1.0)';
      PINUSE='BI';
    'VQPS':
      PIN_NUMBER='(0,0,0,G1,0,0,0,0,0,0,0)';
      INPUT_LOAD='(-0.01,0.01)';
      PINUSE='IN';
    'PWR_1A_1':
      PIN_NUMBER='(0,0,0,BV20,0,0,0,0,0,0,0)';
      PINUSE='POWER';
      NO_LOAD_CHECK='Both';
      NO_IO_CHECK='Both';
      NO_ASSERT_CHECK='TRUE';
      NO_DIR_CHECK='TRUE';
      ALLOW_CONNECT='TRUE';
    'PWR_1A_2':
      PIN_NUMBER='(0,0,0,CE17,0,0,0,0,0,0,0)';
      PINUSE='POWER';
      NO_LOAD_CHECK='Both';
      NO_IO_CHECK='Both';
      NO_ASSERT_CHECK='TRUE';
      NO_DIR_CHECK='TRUE';
      ALLOW_CONNECT='TRUE';
    'PWR_1A_3':
      PIN_NUMBER='(0,0,0,CE20,0,0,0,0,0,0,0)';
      PINUSE='POWER';
      NO_LOAD_CHECK='Both';
      NO_IO_CHECK='Both';
      NO_ASSERT_CHECK='TRUE';
      NO_DIR_CHECK='TRUE';
      ALLOW_CONNECT='TRUE';
    'PWR_1A_4':
      PIN_NUMBER='(0,0,0,CM17,0,0,0,0,0,0,0)';
      PINUSE='POWER';
      NO_LOAD_CHECK='Both';
      NO_IO_CHECK='Both';
      NO_ASSERT_CHECK='TRUE';
      NO_DIR_CHECK='TRUE';
      ALLOW_CONNECT='TRUE';
    'PWR_1A_5':
      PIN_NUMBER='(0,0,0,CM20,0,0,0,0,0,0,0)';
      PINUSE='POWER';
      NO_LOAD_CHECK='Both';
      NO_IO_CHECK='Both';
      NO_ASSERT_CHECK='TRUE';
      NO_DIR_CHECK='TRUE';
      ALLOW_CONNECT='TRUE';
    'PWR_2D_1':
      PIN_NUMBER='(0,0,0,BL17,0,0,0,0,0,0,0)';
      PINUSE='POWER';
      NO_LOAD_CHECK='Both';
      NO_IO_CHECK='Both';
      NO_ASSERT_CHECK='TRUE';
      NO_DIR_CHECK='TRUE';
      ALLOW_CONNECT='TRUE';
    'PWR_2D_2':
      PIN_NUMBER='(0,0,0,BL20,0,0,0,0,0,0,0)';
      PINUSE='POWER';
      NO_LOAD_CHECK='Both';
      NO_IO_CHECK='Both';
      NO_ASSERT_CHECK='TRUE';
      NO_DIR_CHECK='TRUE';
      ALLOW_CONNECT='TRUE';
    'PWR_2D_3':
      PIN_NUMBER='(0,0,0,CW17,0,0,0,0,0,0,0)';
      PINUSE='POWER';
      NO_LOAD_CHECK='Both';
      NO_IO_CHECK='Both';
      NO_ASSERT_CHECK='TRUE';
      NO_DIR_CHECK='TRUE';
      ALLOW_CONNECT='TRUE';
    'PWR_2D_4':
      PIN_NUMBER='(0,0,0,CW20,0,0,0,0,0,0,0)';
      PINUSE='POWER';
      NO_LOAD_CHECK='Both';
      NO_IO_CHECK='Both';
      NO_ASSERT_CHECK='TRUE';
      NO_DIR_CHECK='TRUE';
      ALLOW_CONNECT='TRUE';
    'PWR_1D':
      PIN_NUMBER='(0,0,0,BV17,0,0,0,0,0,0,0)';
      PINUSE='POWER';
      NO_LOAD_CHECK='Both';
      NO_IO_CHECK='Both';
      NO_ASSERT_CHECK='TRUE';
      NO_DIR_CHECK='TRUE';
      ALLOW_CONNECT='TRUE';
    'PWR_2A_1':
      PIN_NUMBER='(0,0,0,AC17,0,0,0,0,0,0,0)';
      PINUSE='POWER';
      NO_LOAD_CHECK='Both';
      NO_IO_CHECK='Both';
      NO_ASSERT_CHECK='TRUE';
      NO_DIR_CHECK='TRUE';
      ALLOW_CONNECT='TRUE';
    'PWR_2A_2':
      PIN_NUMBER='(0,0,0,AC20,0,0,0,0,0,0,0)';
      PINUSE='POWER';
      NO_LOAD_CHECK='Both';
      NO_IO_CHECK='Both';
      NO_ASSERT_CHECK='TRUE';
      NO_DIR_CHECK='TRUE';
      ALLOW_CONNECT='TRUE';
    'PWR_2A_3':
      PIN_NUMBER='(0,0,0,AK17,0,0,0,0,0,0,0)';
      PINUSE='POWER';
      NO_LOAD_CHECK='Both';
      NO_IO_CHECK='Both';
      NO_ASSERT_CHECK='TRUE';
      NO_DIR_CHECK='TRUE';
      ALLOW_CONNECT='TRUE';
    'PWR_2A_4':
      PIN_NUMBER='(0,0,0,AK20,0,0,0,0,0,0,0)';
      PINUSE='POWER';
      NO_LOAD_CHECK='Both';
      NO_IO_CHECK='Both';
      NO_ASSERT_CHECK='TRUE';
      NO_DIR_CHECK='TRUE';
      ALLOW_CONNECT='TRUE';
    'PWR_2A_5':
      PIN_NUMBER='(0,0,0,AU17,0,0,0,0,0,0,0)';
      PINUSE='POWER';
      NO_LOAD_CHECK='Both';
      NO_IO_CHECK='Both';
      NO_ASSERT_CHECK='TRUE';
      NO_DIR_CHECK='TRUE';
      ALLOW_CONNECT='TRUE';
    'PWR_2A_6':
      PIN_NUMBER='(0,0,0,AU20,0,0,0,0,0,0,0)';
      PINUSE='POWER';
      NO_LOAD_CHECK='Both';
      NO_IO_CHECK='Both';
      NO_ASSERT_CHECK='TRUE';
      NO_DIR_CHECK='TRUE';
      ALLOW_CONNECT='TRUE';
    'PWR_2A_7':
      PIN_NUMBER='(0,0,0,BD17,0,0,0,0,0,0,0)';
      PINUSE='POWER';
      NO_LOAD_CHECK='Both';
      NO_IO_CHECK='Both';
      NO_ASSERT_CHECK='TRUE';
      NO_DIR_CHECK='TRUE';
      ALLOW_CONNECT='TRUE';
    'PWR_2A_8':
      PIN_NUMBER='(0,0,0,BD20,0,0,0,0,0,0,0)';
      PINUSE='POWER';
      NO_LOAD_CHECK='Both';
      NO_IO_CHECK='Both';
      NO_ASSERT_CHECK='TRUE';
      NO_DIR_CHECK='TRUE';
      ALLOW_CONNECT='TRUE';
    'PWR_2A_9':
      PIN_NUMBER='(0,0,0,DF17,0,0,0,0,0,0,0)';
      PINUSE='POWER';
      NO_LOAD_CHECK='Both';
      NO_IO_CHECK='Both';
      NO_ASSERT_CHECK='TRUE';
      NO_DIR_CHECK='TRUE';
      ALLOW_CONNECT='TRUE';
    'PWR_2A_10':
      PIN_NUMBER='(0,0,0,DF20,0,0,0,0,0,0,0)';
      PINUSE='POWER';
      NO_LOAD_CHECK='Both';
      NO_IO_CHECK='Both';
      NO_ASSERT_CHECK='TRUE';
      NO_DIR_CHECK='TRUE';
      ALLOW_CONNECT='TRUE';
    'PWR_2A_11':
      PIN_NUMBER='(0,0,0,DN17,0,0,0,0,0,0,0)';
      PINUSE='POWER';
      NO_LOAD_CHECK='Both';
      NO_IO_CHECK='Both';
      NO_ASSERT_CHECK='TRUE';
      NO_DIR_CHECK='TRUE';
      ALLOW_CONNECT='TRUE';
    'PWR_2A_12':
      PIN_NUMBER='(0,0,0,DN20,0,0,0,0,0,0,0)';
      PINUSE='POWER';
      NO_LOAD_CHECK='Both';
      NO_IO_CHECK='Both';
      NO_ASSERT_CHECK='TRUE';
      NO_DIR_CHECK='TRUE';
      ALLOW_CONNECT='TRUE';
    'PWR_2A_13':
      PIN_NUMBER='(0,0,0,DY17,0,0,0,0,0,0,0)';
      PINUSE='POWER';
      NO_LOAD_CHECK='Both';
      NO_IO_CHECK='Both';
      NO_ASSERT_CHECK='TRUE';
      NO_DIR_CHECK='TRUE';
      ALLOW_CONNECT='TRUE';
    'PWR_2A_14':
      PIN_NUMBER='(0,0,0,DY20,0,0,0,0,0,0,0)';
      PINUSE='POWER';
      NO_LOAD_CHECK='Both';
      NO_IO_CHECK='Both';
      NO_ASSERT_CHECK='TRUE';
      NO_DIR_CHECK='TRUE';
      ALLOW_CONNECT='TRUE';
    'PWR_2A_15':
      PIN_NUMBER='(0,0,0,EG17,0,0,0,0,0,0,0)';
      PINUSE='POWER';
      NO_LOAD_CHECK='Both';
      NO_IO_CHECK='Both';
      NO_ASSERT_CHECK='TRUE';
      NO_DIR_CHECK='TRUE';
      ALLOW_CONNECT='TRUE';
    'PWR_2A_16':
      PIN_NUMBER='(0,0,0,EG20,0,0,0,0,0,0,0)';
      PINUSE='POWER';
      NO_LOAD_CHECK='Both';
      NO_IO_CHECK='Both';
      NO_ASSERT_CHECK='TRUE';
      NO_DIR_CHECK='TRUE';
      ALLOW_CONNECT='TRUE';
    'PWR_2A_17':
      PIN_NUMBER='(0,0,0,EP17,0,0,0,0,0,0,0)';
      PINUSE='POWER';
      NO_LOAD_CHECK='Both';
      NO_IO_CHECK='Both';
      NO_ASSERT_CHECK='TRUE';
      NO_DIR_CHECK='TRUE';
      ALLOW_CONNECT='TRUE';
    'PWR_2A_18':
      PIN_NUMBER='(0,0,0,EP20,0,0,0,0,0,0,0)';
      PINUSE='POWER';
      NO_LOAD_CHECK='Both';
      NO_IO_CHECK='Both';
      NO_ASSERT_CHECK='TRUE';
      NO_DIR_CHECK='TRUE';
      ALLOW_CONNECT='TRUE';
    'PWR_2A_19':
      PIN_NUMBER='(0,0,0,T17,0,0,0,0,0,0,0)';
      PINUSE='POWER';
      NO_LOAD_CHECK='Both';
      NO_IO_CHECK='Both';
      NO_ASSERT_CHECK='TRUE';
      NO_DIR_CHECK='TRUE';
      ALLOW_CONNECT='TRUE';
    'PWR_2A_20':
      PIN_NUMBER='(0,0,0,T20,0,0,0,0,0,0,0)';
      PINUSE='POWER';
      NO_LOAD_CHECK='Both';
      NO_IO_CHECK='Both';
      NO_ASSERT_CHECK='TRUE';
      NO_DIR_CHECK='TRUE';
      ALLOW_CONNECT='TRUE';
    'GND1':
      PIN_NUMBER='(0,0,0,0,AC13,0,0,0,0,0,0)';
      PINUSE='POWER';
      NO_LOAD_CHECK='Both';
      NO_IO_CHECK='Both';
      NO_ASSERT_CHECK='TRUE';
      NO_DIR_CHECK='TRUE';
      ALLOW_CONNECT='TRUE';
    'GND2':
      PIN_NUMBER='(0,0,0,0,AC22,0,0,0,0,0,0)';
      PINUSE='POWER';
      NO_LOAD_CHECK='Both';
      NO_IO_CHECK='Both';
      NO_ASSERT_CHECK='TRUE';
      NO_DIR_CHECK='TRUE';
      ALLOW_CONNECT='TRUE';
    'GND3':
      PIN_NUMBER='(0,0,0,0,AC32,0,0,0,0,0,0)';
      PINUSE='POWER';
      NO_LOAD_CHECK='Both';
      NO_IO_CHECK='Both';
      NO_ASSERT_CHECK='TRUE';
      NO_DIR_CHECK='TRUE';
      ALLOW_CONNECT='TRUE';
    'GND4':
      PIN_NUMBER='(0,0,0,0,AC4,0,0,0,0,0,0)';
      PINUSE='POWER';
      NO_LOAD_CHECK='Both';
      NO_IO_CHECK='Both';
      NO_ASSERT_CHECK='TRUE';
      NO_DIR_CHECK='TRUE';
      ALLOW_CONNECT='TRUE';
    'GND5':
      PIN_NUMBER='(0,0,0,0,AD2,0,0,0,0,0,0)';
      PINUSE='POWER';
      NO_LOAD_CHECK='Both';
      NO_IO_CHECK='Both';
      NO_ASSERT_CHECK='TRUE';
      NO_DIR_CHECK='TRUE';
      ALLOW_CONNECT='TRUE';
    'GND6':
      PIN_NUMBER='(0,0,0,0,AD34,0,0,0,0,0,0)';
      PINUSE='POWER';
      NO_LOAD_CHECK='Both';
      NO_IO_CHECK='Both';
      NO_ASSERT_CHECK='TRUE';
      NO_DIR_CHECK='TRUE';
      ALLOW_CONNECT='TRUE';
    'GND7':
      PIN_NUMBER='(0,0,0,0,AE1,0,0,0,0,0,0)';
      PINUSE='POWER';
      NO_LOAD_CHECK='Both';
      NO_IO_CHECK='Both';
      NO_ASSERT_CHECK='TRUE';
      NO_DIR_CHECK='TRUE';
      ALLOW_CONNECT='TRUE';
    'GND8':
      PIN_NUMBER='(0,0,0,0,AE35,0,0,0,0,0,0)';
      PINUSE='POWER';
      NO_LOAD_CHECK='Both';
      NO_IO_CHECK='Both';
      NO_ASSERT_CHECK='TRUE';
      NO_DIR_CHECK='TRUE';
      ALLOW_CONNECT='TRUE';
    'GND9':
      PIN_NUMBER='(0,0,0,0,AK13,0,0,0,0,0,0)';
      PINUSE='POWER';
      NO_LOAD_CHECK='Both';
      NO_IO_CHECK='Both';
      NO_ASSERT_CHECK='TRUE';
      NO_DIR_CHECK='TRUE';
      ALLOW_CONNECT='TRUE';
    'GND10':
      PIN_NUMBER='(0,0,0,0,AK22,0,0,0,0,0,0)';
      PINUSE='POWER';
      NO_LOAD_CHECK='Both';
      NO_IO_CHECK='Both';
      NO_ASSERT_CHECK='TRUE';
      NO_DIR_CHECK='TRUE';
      ALLOW_CONNECT='TRUE';
    'GND11':
      PIN_NUMBER='(0,0,0,0,AK32,0,0,0,0,0,0)';
      PINUSE='POWER';
      NO_LOAD_CHECK='Both';
      NO_IO_CHECK='Both';
      NO_ASSERT_CHECK='TRUE';
      NO_DIR_CHECK='TRUE';
      ALLOW_CONNECT='TRUE';
    'GND12':
      PIN_NUMBER='(0,0,0,0,AK4,0,0,0,0,0,0)';
      PINUSE='POWER';
      NO_LOAD_CHECK='Both';
      NO_IO_CHECK='Both';
      NO_ASSERT_CHECK='TRUE';
      NO_DIR_CHECK='TRUE';
      ALLOW_CONNECT='TRUE';
    'GND13':
      PIN_NUMBER='(0,0,0,0,AL2,0,0,0,0,0,0)';
      PINUSE='POWER';
      NO_LOAD_CHECK='Both';
      NO_IO_CHECK='Both';
      NO_ASSERT_CHECK='TRUE';
      NO_DIR_CHECK='TRUE';
      ALLOW_CONNECT='TRUE';
    'GND14':
      PIN_NUMBER='(0,0,0,0,AL34,0,0,0,0,0,0)';
      PINUSE='POWER';
      NO_LOAD_CHECK='Both';
      NO_IO_CHECK='Both';
      NO_ASSERT_CHECK='TRUE';
      NO_DIR_CHECK='TRUE';
      ALLOW_CONNECT='TRUE';
    'GND15':
      PIN_NUMBER='(0,0,0,0,AM1,0,0,0,0,0,0)';
      PINUSE='POWER';
      NO_LOAD_CHECK='Both';
      NO_IO_CHECK='Both';
      NO_ASSERT_CHECK='TRUE';
      NO_DIR_CHECK='TRUE';
      ALLOW_CONNECT='TRUE';
    'GND16':
      PIN_NUMBER='(0,0,0,0,AM35,0,0,0,0,0,0)';
      PINUSE='POWER';
      NO_LOAD_CHECK='Both';
      NO_IO_CHECK='Both';
      NO_ASSERT_CHECK='TRUE';
      NO_DIR_CHECK='TRUE';
      ALLOW_CONNECT='TRUE';
    'GND17':
      PIN_NUMBER='(0,0,0,0,AU13,0,0,0,0,0,0)';
      PINUSE='POWER';
      NO_LOAD_CHECK='Both';
      NO_IO_CHECK='Both';
      NO_ASSERT_CHECK='TRUE';
      NO_DIR_CHECK='TRUE';
      ALLOW_CONNECT='TRUE';
    'GND18':
      PIN_NUMBER='(0,0,0,0,AU22,0,0,0,0,0,0)';
      PINUSE='POWER';
      NO_LOAD_CHECK='Both';
      NO_IO_CHECK='Both';
      NO_ASSERT_CHECK='TRUE';
      NO_DIR_CHECK='TRUE';
      ALLOW_CONNECT='TRUE';
    'GND19':
      PIN_NUMBER='(0,0,0,0,AU32,0,0,0,0,0,0)';
      PINUSE='POWER';
      NO_LOAD_CHECK='Both';
      NO_IO_CHECK='Both';
      NO_ASSERT_CHECK='TRUE';
      NO_DIR_CHECK='TRUE';
      ALLOW_CONNECT='TRUE';
    'GND20':
      PIN_NUMBER='(0,0,0,0,AU4,0,0,0,0,0,0)';
      PINUSE='POWER';
      NO_LOAD_CHECK='Both';
      NO_IO_CHECK='Both';
      NO_ASSERT_CHECK='TRUE';
      NO_DIR_CHECK='TRUE';
      ALLOW_CONNECT='TRUE';
    'GND21':
      PIN_NUMBER='(0,0,0,0,AV2,0,0,0,0,0,0)';
      PINUSE='POWER';
      NO_LOAD_CHECK='Both';
      NO_IO_CHECK='Both';
      NO_ASSERT_CHECK='TRUE';
      NO_DIR_CHECK='TRUE';
      ALLOW_CONNECT='TRUE';
    'GND22':
      PIN_NUMBER='(0,0,0,0,AV34,0,0,0,0,0,0)';
      PINUSE='POWER';
      NO_LOAD_CHECK='Both';
      NO_IO_CHECK='Both';
      NO_ASSERT_CHECK='TRUE';
      NO_DIR_CHECK='TRUE';
      ALLOW_CONNECT='TRUE';
    'GND23':
      PIN_NUMBER='(0,0,0,0,AW1,0,0,0,0,0,0)';
      PINUSE='POWER';
      NO_LOAD_CHECK='Both';
      NO_IO_CHECK='Both';
      NO_ASSERT_CHECK='TRUE';
      NO_DIR_CHECK='TRUE';
      ALLOW_CONNECT='TRUE';
    'GND24':
      PIN_NUMBER='(0,0,0,0,AW35,0,0,0,0,0,0)';
      PINUSE='POWER';
      NO_LOAD_CHECK='Both';
      NO_IO_CHECK='Both';
      NO_ASSERT_CHECK='TRUE';
      NO_DIR_CHECK='TRUE';
      ALLOW_CONNECT='TRUE';
    'GND25':
      PIN_NUMBER='(0,0,0,0,B19,0,0,0,0,0,0)';
      PINUSE='POWER';
      NO_LOAD_CHECK='Both';
      NO_IO_CHECK='Both';
      NO_ASSERT_CHECK='TRUE';
      NO_DIR_CHECK='TRUE';
      ALLOW_CONNECT='TRUE';
    'GND26':
      PIN_NUMBER='(0,0,0,0,BD13,0,0,0,0,0,0)';
      PINUSE='POWER';
      NO_LOAD_CHECK='Both';
      NO_IO_CHECK='Both';
      NO_ASSERT_CHECK='TRUE';
      NO_DIR_CHECK='TRUE';
      ALLOW_CONNECT='TRUE';
    'GND27':
      PIN_NUMBER='(0,0,0,0,BD22,0,0,0,0,0,0)';
      PINUSE='POWER';
      NO_LOAD_CHECK='Both';
      NO_IO_CHECK='Both';
      NO_ASSERT_CHECK='TRUE';
      NO_DIR_CHECK='TRUE';
      ALLOW_CONNECT='TRUE';
    'GND28':
      PIN_NUMBER='(0,0,0,0,BD32,0,0,0,0,0,0)';
      PINUSE='POWER';
      NO_LOAD_CHECK='Both';
      NO_IO_CHECK='Both';
      NO_ASSERT_CHECK='TRUE';
      NO_DIR_CHECK='TRUE';
      ALLOW_CONNECT='TRUE';
    'GND29':
      PIN_NUMBER='(0,0,0,0,BD4,0,0,0,0,0,0)';
      PINUSE='POWER';
      NO_LOAD_CHECK='Both';
      NO_IO_CHECK='Both';
      NO_ASSERT_CHECK='TRUE';
      NO_DIR_CHECK='TRUE';
      ALLOW_CONNECT='TRUE';
    'GND30':
      PIN_NUMBER='(0,0,0,0,BE2,0,0,0,0,0,0)';
      PINUSE='POWER';
      NO_LOAD_CHECK='Both';
      NO_IO_CHECK='Both';
      NO_ASSERT_CHECK='TRUE';
      NO_DIR_CHECK='TRUE';
      ALLOW_CONNECT='TRUE';
    'GND31':
      PIN_NUMBER='(0,0,0,0,BE34,0,0,0,0,0,0)';
      PINUSE='POWER';
      NO_LOAD_CHECK='Both';
      NO_IO_CHECK='Both';
      NO_ASSERT_CHECK='TRUE';
      NO_DIR_CHECK='TRUE';
      ALLOW_CONNECT='TRUE';
    'GND32':
      PIN_NUMBER='(0,0,0,0,BF1,0,0,0,0,0,0)';
      PINUSE='POWER';
      NO_LOAD_CHECK='Both';
      NO_IO_CHECK='Both';
      NO_ASSERT_CHECK='TRUE';
      NO_DIR_CHECK='TRUE';
      ALLOW_CONNECT='TRUE';
    'GND33':
      PIN_NUMBER='(0,0,0,0,BF35,0,0,0,0,0,0)';
      PINUSE='POWER';
      NO_LOAD_CHECK='Both';
      NO_IO_CHECK='Both';
      NO_ASSERT_CHECK='TRUE';
      NO_DIR_CHECK='TRUE';
      ALLOW_CONNECT='TRUE';
    'GND34':
      PIN_NUMBER='(0,0,0,0,BL13,0,0,0,0,0,0)';
      PINUSE='POWER';
      NO_LOAD_CHECK='Both';
      NO_IO_CHECK='Both';
      NO_ASSERT_CHECK='TRUE';
      NO_DIR_CHECK='TRUE';
      ALLOW_CONNECT='TRUE';
    'GND35':
      PIN_NUMBER='(0,0,0,0,BL22,0,0,0,0,0,0)';
      PINUSE='POWER';
      NO_LOAD_CHECK='Both';
      NO_IO_CHECK='Both';
      NO_ASSERT_CHECK='TRUE';
      NO_DIR_CHECK='TRUE';
      ALLOW_CONNECT='TRUE';
    'GND36':
      PIN_NUMBER='(0,0,0,0,BL32,0,0,0,0,0,0)';
      PINUSE='POWER';
      NO_LOAD_CHECK='Both';
      NO_IO_CHECK='Both';
      NO_ASSERT_CHECK='TRUE';
      NO_DIR_CHECK='TRUE';
      ALLOW_CONNECT='TRUE';
    'GND37':
      PIN_NUMBER='(0,0,0,0,BL4,0,0,0,0,0,0)';
      PINUSE='POWER';
      NO_LOAD_CHECK='Both';
      NO_IO_CHECK='Both';
      NO_ASSERT_CHECK='TRUE';
      NO_DIR_CHECK='TRUE';
      ALLOW_CONNECT='TRUE';
    'GND38':
      PIN_NUMBER='(0,0,0,0,BM2,0,0,0,0,0,0)';
      PINUSE='POWER';
      NO_LOAD_CHECK='Both';
      NO_IO_CHECK='Both';
      NO_ASSERT_CHECK='TRUE';
      NO_DIR_CHECK='TRUE';
      ALLOW_CONNECT='TRUE';
    'GND39':
      PIN_NUMBER='(0,0,0,0,BM34,0,0,0,0,0,0)';
      PINUSE='POWER';
      NO_LOAD_CHECK='Both';
      NO_IO_CHECK='Both';
      NO_ASSERT_CHECK='TRUE';
      NO_DIR_CHECK='TRUE';
      ALLOW_CONNECT='TRUE';
    'GND40':
      PIN_NUMBER='(0,0,0,0,BN1,0,0,0,0,0,0)';
      PINUSE='POWER';
      NO_LOAD_CHECK='Both';
      NO_IO_CHECK='Both';
      NO_ASSERT_CHECK='TRUE';
      NO_DIR_CHECK='TRUE';
      ALLOW_CONNECT='TRUE';
    'GND41':
      PIN_NUMBER='(0,0,0,0,BN35,0,0,0,0,0,0)';
      PINUSE='POWER';
      NO_LOAD_CHECK='Both';
      NO_IO_CHECK='Both';
      NO_ASSERT_CHECK='TRUE';
      NO_DIR_CHECK='TRUE';
      ALLOW_CONNECT='TRUE';
    'GND42':
      PIN_NUMBER='(0,0,0,0,BV13,0,0,0,0,0,0)';
      PINUSE='POWER';
      NO_LOAD_CHECK='Both';
      NO_IO_CHECK='Both';
      NO_ASSERT_CHECK='TRUE';
      NO_DIR_CHECK='TRUE';
      ALLOW_CONNECT='TRUE';
    'GND43':
      PIN_NUMBER='(0,0,0,0,BV22,0,0,0,0,0,0)';
      PINUSE='POWER';
      NO_LOAD_CHECK='Both';
      NO_IO_CHECK='Both';
      NO_ASSERT_CHECK='TRUE';
      NO_DIR_CHECK='TRUE';
      ALLOW_CONNECT='TRUE';
    'GND44':
      PIN_NUMBER='(0,0,0,0,BV32,0,0,0,0,0,0)';
      PINUSE='POWER';
      NO_LOAD_CHECK='Both';
      NO_IO_CHECK='Both';
      NO_ASSERT_CHECK='TRUE';
      NO_DIR_CHECK='TRUE';
      ALLOW_CONNECT='TRUE';
    'GND45':
      PIN_NUMBER='(0,0,0,0,BV4,0,0,0,0,0,0)';
      PINUSE='POWER';
      NO_LOAD_CHECK='Both';
      NO_IO_CHECK='Both';
      NO_ASSERT_CHECK='TRUE';
      NO_DIR_CHECK='TRUE';
      ALLOW_CONNECT='TRUE';
    'GND46':
      PIN_NUMBER='(0,0,0,0,BW2,0,0,0,0,0,0)';
      PINUSE='POWER';
      NO_LOAD_CHECK='Both';
      NO_IO_CHECK='Both';
      NO_ASSERT_CHECK='TRUE';
      NO_DIR_CHECK='TRUE';
      ALLOW_CONNECT='TRUE';
    'GND47':
      PIN_NUMBER='(0,0,0,0,BW34,0,0,0,0,0,0)';
      PINUSE='POWER';
      NO_LOAD_CHECK='Both';
      NO_IO_CHECK='Both';
      NO_ASSERT_CHECK='TRUE';
      NO_DIR_CHECK='TRUE';
      ALLOW_CONNECT='TRUE';
    'GND48':
      PIN_NUMBER='(0,0,0,0,BY1,0,0,0,0,0,0)';
      PINUSE='POWER';
      NO_LOAD_CHECK='Both';
      NO_IO_CHECK='Both';
      NO_ASSERT_CHECK='TRUE';
      NO_DIR_CHECK='TRUE';
      ALLOW_CONNECT='TRUE';
    'GND49':
      PIN_NUMBER='(0,0,0,0,BY35,0,0,0,0,0,0)';
      PINUSE='POWER';
      NO_LOAD_CHECK='Both';
      NO_IO_CHECK='Both';
      NO_ASSERT_CHECK='TRUE';
      NO_DIR_CHECK='TRUE';
      ALLOW_CONNECT='TRUE';
    'GND50':
      PIN_NUMBER='(0,0,0,0,CE13,0,0,0,0,0,0)';
      PINUSE='POWER';
      NO_LOAD_CHECK='Both';
      NO_IO_CHECK='Both';
      NO_ASSERT_CHECK='TRUE';
      NO_DIR_CHECK='TRUE';
      ALLOW_CONNECT='TRUE';
    'GND51':
      PIN_NUMBER='(0,0,0,0,CE22,0,0,0,0,0,0)';
      PINUSE='POWER';
      NO_LOAD_CHECK='Both';
      NO_IO_CHECK='Both';
      NO_ASSERT_CHECK='TRUE';
      NO_DIR_CHECK='TRUE';
      ALLOW_CONNECT='TRUE';
    'GND52':
      PIN_NUMBER='(0,0,0,0,CE32,0,0,0,0,0,0)';
      PINUSE='POWER';
      NO_LOAD_CHECK='Both';
      NO_IO_CHECK='Both';
      NO_ASSERT_CHECK='TRUE';
      NO_DIR_CHECK='TRUE';
      ALLOW_CONNECT='TRUE';
    'GND53':
      PIN_NUMBER='(0,0,0,0,CE4,0,0,0,0,0,0)';
      PINUSE='POWER';
      NO_LOAD_CHECK='Both';
      NO_IO_CHECK='Both';
      NO_ASSERT_CHECK='TRUE';
      NO_DIR_CHECK='TRUE';
      ALLOW_CONNECT='TRUE';
    'GND54':
      PIN_NUMBER='(0,0,0,0,CF2,0,0,0,0,0,0)';
      PINUSE='POWER';
      NO_LOAD_CHECK='Both';
      NO_IO_CHECK='Both';
      NO_ASSERT_CHECK='TRUE';
      NO_DIR_CHECK='TRUE';
      ALLOW_CONNECT='TRUE';
    'GND55':
      PIN_NUMBER='(0,0,0,0,CF34,0,0,0,0,0,0)';
      PINUSE='POWER';
      NO_LOAD_CHECK='Both';
      NO_IO_CHECK='Both';
      NO_ASSERT_CHECK='TRUE';
      NO_DIR_CHECK='TRUE';
      ALLOW_CONNECT='TRUE';
    'GND56':
      PIN_NUMBER='(0,0,0,0,CG1,0,0,0,0,0,0)';
      PINUSE='POWER';
      NO_LOAD_CHECK='Both';
      NO_IO_CHECK='Both';
      NO_ASSERT_CHECK='TRUE';
      NO_DIR_CHECK='TRUE';
      ALLOW_CONNECT='TRUE';
    'GND57':
      PIN_NUMBER='(0,0,0,0,CG35,0,0,0,0,0,0)';
      PINUSE='POWER';
      NO_LOAD_CHECK='Both';
      NO_IO_CHECK='Both';
      NO_ASSERT_CHECK='TRUE';
      NO_DIR_CHECK='TRUE';
      ALLOW_CONNECT='TRUE';
    'GND58':
      PIN_NUMBER='(0,0,0,0,CM13,0,0,0,0,0,0)';
      PINUSE='POWER';
      NO_LOAD_CHECK='Both';
      NO_IO_CHECK='Both';
      NO_ASSERT_CHECK='TRUE';
      NO_DIR_CHECK='TRUE';
      ALLOW_CONNECT='TRUE';
    'GND59':
      PIN_NUMBER='(0,0,0,0,CM22,0,0,0,0,0,0)';
      PINUSE='POWER';
      NO_LOAD_CHECK='Both';
      NO_IO_CHECK='Both';
      NO_ASSERT_CHECK='TRUE';
      NO_DIR_CHECK='TRUE';
      ALLOW_CONNECT='TRUE';
    'GND60':
      PIN_NUMBER='(0,0,0,0,CM32,0,0,0,0,0,0)';
      PINUSE='POWER';
      NO_LOAD_CHECK='Both';
      NO_IO_CHECK='Both';
      NO_ASSERT_CHECK='TRUE';
      NO_DIR_CHECK='TRUE';
      ALLOW_CONNECT='TRUE';
    'GND61':
      PIN_NUMBER='(0,0,0,0,CM4,0,0,0,0,0,0)';
      PINUSE='POWER';
      NO_LOAD_CHECK='Both';
      NO_IO_CHECK='Both';
      NO_ASSERT_CHECK='TRUE';
      NO_DIR_CHECK='TRUE';
      ALLOW_CONNECT='TRUE';
    'GND62':
      PIN_NUMBER='(0,0,0,0,CN2,0,0,0,0,0,0)';
      PINUSE='POWER';
      NO_LOAD_CHECK='Both';
      NO_IO_CHECK='Both';
      NO_ASSERT_CHECK='TRUE';
      NO_DIR_CHECK='TRUE';
      ALLOW_CONNECT='TRUE';
    'GND63':
      PIN_NUMBER='(0,0,0,0,CN34,0,0,0,0,0,0)';
      PINUSE='POWER';
      NO_LOAD_CHECK='Both';
      NO_IO_CHECK='Both';
      NO_ASSERT_CHECK='TRUE';
      NO_DIR_CHECK='TRUE';
      ALLOW_CONNECT='TRUE';
    'GND64':
      PIN_NUMBER='(0,0,0,0,CP1,0,0,0,0,0,0)';
      PINUSE='POWER';
      NO_LOAD_CHECK='Both';
      NO_IO_CHECK='Both';
      NO_ASSERT_CHECK='TRUE';
      NO_DIR_CHECK='TRUE';
      ALLOW_CONNECT='TRUE';
    'GND65':
      PIN_NUMBER='(0,0,0,0,CP35,0,0,0,0,0,0)';
      PINUSE='POWER';
      NO_LOAD_CHECK='Both';
      NO_IO_CHECK='Both';
      NO_ASSERT_CHECK='TRUE';
      NO_DIR_CHECK='TRUE';
      ALLOW_CONNECT='TRUE';
    'GND66':
      PIN_NUMBER='(0,0,0,0,CW13,0,0,0,0,0,0)';
      PINUSE='POWER';
      NO_LOAD_CHECK='Both';
      NO_IO_CHECK='Both';
      NO_ASSERT_CHECK='TRUE';
      NO_DIR_CHECK='TRUE';
      ALLOW_CONNECT='TRUE';
    'GND67':
      PIN_NUMBER='(0,0,0,0,CW22,0,0,0,0,0,0)';
      PINUSE='POWER';
      NO_LOAD_CHECK='Both';
      NO_IO_CHECK='Both';
      NO_ASSERT_CHECK='TRUE';
      NO_DIR_CHECK='TRUE';
      ALLOW_CONNECT='TRUE';
    'GND68':
      PIN_NUMBER='(0,0,0,0,CW32,0,0,0,0,0,0)';
      PINUSE='POWER';
      NO_LOAD_CHECK='Both';
      NO_IO_CHECK='Both';
      NO_ASSERT_CHECK='TRUE';
      NO_DIR_CHECK='TRUE';
      ALLOW_CONNECT='TRUE';
    'GND69':
      PIN_NUMBER='(0,0,0,0,CW4,0,0,0,0,0,0)';
      PINUSE='POWER';
      NO_LOAD_CHECK='Both';
      NO_IO_CHECK='Both';
      NO_ASSERT_CHECK='TRUE';
      NO_DIR_CHECK='TRUE';
      ALLOW_CONNECT='TRUE';
    'GND70':
      PIN_NUMBER='(0,0,0,0,CY2,0,0,0,0,0,0)';
      PINUSE='POWER';
      NO_LOAD_CHECK='Both';
      NO_IO_CHECK='Both';
      NO_ASSERT_CHECK='TRUE';
      NO_DIR_CHECK='TRUE';
      ALLOW_CONNECT='TRUE';
    'GND71':
      PIN_NUMBER='(0,0,0,0,CY34,0,0,0,0,0,0)';
      PINUSE='POWER';
      NO_LOAD_CHECK='Both';
      NO_IO_CHECK='Both';
      NO_ASSERT_CHECK='TRUE';
      NO_DIR_CHECK='TRUE';
      ALLOW_CONNECT='TRUE';
    'GND72':
      PIN_NUMBER='(0,0,0,0,DA1,0,0,0,0,0,0)';
      PINUSE='POWER';
      NO_LOAD_CHECK='Both';
      NO_IO_CHECK='Both';
      NO_ASSERT_CHECK='TRUE';
      NO_DIR_CHECK='TRUE';
      ALLOW_CONNECT='TRUE';
    'GND73':
      PIN_NUMBER='(0,0,0,0,DA35,0,0,0,0,0,0)';
      PINUSE='POWER';
      NO_LOAD_CHECK='Both';
      NO_IO_CHECK='Both';
      NO_ASSERT_CHECK='TRUE';
      NO_DIR_CHECK='TRUE';
      ALLOW_CONNECT='TRUE';
    'GND74':
      PIN_NUMBER='(0,0,0,0,DF13,0,0,0,0,0,0)';
      PINUSE='POWER';
      NO_LOAD_CHECK='Both';
      NO_IO_CHECK='Both';
      NO_ASSERT_CHECK='TRUE';
      NO_DIR_CHECK='TRUE';
      ALLOW_CONNECT='TRUE';
    'GND75':
      PIN_NUMBER='(0,0,0,0,DF22,0,0,0,0,0,0)';
      PINUSE='POWER';
      NO_LOAD_CHECK='Both';
      NO_IO_CHECK='Both';
      NO_ASSERT_CHECK='TRUE';
      NO_DIR_CHECK='TRUE';
      ALLOW_CONNECT='TRUE';
    'GND76':
      PIN_NUMBER='(0,0,0,0,DF32,0,0,0,0,0,0)';
      PINUSE='POWER';
      NO_LOAD_CHECK='Both';
      NO_IO_CHECK='Both';
      NO_ASSERT_CHECK='TRUE';
      NO_DIR_CHECK='TRUE';
      ALLOW_CONNECT='TRUE';
    'GND77':
      PIN_NUMBER='(0,0,0,0,DF4,0,0,0,0,0,0)';
      PINUSE='POWER';
      NO_LOAD_CHECK='Both';
      NO_IO_CHECK='Both';
      NO_ASSERT_CHECK='TRUE';
      NO_DIR_CHECK='TRUE';
      ALLOW_CONNECT='TRUE';
    'GND78':
      PIN_NUMBER='(0,0,0,0,DG2,0,0,0,0,0,0)';
      PINUSE='POWER';
      NO_LOAD_CHECK='Both';
      NO_IO_CHECK='Both';
      NO_ASSERT_CHECK='TRUE';
      NO_DIR_CHECK='TRUE';
      ALLOW_CONNECT='TRUE';
    'GND79':
      PIN_NUMBER='(0,0,0,0,DG34,0,0,0,0,0,0)';
      PINUSE='POWER';
      NO_LOAD_CHECK='Both';
      NO_IO_CHECK='Both';
      NO_ASSERT_CHECK='TRUE';
      NO_DIR_CHECK='TRUE';
      ALLOW_CONNECT='TRUE';
    'GND80':
      PIN_NUMBER='(0,0,0,0,DH1,0,0,0,0,0,0)';
      PINUSE='POWER';
      NO_LOAD_CHECK='Both';
      NO_IO_CHECK='Both';
      NO_ASSERT_CHECK='TRUE';
      NO_DIR_CHECK='TRUE';
      ALLOW_CONNECT='TRUE';
    'GND81':
      PIN_NUMBER='(0,0,0,0,DH35,0,0,0,0,0,0)';
      PINUSE='POWER';
      NO_LOAD_CHECK='Both';
      NO_IO_CHECK='Both';
      NO_ASSERT_CHECK='TRUE';
      NO_DIR_CHECK='TRUE';
      ALLOW_CONNECT='TRUE';
    'GND82':
      PIN_NUMBER='(0,0,0,0,DN13,0,0,0,0,0,0)';
      PINUSE='POWER';
      NO_LOAD_CHECK='Both';
      NO_IO_CHECK='Both';
      NO_ASSERT_CHECK='TRUE';
      NO_DIR_CHECK='TRUE';
      ALLOW_CONNECT='TRUE';
    'NCF_GND1':
      PIN_NUMBER='(0,0,0,0,A1,0,0,0,0,0,0)';
      PINUSE='POWER';
      NO_LOAD_CHECK='Both';
      NO_IO_CHECK='Both';
      NO_ASSERT_CHECK='TRUE';
      NO_DIR_CHECK='TRUE';
      ALLOW_CONNECT='TRUE';
    'NCF_GND2':
      PIN_NUMBER='(0,0,0,0,A35,0,0,0,0,0,0)';
      PINUSE='POWER';
      NO_LOAD_CHECK='Both';
      NO_IO_CHECK='Both';
      NO_ASSERT_CHECK='TRUE';
      NO_DIR_CHECK='TRUE';
      ALLOW_CONNECT='TRUE';
    'NCF_GND3':
      PIN_NUMBER='(0,0,0,0,C2,0,0,0,0,0,0)';
      PINUSE='POWER';
      NO_LOAD_CHECK='Both';
      NO_IO_CHECK='Both';
      NO_ASSERT_CHECK='TRUE';
      NO_DIR_CHECK='TRUE';
      ALLOW_CONNECT='TRUE';
    'NCF_GND4':
      PIN_NUMBER='(0,0,0,0,C34,0,0,0,0,0,0)';
      PINUSE='POWER';
      NO_LOAD_CHECK='Both';
      NO_IO_CHECK='Both';
      NO_ASSERT_CHECK='TRUE';
      NO_DIR_CHECK='TRUE';
      ALLOW_CONNECT='TRUE';
    'NCF_GND5':
      PIN_NUMBER='(0,0,0,0,D1,0,0,0,0,0,0)';
      PINUSE='POWER';
      NO_LOAD_CHECK='Both';
      NO_IO_CHECK='Both';
      NO_ASSERT_CHECK='TRUE';
      NO_DIR_CHECK='TRUE';
      ALLOW_CONNECT='TRUE';
    'NCF_GND6':
      PIN_NUMBER='(0,0,0,0,D35,0,0,0,0,0,0)';
      PINUSE='POWER';
      NO_LOAD_CHECK='Both';
      NO_IO_CHECK='Both';
      NO_ASSERT_CHECK='TRUE';
      NO_DIR_CHECK='TRUE';
      ALLOW_CONNECT='TRUE';
    'NCF_GND7':
      PIN_NUMBER='(0,0,0,0,FE2,0,0,0,0,0,0)';
      PINUSE='POWER';
      NO_LOAD_CHECK='Both';
      NO_IO_CHECK='Both';
      NO_ASSERT_CHECK='TRUE';
      NO_DIR_CHECK='TRUE';
      ALLOW_CONNECT='TRUE';
    'NCF_GND8':
      PIN_NUMBER='(0,0,0,0,FE34,0,0,0,0,0,0)';
      PINUSE='POWER';
      NO_LOAD_CHECK='Both';
      NO_IO_CHECK='Both';
      NO_ASSERT_CHECK='TRUE';
      NO_DIR_CHECK='TRUE';
      ALLOW_CONNECT='TRUE';
    'NCF_GND9':
      PIN_NUMBER='(0,0,0,0,FG1,0,0,0,0,0,0)';
      PINUSE='POWER';
      NO_LOAD_CHECK='Both';
      NO_IO_CHECK='Both';
      NO_ASSERT_CHECK='TRUE';
      NO_DIR_CHECK='TRUE';
      ALLOW_CONNECT='TRUE';
    'NCF_GND10':
      PIN_NUMBER='(0,0,0,0,FG35,0,0,0,0,0,0)';
      PINUSE='POWER';
      NO_LOAD_CHECK='Both';
      NO_IO_CHECK='Both';
      NO_ASSERT_CHECK='TRUE';
      NO_DIR_CHECK='TRUE';
      ALLOW_CONNECT='TRUE';
    'NCF_GND11':
      PIN_NUMBER='(0,0,0,0,FH2,0,0,0,0,0,0)';
      PINUSE='POWER';
      NO_LOAD_CHECK='Both';
      NO_IO_CHECK='Both';
      NO_ASSERT_CHECK='TRUE';
      NO_DIR_CHECK='TRUE';
      ALLOW_CONNECT='TRUE';
    'NCF_GND12':
      PIN_NUMBER='(0,0,0,0,FH34,0,0,0,0,0,0)';
      PINUSE='POWER';
      NO_LOAD_CHECK='Both';
      NO_IO_CHECK='Both';
      NO_ASSERT_CHECK='TRUE';
      NO_DIR_CHECK='TRUE';
      ALLOW_CONNECT='TRUE';
    'GND83':
      PIN_NUMBER='(0,0,0,0,DN22,0,0,0,0,0,0)';
      PINUSE='POWER';
      NO_LOAD_CHECK='Both';
      NO_IO_CHECK='Both';
      NO_ASSERT_CHECK='TRUE';
      NO_DIR_CHECK='TRUE';
      ALLOW_CONNECT='TRUE';
    'GND84':
      PIN_NUMBER='(0,0,0,0,DN32,0,0,0,0,0,0)';
      PINUSE='POWER';
      NO_LOAD_CHECK='Both';
      NO_IO_CHECK='Both';
      NO_ASSERT_CHECK='TRUE';
      NO_DIR_CHECK='TRUE';
      ALLOW_CONNECT='TRUE';
    'GND85':
      PIN_NUMBER='(0,0,0,0,DN4,0,0,0,0,0,0)';
      PINUSE='POWER';
      NO_LOAD_CHECK='Both';
      NO_IO_CHECK='Both';
      NO_ASSERT_CHECK='TRUE';
      NO_DIR_CHECK='TRUE';
      ALLOW_CONNECT='TRUE';
    'GND86':
      PIN_NUMBER='(0,0,0,0,DP2,0,0,0,0,0,0)';
      PINUSE='POWER';
      NO_LOAD_CHECK='Both';
      NO_IO_CHECK='Both';
      NO_ASSERT_CHECK='TRUE';
      NO_DIR_CHECK='TRUE';
      ALLOW_CONNECT='TRUE';
    'GND87':
      PIN_NUMBER='(0,0,0,0,DP34,0,0,0,0,0,0)';
      PINUSE='POWER';
      NO_LOAD_CHECK='Both';
      NO_IO_CHECK='Both';
      NO_ASSERT_CHECK='TRUE';
      NO_DIR_CHECK='TRUE';
      ALLOW_CONNECT='TRUE';
    'GND88':
      PIN_NUMBER='(0,0,0,0,DR1,0,0,0,0,0,0)';
      PINUSE='POWER';
      NO_LOAD_CHECK='Both';
      NO_IO_CHECK='Both';
      NO_ASSERT_CHECK='TRUE';
      NO_DIR_CHECK='TRUE';
      ALLOW_CONNECT='TRUE';
    'GND89':
      PIN_NUMBER='(0,0,0,0,DR35,0,0,0,0,0,0)';
      PINUSE='POWER';
      NO_LOAD_CHECK='Both';
      NO_IO_CHECK='Both';
      NO_ASSERT_CHECK='TRUE';
      NO_DIR_CHECK='TRUE';
      ALLOW_CONNECT='TRUE';
    'GND90':
      PIN_NUMBER='(0,0,0,0,DY13,0,0,0,0,0,0)';
      PINUSE='POWER';
      NO_LOAD_CHECK='Both';
      NO_IO_CHECK='Both';
      NO_ASSERT_CHECK='TRUE';
      NO_DIR_CHECK='TRUE';
      ALLOW_CONNECT='TRUE';
    'GND91':
      PIN_NUMBER='(0,0,0,0,DY22,0,0,0,0,0,0)';
      PINUSE='POWER';
      NO_LOAD_CHECK='Both';
      NO_IO_CHECK='Both';
      NO_ASSERT_CHECK='TRUE';
      NO_DIR_CHECK='TRUE';
      ALLOW_CONNECT='TRUE';
    'GND92':
      PIN_NUMBER='(0,0,0,0,DY32,0,0,0,0,0,0)';
      PINUSE='POWER';
      NO_LOAD_CHECK='Both';
      NO_IO_CHECK='Both';
      NO_ASSERT_CHECK='TRUE';
      NO_DIR_CHECK='TRUE';
      ALLOW_CONNECT='TRUE';
    'GND93':
      PIN_NUMBER='(0,0,0,0,DY4,0,0,0,0,0,0)';
      PINUSE='POWER';
      NO_LOAD_CHECK='Both';
      NO_IO_CHECK='Both';
      NO_ASSERT_CHECK='TRUE';
      NO_DIR_CHECK='TRUE';
      ALLOW_CONNECT='TRUE';
    'GND94':
      PIN_NUMBER='(0,0,0,0,E14,0,0,0,0,0,0)';
      PINUSE='POWER';
      NO_LOAD_CHECK='Both';
      NO_IO_CHECK='Both';
      NO_ASSERT_CHECK='TRUE';
      NO_DIR_CHECK='TRUE';
      ALLOW_CONNECT='TRUE';
    'GND95':
      PIN_NUMBER='(0,0,0,0,E27,0,0,0,0,0,0)';
      PINUSE='POWER';
      NO_LOAD_CHECK='Both';
      NO_IO_CHECK='Both';
      NO_ASSERT_CHECK='TRUE';
      NO_DIR_CHECK='TRUE';
      ALLOW_CONNECT='TRUE';
    'GND96':
      PIN_NUMBER='(0,0,0,0,E33,0,0,0,0,0,0)';
      PINUSE='POWER';
      NO_LOAD_CHECK='Both';
      NO_IO_CHECK='Both';
      NO_ASSERT_CHECK='TRUE';
      NO_DIR_CHECK='TRUE';
      ALLOW_CONNECT='TRUE';
    'GND97':
      PIN_NUMBER='(0,0,0,0,EA2,0,0,0,0,0,0)';
      PINUSE='POWER';
      NO_LOAD_CHECK='Both';
      NO_IO_CHECK='Both';
      NO_ASSERT_CHECK='TRUE';
      NO_DIR_CHECK='TRUE';
      ALLOW_CONNECT='TRUE';
    'GND98':
      PIN_NUMBER='(0,0,0,0,EA34,0,0,0,0,0,0)';
      PINUSE='POWER';
      NO_LOAD_CHECK='Both';
      NO_IO_CHECK='Both';
      NO_ASSERT_CHECK='TRUE';
      NO_DIR_CHECK='TRUE';
      ALLOW_CONNECT='TRUE';
    'GND99':
      PIN_NUMBER='(0,0,0,0,EB1,0,0,0,0,0,0)';
      PINUSE='POWER';
      NO_LOAD_CHECK='Both';
      NO_IO_CHECK='Both';
      NO_ASSERT_CHECK='TRUE';
      NO_DIR_CHECK='TRUE';
      ALLOW_CONNECT='TRUE';
    'GND100':
      PIN_NUMBER='(0,0,0,0,EB35,0,0,0,0,0,0)';
      PINUSE='POWER';
      NO_LOAD_CHECK='Both';
      NO_IO_CHECK='Both';
      NO_ASSERT_CHECK='TRUE';
      NO_DIR_CHECK='TRUE';
      ALLOW_CONNECT='TRUE';
    'GND101':
      PIN_NUMBER='(0,0,0,0,EG13,0,0,0,0,0,0)';
      PINUSE='POWER';
      NO_LOAD_CHECK='Both';
      NO_IO_CHECK='Both';
      NO_ASSERT_CHECK='TRUE';
      NO_DIR_CHECK='TRUE';
      ALLOW_CONNECT='TRUE';
    'GND102':
      PIN_NUMBER='(0,0,0,0,EG22,0,0,0,0,0,0)';
      PINUSE='POWER';
      NO_LOAD_CHECK='Both';
      NO_IO_CHECK='Both';
      NO_ASSERT_CHECK='TRUE';
      NO_DIR_CHECK='TRUE';
      ALLOW_CONNECT='TRUE';
    'GND103':
      PIN_NUMBER='(0,0,0,0,EG32,0,0,0,0,0,0)';
      PINUSE='POWER';
      NO_LOAD_CHECK='Both';
      NO_IO_CHECK='Both';
      NO_ASSERT_CHECK='TRUE';
      NO_DIR_CHECK='TRUE';
      ALLOW_CONNECT='TRUE';
    'GND104':
      PIN_NUMBER='(0,0,0,0,EG4,0,0,0,0,0,0)';
      PINUSE='POWER';
      NO_LOAD_CHECK='Both';
      NO_IO_CHECK='Both';
      NO_ASSERT_CHECK='TRUE';
      NO_DIR_CHECK='TRUE';
      ALLOW_CONNECT='TRUE';
    'GND105':
      PIN_NUMBER='(0,0,0,0,EH2,0,0,0,0,0,0)';
      PINUSE='POWER';
      NO_LOAD_CHECK='Both';
      NO_IO_CHECK='Both';
      NO_ASSERT_CHECK='TRUE';
      NO_DIR_CHECK='TRUE';
      ALLOW_CONNECT='TRUE';
    'GND106':
      PIN_NUMBER='(0,0,0,0,EH34,0,0,0,0,0,0)';
      PINUSE='POWER';
      NO_LOAD_CHECK='Both';
      NO_IO_CHECK='Both';
      NO_ASSERT_CHECK='TRUE';
      NO_DIR_CHECK='TRUE';
      ALLOW_CONNECT='TRUE';
    'GND107':
      PIN_NUMBER='(0,0,0,0,EJ1,0,0,0,0,0,0)';
      PINUSE='POWER';
      NO_LOAD_CHECK='Both';
      NO_IO_CHECK='Both';
      NO_ASSERT_CHECK='TRUE';
      NO_DIR_CHECK='TRUE';
      ALLOW_CONNECT='TRUE';
    'GND108':
      PIN_NUMBER='(0,0,0,0,EJ35,0,0,0,0,0,0)';
      PINUSE='POWER';
      NO_LOAD_CHECK='Both';
      NO_IO_CHECK='Both';
      NO_ASSERT_CHECK='TRUE';
      NO_DIR_CHECK='TRUE';
      ALLOW_CONNECT='TRUE';
    'GND109':
      PIN_NUMBER='(0,0,0,0,EP13,0,0,0,0,0,0)';
      PINUSE='POWER';
      NO_LOAD_CHECK='Both';
      NO_IO_CHECK='Both';
      NO_ASSERT_CHECK='TRUE';
      NO_DIR_CHECK='TRUE';
      ALLOW_CONNECT='TRUE';
    'GND110':
      PIN_NUMBER='(0,0,0,0,EP22,0,0,0,0,0,0)';
      PINUSE='POWER';
      NO_LOAD_CHECK='Both';
      NO_IO_CHECK='Both';
      NO_ASSERT_CHECK='TRUE';
      NO_DIR_CHECK='TRUE';
      ALLOW_CONNECT='TRUE';
    'GND111':
      PIN_NUMBER='(0,0,0,0,EP32,0,0,0,0,0,0)';
      PINUSE='POWER';
      NO_LOAD_CHECK='Both';
      NO_IO_CHECK='Both';
      NO_ASSERT_CHECK='TRUE';
      NO_DIR_CHECK='TRUE';
      ALLOW_CONNECT='TRUE';
    'GND112':
      PIN_NUMBER='(0,0,0,0,EP4,0,0,0,0,0,0)';
      PINUSE='POWER';
      NO_LOAD_CHECK='Both';
      NO_IO_CHECK='Both';
      NO_ASSERT_CHECK='TRUE';
      NO_DIR_CHECK='TRUE';
      ALLOW_CONNECT='TRUE';
    'GND113':
      PIN_NUMBER='(0,0,0,0,ER2,0,0,0,0,0,0)';
      PINUSE='POWER';
      NO_LOAD_CHECK='Both';
      NO_IO_CHECK='Both';
      NO_ASSERT_CHECK='TRUE';
      NO_DIR_CHECK='TRUE';
      ALLOW_CONNECT='TRUE';
    'GND114':
      PIN_NUMBER='(0,0,0,0,ER34,0,0,0,0,0,0)';
      PINUSE='POWER';
      NO_LOAD_CHECK='Both';
      NO_IO_CHECK='Both';
      NO_ASSERT_CHECK='TRUE';
      NO_DIR_CHECK='TRUE';
      ALLOW_CONNECT='TRUE';
    'GND115':
      PIN_NUMBER='(0,0,0,0,ET1,0,0,0,0,0,0)';
      PINUSE='POWER';
      NO_LOAD_CHECK='Both';
      NO_IO_CHECK='Both';
      NO_ASSERT_CHECK='TRUE';
      NO_DIR_CHECK='TRUE';
      ALLOW_CONNECT='TRUE';
    'GND116':
      PIN_NUMBER='(0,0,0,0,ET35,0,0,0,0,0,0)';
      PINUSE='POWER';
      NO_LOAD_CHECK='Both';
      NO_IO_CHECK='Both';
      NO_ASSERT_CHECK='TRUE';
      NO_DIR_CHECK='TRUE';
      ALLOW_CONNECT='TRUE';
    'GND117':
      PIN_NUMBER='(0,0,0,0,FA15,0,0,0,0,0,0)';
      PINUSE='POWER';
      NO_LOAD_CHECK='Both';
      NO_IO_CHECK='Both';
      NO_ASSERT_CHECK='TRUE';
      NO_DIR_CHECK='TRUE';
      ALLOW_CONNECT='TRUE';
    'GND118':
      PIN_NUMBER='(0,0,0,0,FA32,0,0,0,0,0,0)';
      PINUSE='POWER';
      NO_LOAD_CHECK='Both';
      NO_IO_CHECK='Both';
      NO_ASSERT_CHECK='TRUE';
      NO_DIR_CHECK='TRUE';
      ALLOW_CONNECT='TRUE';
    'GND119':
      PIN_NUMBER='(0,0,0,0,FB2,0,0,0,0,0,0)';
      PINUSE='POWER';
      NO_LOAD_CHECK='Both';
      NO_IO_CHECK='Both';
      NO_ASSERT_CHECK='TRUE';
      NO_DIR_CHECK='TRUE';
      ALLOW_CONNECT='TRUE';
    'GND120':
      PIN_NUMBER='(0,0,0,0,FB34,0,0,0,0,0,0)';
      PINUSE='POWER';
      NO_LOAD_CHECK='Both';
      NO_IO_CHECK='Both';
      NO_ASSERT_CHECK='TRUE';
      NO_DIR_CHECK='TRUE';
      ALLOW_CONNECT='TRUE';
    'GND121':
      PIN_NUMBER='(0,0,0,0,FC19,0,0,0,0,0,0)';
      PINUSE='POWER';
      NO_LOAD_CHECK='Both';
      NO_IO_CHECK='Both';
      NO_ASSERT_CHECK='TRUE';
      NO_DIR_CHECK='TRUE';
      ALLOW_CONNECT='TRUE';
    'GND122':
      PIN_NUMBER='(0,0,0,0,FC23,0,0,0,0,0,0)';
      PINUSE='POWER';
      NO_LOAD_CHECK='Both';
      NO_IO_CHECK='Both';
      NO_ASSERT_CHECK='TRUE';
      NO_DIR_CHECK='TRUE';
      ALLOW_CONNECT='TRUE';
    'GND123':
      PIN_NUMBER='(0,0,0,0,FC25,0,0,0,0,0,0)';
      PINUSE='POWER';
      NO_LOAD_CHECK='Both';
      NO_IO_CHECK='Both';
      NO_ASSERT_CHECK='TRUE';
      NO_DIR_CHECK='TRUE';
      ALLOW_CONNECT='TRUE';
    'GND124':
      PIN_NUMBER='(0,0,0,0,FC28,0,0,0,0,0,0)';
      PINUSE='POWER';
      NO_LOAD_CHECK='Both';
      NO_IO_CHECK='Both';
      NO_ASSERT_CHECK='TRUE';
      NO_DIR_CHECK='TRUE';
      ALLOW_CONNECT='TRUE';
    'GND125':
      PIN_NUMBER='(0,0,0,0,FC3,0,0,0,0,0,0)';
      PINUSE='POWER';
      NO_LOAD_CHECK='Both';
      NO_IO_CHECK='Both';
      NO_ASSERT_CHECK='TRUE';
      NO_DIR_CHECK='TRUE';
      ALLOW_CONNECT='TRUE';
    'GND126':
      PIN_NUMBER='(0,0,0,0,FC6,0,0,0,0,0,0)';
      PINUSE='POWER';
      NO_LOAD_CHECK='Both';
      NO_IO_CHECK='Both';
      NO_ASSERT_CHECK='TRUE';
      NO_DIR_CHECK='TRUE';
      ALLOW_CONNECT='TRUE';
    'GND127':
      PIN_NUMBER='(0,0,0,0,FC9,0,0,0,0,0,0)';
      PINUSE='POWER';
      NO_LOAD_CHECK='Both';
      NO_IO_CHECK='Both';
      NO_ASSERT_CHECK='TRUE';
      NO_DIR_CHECK='TRUE';
      ALLOW_CONNECT='TRUE';
    'GND128':
      PIN_NUMBER='(0,0,0,0,FD1,0,0,0,0,0,0)';
      PINUSE='POWER';
      NO_LOAD_CHECK='Both';
      NO_IO_CHECK='Both';
      NO_ASSERT_CHECK='TRUE';
      NO_DIR_CHECK='TRUE';
      ALLOW_CONNECT='TRUE';
    'GND129':
      PIN_NUMBER='(0,0,0,0,FD35,0,0,0,0,0,0)';
      PINUSE='POWER';
      NO_LOAD_CHECK='Both';
      NO_IO_CHECK='Both';
      NO_ASSERT_CHECK='TRUE';
      NO_DIR_CHECK='TRUE';
      ALLOW_CONNECT='TRUE';
    'GND130':
      PIN_NUMBER='(0,0,0,0,FF14,0,0,0,0,0,0)';
      PINUSE='POWER';
      NO_LOAD_CHECK='Both';
      NO_IO_CHECK='Both';
      NO_ASSERT_CHECK='TRUE';
      NO_DIR_CHECK='TRUE';
      ALLOW_CONNECT='TRUE';
    'GND131':
      PIN_NUMBER='(0,0,0,0,FF21,0,0,0,0,0,0)';
      PINUSE='POWER';
      NO_LOAD_CHECK='Both';
      NO_IO_CHECK='Both';
      NO_ASSERT_CHECK='TRUE';
      NO_DIR_CHECK='TRUE';
      ALLOW_CONNECT='TRUE';
    'GND132':
      PIN_NUMBER='(0,0,0,0,FJ12,0,0,0,0,0,0)';
      PINUSE='POWER';
      NO_LOAD_CHECK='Both';
      NO_IO_CHECK='Both';
      NO_ASSERT_CHECK='TRUE';
      NO_DIR_CHECK='TRUE';
      ALLOW_CONNECT='TRUE';
    'GND133':
      PIN_NUMBER='(0,0,0,0,FJ19,0,0,0,0,0,0)';
      PINUSE='POWER';
      NO_LOAD_CHECK='Both';
      NO_IO_CHECK='Both';
      NO_ASSERT_CHECK='TRUE';
      NO_DIR_CHECK='TRUE';
      ALLOW_CONNECT='TRUE';
    'GND134':
      PIN_NUMBER='(0,0,0,0,H12,0,0,0,0,0,0)';
      PINUSE='POWER';
      NO_LOAD_CHECK='Both';
      NO_IO_CHECK='Both';
      NO_ASSERT_CHECK='TRUE';
      NO_DIR_CHECK='TRUE';
      ALLOW_CONNECT='TRUE';
    'GND135':
      PIN_NUMBER='(0,0,0,0,H16,0,0,0,0,0,0)';
      PINUSE='POWER';
      NO_LOAD_CHECK='Both';
      NO_IO_CHECK='Both';
      NO_ASSERT_CHECK='TRUE';
      NO_DIR_CHECK='TRUE';
      ALLOW_CONNECT='TRUE';
    'GND136':
      PIN_NUMBER='(0,0,0,0,H19,0,0,0,0,0,0)';
      PINUSE='POWER';
      NO_LOAD_CHECK='Both';
      NO_IO_CHECK='Both';
      NO_ASSERT_CHECK='TRUE';
      NO_DIR_CHECK='TRUE';
      ALLOW_CONNECT='TRUE';
    'GND137':
      PIN_NUMBER='(0,0,0,0,H31,0,0,0,0,0,0)';
      PINUSE='POWER';
      NO_LOAD_CHECK='Both';
      NO_IO_CHECK='Both';
      NO_ASSERT_CHECK='TRUE';
      NO_DIR_CHECK='TRUE';
      ALLOW_CONNECT='TRUE';
    'GND138':
      PIN_NUMBER='(0,0,0,0,J22,0,0,0,0,0,0)';
      PINUSE='POWER';
      NO_LOAD_CHECK='Both';
      NO_IO_CHECK='Both';
      NO_ASSERT_CHECK='TRUE';
      NO_DIR_CHECK='TRUE';
      ALLOW_CONNECT='TRUE';
    'GND139':
      PIN_NUMBER='(0,0,0,0,J4,0,0,0,0,0,0)';
      PINUSE='POWER';
      NO_LOAD_CHECK='Both';
      NO_IO_CHECK='Both';
      NO_ASSERT_CHECK='TRUE';
      NO_DIR_CHECK='TRUE';
      ALLOW_CONNECT='TRUE';
    'GND140':
      PIN_NUMBER='(0,0,0,0,K2,0,0,0,0,0,0)';
      PINUSE='POWER';
      NO_LOAD_CHECK='Both';
      NO_IO_CHECK='Both';
      NO_ASSERT_CHECK='TRUE';
      NO_DIR_CHECK='TRUE';
      ALLOW_CONNECT='TRUE';
    'GND141':
      PIN_NUMBER='(0,0,0,0,K34,0,0,0,0,0,0)';
      PINUSE='POWER';
      NO_LOAD_CHECK='Both';
      NO_IO_CHECK='Both';
      NO_ASSERT_CHECK='TRUE';
      NO_DIR_CHECK='TRUE';
      ALLOW_CONNECT='TRUE';
    'GND142':
      PIN_NUMBER='(0,0,0,0,L1,0,0,0,0,0,0)';
      PINUSE='POWER';
      NO_LOAD_CHECK='Both';
      NO_IO_CHECK='Both';
      NO_ASSERT_CHECK='TRUE';
      NO_DIR_CHECK='TRUE';
      ALLOW_CONNECT='TRUE';
    'GND143':
      PIN_NUMBER='(0,0,0,0,L35,0,0,0,0,0,0)';
      PINUSE='POWER';
      NO_LOAD_CHECK='Both';
      NO_IO_CHECK='Both';
      NO_ASSERT_CHECK='TRUE';
      NO_DIR_CHECK='TRUE';
      ALLOW_CONNECT='TRUE';
    'GND144':
      PIN_NUMBER='(0,0,0,0,T13,0,0,0,0,0,0)';
      PINUSE='POWER';
      NO_LOAD_CHECK='Both';
      NO_IO_CHECK='Both';
      NO_ASSERT_CHECK='TRUE';
      NO_DIR_CHECK='TRUE';
      ALLOW_CONNECT='TRUE';
    'GND145':
      PIN_NUMBER='(0,0,0,0,T22,0,0,0,0,0,0)';
      PINUSE='POWER';
      NO_LOAD_CHECK='Both';
      NO_IO_CHECK='Both';
      NO_ASSERT_CHECK='TRUE';
      NO_DIR_CHECK='TRUE';
      ALLOW_CONNECT='TRUE';
    'GND146':
      PIN_NUMBER='(0,0,0,0,T32,0,0,0,0,0,0)';
      PINUSE='POWER';
      NO_LOAD_CHECK='Both';
      NO_IO_CHECK='Both';
      NO_ASSERT_CHECK='TRUE';
      NO_DIR_CHECK='TRUE';
      ALLOW_CONNECT='TRUE';
    'GND147':
      PIN_NUMBER='(0,0,0,0,T4,0,0,0,0,0,0)';
      PINUSE='POWER';
      NO_LOAD_CHECK='Both';
      NO_IO_CHECK='Both';
      NO_ASSERT_CHECK='TRUE';
      NO_DIR_CHECK='TRUE';
      ALLOW_CONNECT='TRUE';
    'GND148':
      PIN_NUMBER='(0,0,0,0,U2,0,0,0,0,0,0)';
      PINUSE='POWER';
      NO_LOAD_CHECK='Both';
      NO_IO_CHECK='Both';
      NO_ASSERT_CHECK='TRUE';
      NO_DIR_CHECK='TRUE';
      ALLOW_CONNECT='TRUE';
    'GND149':
      PIN_NUMBER='(0,0,0,0,U34,0,0,0,0,0,0)';
      PINUSE='POWER';
      NO_LOAD_CHECK='Both';
      NO_IO_CHECK='Both';
      NO_ASSERT_CHECK='TRUE';
      NO_DIR_CHECK='TRUE';
      ALLOW_CONNECT='TRUE';
    'GND150':
      PIN_NUMBER='(0,0,0,0,V1,0,0,0,0,0,0)';
      PINUSE='POWER';
      NO_LOAD_CHECK='Both';
      NO_IO_CHECK='Both';
      NO_ASSERT_CHECK='TRUE';
      NO_DIR_CHECK='TRUE';
      ALLOW_CONNECT='TRUE';
    'GND151':
      PIN_NUMBER='(0,0,0,0,V35,0,0,0,0,0,0)';
      PINUSE='POWER';
      NO_LOAD_CHECK='Both';
      NO_IO_CHECK='Both';
      NO_ASSERT_CHECK='TRUE';
      NO_DIR_CHECK='TRUE';
      ALLOW_CONNECT='TRUE';
    'A_PETP0':
      PIN_NUMBER='(0,0,0,0,0,M26,0,0,0,0,0)';
      OUTPUT_LOAD='(1.0,-1.0)';
      PINUSE='OUT';
    'A_PETN0':
      PIN_NUMBER='(0,0,0,0,0,P29,0,0,0,0,0)';
      OUTPUT_LOAD='(1.0,-1.0)';
      PINUSE='OUT';
    'A_PETP1':
      PIN_NUMBER='(0,0,0,0,0,W26,0,0,0,0,0)';
      OUTPUT_LOAD='(1.0,-1.0)';
      PINUSE='OUT';
    'A_PETN1':
      PIN_NUMBER='(0,0,0,0,0,AA29,0,0,0,0,0)';
      OUTPUT_LOAD='(1.0,-1.0)';
      PINUSE='OUT';
    'A_PETP2':
      PIN_NUMBER='(0,0,0,0,0,AF26,0,0,0,0,0)';
      OUTPUT_LOAD='(1.0,-1.0)';
      PINUSE='OUT';
    'A_PETN2':
      PIN_NUMBER='(0,0,0,0,0,AH29,0,0,0,0,0)';
      OUTPUT_LOAD='(1.0,-1.0)';
      PINUSE='OUT';
    'A_PETP3':
      PIN_NUMBER='(0,0,0,0,0,AN26,0,0,0,0,0)';
      OUTPUT_LOAD='(1.0,-1.0)';
      PINUSE='OUT';
    'A_PETN3':
      PIN_NUMBER='(0,0,0,0,0,AR29,0,0,0,0,0)';
      OUTPUT_LOAD='(1.0,-1.0)';
      PINUSE='OUT';
    'A_PETP4':
      PIN_NUMBER='(0,0,0,0,0,AY26,0,0,0,0,0)';
      OUTPUT_LOAD='(1.0,-1.0)';
      PINUSE='OUT';
    'A_PETN4':
      PIN_NUMBER='(0,0,0,0,0,BB29,0,0,0,0,0)';
      OUTPUT_LOAD='(1.0,-1.0)';
      PINUSE='OUT';
    'A_PETP5':
      PIN_NUMBER='(0,0,0,0,0,BG26,0,0,0,0,0)';
      OUTPUT_LOAD='(1.0,-1.0)';
      PINUSE='OUT';
    'A_PETN5':
      PIN_NUMBER='(0,0,0,0,0,BJ29,0,0,0,0,0)';
      OUTPUT_LOAD='(1.0,-1.0)';
      PINUSE='OUT';
    'A_PETP6':
      PIN_NUMBER='(0,0,0,0,0,BP26,0,0,0,0,0)';
      OUTPUT_LOAD='(1.0,-1.0)';
      PINUSE='OUT';
    'A_PETN6':
      PIN_NUMBER='(0,0,0,0,0,BT29,0,0,0,0,0)';
      OUTPUT_LOAD='(1.0,-1.0)';
      PINUSE='OUT';
    'A_PETP7':
      PIN_NUMBER='(0,0,0,0,0,CA26,0,0,0,0,0)';
      OUTPUT_LOAD='(1.0,-1.0)';
      PINUSE='OUT';
    'A_PETN7':
      PIN_NUMBER='(0,0,0,0,0,CC29,0,0,0,0,0)';
      OUTPUT_LOAD='(1.0,-1.0)';
      PINUSE='OUT';
    'A_PETP8':
      PIN_NUMBER='(0,0,0,0,0,0,CH26,0,0,0,0)';
      OUTPUT_LOAD='(1.0,-1.0)';
      PINUSE='OUT';
    'A_PETN8':
      PIN_NUMBER='(0,0,0,0,0,0,CK29,0,0,0,0)';
      OUTPUT_LOAD='(1.0,-1.0)';
      PINUSE='OUT';
    'A_PETP9':
      PIN_NUMBER='(0,0,0,0,0,0,CR26,0,0,0,0)';
      OUTPUT_LOAD='(1.0,-1.0)';
      PINUSE='OUT';
    'A_PETN9':
      PIN_NUMBER='(0,0,0,0,0,0,CU29,0,0,0,0)';
      OUTPUT_LOAD='(1.0,-1.0)';
      PINUSE='OUT';
    'A_PETP10':
      PIN_NUMBER='(0,0,0,0,0,0,DB26,0,0,0,0)';
      OUTPUT_LOAD='(1.0,-1.0)';
      PINUSE='OUT';
    'A_PETN10':
      PIN_NUMBER='(0,0,0,0,0,0,DD29,0,0,0,0)';
      OUTPUT_LOAD='(1.0,-1.0)';
      PINUSE='OUT';
    'A_PETP11':
      PIN_NUMBER='(0,0,0,0,0,0,DJ26,0,0,0,0)';
      OUTPUT_LOAD='(1.0,-1.0)';
      PINUSE='OUT';
    'A_PETN11':
      PIN_NUMBER='(0,0,0,0,0,0,DL29,0,0,0,0)';
      OUTPUT_LOAD='(1.0,-1.0)';
      PINUSE='OUT';
    'A_PETP12':
      PIN_NUMBER='(0,0,0,0,0,0,DT26,0,0,0,0)';
      OUTPUT_LOAD='(1.0,-1.0)';
      PINUSE='OUT';
    'A_PETN12':
      PIN_NUMBER='(0,0,0,0,0,0,DV29,0,0,0,0)';
      OUTPUT_LOAD='(1.0,-1.0)';
      PINUSE='OUT';
    'A_PETP13':
      PIN_NUMBER='(0,0,0,0,0,0,EC26,0,0,0,0)';
      OUTPUT_LOAD='(1.0,-1.0)';
      PINUSE='OUT';
    'A_PETN13':
      PIN_NUMBER='(0,0,0,0,0,0,EE29,0,0,0,0)';
      OUTPUT_LOAD='(1.0,-1.0)';
      PINUSE='OUT';
    'A_PETP14':
      PIN_NUMBER='(0,0,0,0,0,0,EK26,0,0,0,0)';
      OUTPUT_LOAD='(1.0,-1.0)';
      PINUSE='OUT';
    'A_PETN14':
      PIN_NUMBER='(0,0,0,0,0,0,EM29,0,0,0,0)';
      OUTPUT_LOAD='(1.0,-1.0)';
      PINUSE='OUT';
    'A_PETP15':
      PIN_NUMBER='(0,0,0,0,0,0,EU26,0,0,0,0)';
      OUTPUT_LOAD='(1.0,-1.0)';
      PINUSE='OUT';
    'A_PETN15':
      PIN_NUMBER='(0,0,0,0,0,0,EW29,0,0,0,0)';
      OUTPUT_LOAD='(1.0,-1.0)';
      PINUSE='OUT';
    'B_PERP0':
      PIN_NUMBER='(0,0,0,0,0,0,0,N34,0,0,0)';
      INPUT_LOAD='(-0.01,0.01)';
      PINUSE='IN';
    'B_PERN0':
      PIN_NUMBER='(0,0,0,0,0,0,0,R35,0,0,0)';
      INPUT_LOAD='(-0.01,0.01)';
      PINUSE='IN';
    'B_PERP1':
      PIN_NUMBER='(0,0,0,0,0,0,0,Y34,0,0,0)';
      INPUT_LOAD='(-0.01,0.01)';
      PINUSE='IN';
    'B_PERN1':
      PIN_NUMBER='(0,0,0,0,0,0,0,AB35,0,0,0)';
      INPUT_LOAD='(-0.01,0.01)';
      PINUSE='IN';
    'B_PERP2':
      PIN_NUMBER='(0,0,0,0,0,0,0,AG34,0,0,0)';
      INPUT_LOAD='(-0.01,0.01)';
      PINUSE='IN';
    'B_PERN2':
      PIN_NUMBER='(0,0,0,0,0,0,0,AJ35,0,0,0)';
      INPUT_LOAD='(-0.01,0.01)';
      PINUSE='IN';
    'B_PERP3':
      PIN_NUMBER='(0,0,0,0,0,0,0,AP34,0,0,0)';
      INPUT_LOAD='(-0.01,0.01)';
      PINUSE='IN';
    'B_PERN3':
      PIN_NUMBER='(0,0,0,0,0,0,0,AT35,0,0,0)';
      INPUT_LOAD='(-0.01,0.01)';
      PINUSE='IN';
    'B_PERP4':
      PIN_NUMBER='(0,0,0,0,0,0,0,BA34,0,0,0)';
      INPUT_LOAD='(-0.01,0.01)';
      PINUSE='IN';
    'B_PERN4':
      PIN_NUMBER='(0,0,0,0,0,0,0,BC35,0,0,0)';
      INPUT_LOAD='(-0.01,0.01)';
      PINUSE='IN';
    'B_PERP5':
      PIN_NUMBER='(0,0,0,0,0,0,0,BH34,0,0,0)';
      INPUT_LOAD='(-0.01,0.01)';
      PINUSE='IN';
    'B_PERN5':
      PIN_NUMBER='(0,0,0,0,0,0,0,BK35,0,0,0)';
      INPUT_LOAD='(-0.01,0.01)';
      PINUSE='IN';
    'B_PERP6':
      PIN_NUMBER='(0,0,0,0,0,0,0,BR34,0,0,0)';
      INPUT_LOAD='(-0.01,0.01)';
      PINUSE='IN';
    'B_PERN6':
      PIN_NUMBER='(0,0,0,0,0,0,0,BU35,0,0,0)';
      INPUT_LOAD='(-0.01,0.01)';
      PINUSE='IN';
    'B_PERP7':
      PIN_NUMBER='(0,0,0,0,0,0,0,CB34,0,0,0)';
      INPUT_LOAD='(-0.01,0.01)';
      PINUSE='IN';
    'B_PERN7':
      PIN_NUMBER='(0,0,0,0,0,0,0,CD35,0,0,0)';
      INPUT_LOAD='(-0.01,0.01)';
      PINUSE='IN';
    'B_PERP8':
      PIN_NUMBER='(0,0,0,0,0,0,0,0,CJ34,0,0)';
      INPUT_LOAD='(-0.01,0.01)';
      PINUSE='IN';
    'B_PERN8':
      PIN_NUMBER='(0,0,0,0,0,0,0,0,CL35,0,0)';
      INPUT_LOAD='(-0.01,0.01)';
      PINUSE='IN';
    'B_PERP9':
      PIN_NUMBER='(0,0,0,0,0,0,0,0,CT34,0,0)';
      INPUT_LOAD='(-0.01,0.01)';
      PINUSE='IN';
    'B_PERN9':
      PIN_NUMBER='(0,0,0,0,0,0,0,0,CV35,0,0)';
      INPUT_LOAD='(-0.01,0.01)';
      PINUSE='IN';
    'B_PERP10':
      PIN_NUMBER='(0,0,0,0,0,0,0,0,DC34,0,0)';
      INPUT_LOAD='(-0.01,0.01)';
      PINUSE='IN';
    'B_PERN10':
      PIN_NUMBER='(0,0,0,0,0,0,0,0,DE35,0,0)';
      INPUT_LOAD='(-0.01,0.01)';
      PINUSE='IN';
    'B_PERP11':
      PIN_NUMBER='(0,0,0,0,0,0,0,0,DK34,0,0)';
      INPUT_LOAD='(-0.01,0.01)';
      PINUSE='IN';
    'B_PERN11':
      PIN_NUMBER='(0,0,0,0,0,0,0,0,DM35,0,0)';
      INPUT_LOAD='(-0.01,0.01)';
      PINUSE='IN';
    'B_PERP12':
      PIN_NUMBER='(0,0,0,0,0,0,0,0,DU34,0,0)';
      INPUT_LOAD='(-0.01,0.01)';
      PINUSE='IN';
    'B_PERN12':
      PIN_NUMBER='(0,0,0,0,0,0,0,0,DW35,0,0)';
      INPUT_LOAD='(-0.01,0.01)';
      PINUSE='IN';
    'B_PERP13':
      PIN_NUMBER='(0,0,0,0,0,0,0,0,ED34,0,0)';
      INPUT_LOAD='(-0.01,0.01)';
      PINUSE='IN';
    'B_PERN13':
      PIN_NUMBER='(0,0,0,0,0,0,0,0,EF35,0,0)';
      INPUT_LOAD='(-0.01,0.01)';
      PINUSE='IN';
    'B_PERP14':
      PIN_NUMBER='(0,0,0,0,0,0,0,0,EL34,0,0)';
      INPUT_LOAD='(-0.01,0.01)';
      PINUSE='IN';
    'B_PERN14':
      PIN_NUMBER='(0,0,0,0,0,0,0,0,EN35,0,0)';
      INPUT_LOAD='(-0.01,0.01)';
      PINUSE='IN';
    'B_PERP15':
      PIN_NUMBER='(0,0,0,0,0,0,0,0,EV34,0,0)';
      INPUT_LOAD='(-0.01,0.01)';
      PINUSE='IN';
    'B_PERN15':
      PIN_NUMBER='(0,0,0,0,0,0,0,0,EY35,0,0)';
      INPUT_LOAD='(-0.01,0.01)';
      PINUSE='IN';
    'B_PETP0':
      PIN_NUMBER='(0,0,0,0,0,0,0,0,0,M7,0)';
      OUTPUT_LOAD='(1.0,-1.0)';
      PINUSE='OUT';
    'B_PETN0':
      PIN_NUMBER='(0,0,0,0,0,0,0,0,0,P10,0)';
      OUTPUT_LOAD='(1.0,-1.0)';
      PINUSE='OUT';
    'B_PETP1':
      PIN_NUMBER='(0,0,0,0,0,0,0,0,0,W7,0)';
      OUTPUT_LOAD='(1.0,-1.0)';
      PINUSE='OUT';
    'B_PETN1':
      PIN_NUMBER='(0,0,0,0,0,0,0,0,0,AA10,0)';
      OUTPUT_LOAD='(1.0,-1.0)';
      PINUSE='OUT';
    'B_PETP2':
      PIN_NUMBER='(0,0,0,0,0,0,0,0,0,AF7,0)';
      OUTPUT_LOAD='(1.0,-1.0)';
      PINUSE='OUT';
    'B_PETN2':
      PIN_NUMBER='(0,0,0,0,0,0,0,0,0,AH10,0)';
      OUTPUT_LOAD='(1.0,-1.0)';
      PINUSE='OUT';
    'B_PETP3':
      PIN_NUMBER='(0,0,0,0,0,0,0,0,0,AN7,0)';
      OUTPUT_LOAD='(1.0,-1.0)';
      PINUSE='OUT';
    'B_PETN3':
      PIN_NUMBER='(0,0,0,0,0,0,0,0,0,AR10,0)';
      OUTPUT_LOAD='(1.0,-1.0)';
      PINUSE='OUT';
    'B_PETP4':
      PIN_NUMBER='(0,0,0,0,0,0,0,0,0,AY7,0)';
      OUTPUT_LOAD='(1.0,-1.0)';
      PINUSE='OUT';
    'B_PETN4':
      PIN_NUMBER='(0,0,0,0,0,0,0,0,0,BB10,0)';
      OUTPUT_LOAD='(1.0,-1.0)';
      PINUSE='OUT';
    'B_PETP5':
      PIN_NUMBER='(0,0,0,0,0,0,0,0,0,BG7,0)';
      OUTPUT_LOAD='(1.0,-1.0)';
      PINUSE='OUT';
    'B_PETN5':
      PIN_NUMBER='(0,0,0,0,0,0,0,0,0,BJ10,0)';
      OUTPUT_LOAD='(1.0,-1.0)';
      PINUSE='OUT';
    'B_PETP6':
      PIN_NUMBER='(0,0,0,0,0,0,0,0,0,BP7,0)';
      OUTPUT_LOAD='(1.0,-1.0)';
      PINUSE='OUT';
    'B_PETN6':
      PIN_NUMBER='(0,0,0,0,0,0,0,0,0,BT10,0)';
      OUTPUT_LOAD='(1.0,-1.0)';
      PINUSE='OUT';
    'B_PETP7':
      PIN_NUMBER='(0,0,0,0,0,0,0,0,0,CA7,0)';
      OUTPUT_LOAD='(1.0,-1.0)';
      PINUSE='OUT';
    'B_PETN7':
      PIN_NUMBER='(0,0,0,0,0,0,0,0,0,CC10,0)';
      OUTPUT_LOAD='(1.0,-1.0)';
      PINUSE='OUT';
    'B_PETP8':
      PIN_NUMBER='(0,0,0,0,0,0,0,0,0,0,CH7)';
      OUTPUT_LOAD='(1.0,-1.0)';
      PINUSE='OUT';
    'B_PETN8':
      PIN_NUMBER='(0,0,0,0,0,0,0,0,0,0,CK10)';
      OUTPUT_LOAD='(1.0,-1.0)';
      PINUSE='OUT';
    'B_PETP9':
      PIN_NUMBER='(0,0,0,0,0,0,0,0,0,0,CR7)';
      OUTPUT_LOAD='(1.0,-1.0)';
      PINUSE='OUT';
    'B_PETN9':
      PIN_NUMBER='(0,0,0,0,0,0,0,0,0,0,CU10)';
      OUTPUT_LOAD='(1.0,-1.0)';
      PINUSE='OUT';
    'B_PETP10':
      PIN_NUMBER='(0,0,0,0,0,0,0,0,0,0,DB7)';
      OUTPUT_LOAD='(1.0,-1.0)';
      PINUSE='OUT';
    'B_PETN10':
      PIN_NUMBER='(0,0,0,0,0,0,0,0,0,0,DD10)';
      OUTPUT_LOAD='(1.0,-1.0)';
      PINUSE='OUT';
    'B_PETP11':
      PIN_NUMBER='(0,0,0,0,0,0,0,0,0,0,DJ7)';
      OUTPUT_LOAD='(1.0,-1.0)';
      PINUSE='OUT';
    'B_PETN11':
      PIN_NUMBER='(0,0,0,0,0,0,0,0,0,0,DL10)';
      OUTPUT_LOAD='(1.0,-1.0)';
      PINUSE='OUT';
    'B_PETP12':
      PIN_NUMBER='(0,0,0,0,0,0,0,0,0,0,DT7)';
      OUTPUT_LOAD='(1.0,-1.0)';
      PINUSE='OUT';
    'B_PETN12':
      PIN_NUMBER='(0,0,0,0,0,0,0,0,0,0,DV10)';
      OUTPUT_LOAD='(1.0,-1.0)';
      PINUSE='OUT';
    'B_PETP13':
      PIN_NUMBER='(0,0,0,0,0,0,0,0,0,0,EC7)';
      OUTPUT_LOAD='(1.0,-1.0)';
      PINUSE='OUT';
    'B_PETN13':
      PIN_NUMBER='(0,0,0,0,0,0,0,0,0,0,EE10)';
      OUTPUT_LOAD='(1.0,-1.0)';
      PINUSE='OUT';
    'B_PETP14':
      PIN_NUMBER='(0,0,0,0,0,0,0,0,0,0,EK7)';
      OUTPUT_LOAD='(1.0,-1.0)';
      PINUSE='OUT';
    'B_PETN14':
      PIN_NUMBER='(0,0,0,0,0,0,0,0,0,0,EM10)';
      OUTPUT_LOAD='(1.0,-1.0)';
      PINUSE='OUT';
    'B_PETP15':
      PIN_NUMBER='(0,0,0,0,0,0,0,0,0,0,EU7)';
      OUTPUT_LOAD='(1.0,-1.0)';
      PINUSE='OUT';
    'B_PETN15':
      PIN_NUMBER='(0,0,0,0,0,0,0,0,0,0,EW10)';
      OUTPUT_LOAD='(1.0,-1.0)';
      PINUSE='OUT';
  end_pin;
  body
      PART_NAME='PT5161LRS';
      BODY_NAME='PT5161LRS';
      PHYS_DES_PREFIX='U';
      CLASS='IC';
      STANDARD='End of Design';
      LIFECYCLE='Comp-Approve';
      PART_NUMBER='AJ051610U03';
      JEDEC_TYPE='BGA354_8-9X22-8';
      DESCRIPTION='IC(354P)PT5161LRS(FC-CSP)';
      MANUFTR='AEB';
      MANUF_PN='PT5161LRS';
      RD_CMPLS_LVL='EP(V1)';
      CMPLS_LVL='';
      FROM_PJ='S7P-JIM';
      DIP_SMD='';
      DATA='AEB_PT5161LRS.pdf';
      EE_CHECK_LIST='';
      FP_ECN='PT5161LRS.msg';
      PSL='';
      CREATOR='';
      STATUS='';
      MSD='';
      ESD_CDM='';
      ESD_HBM='';
      ESD_MM='';
      PIN_LENGTH_SHORT_PIN='0 MILS';
      PIN_LENGTH_LONG_PIN='0 MILS';
      CREATEDAY='20220512';
      PARENT_PART_TYPE='PT5161LRS';
      PARENT_PPT='PT5161LRS';
      PARENT_PPT_PART='PT5161LRS-PT5161LRS,SMLF,IC,AJ051610U03';
  end_body;
end_primitive;
primitive 'Q_CAPP_SMLF-100UF,16V,20%,OSCON,CC71003MZ30';
  pin
    'A':
      PIN_NUMBER='(1)';
      PIN_TYPE='UNSPEC';
      NO_LOAD_CHECK='BOTH';
      NO_IO_CHECK='BOTH';
      PINUSE='UNSPEC';
    'B':
      PIN_NUMBER='(2)';
      PIN_TYPE='UNSPEC';
      NO_LOAD_CHECK='BOTH';
      NO_IO_CHECK='BOTH';
      PINUSE='UNSPEC';
  end_pin;
  body
      PART_NAME='Q_CAPP';
      PHYS_DES_PREFIX='C';
      STANDARD='';
      LIFECYCLE='';
      PART_NUMBER='CC71003MZ30';
      JEDEC_TYPE='EC56_197_229SXA';
      VALUE='100UF';
      RATED_VOLTAGE='16V';
      TOL='20%';
      CLASS='DISCRETE';
      DESCRIPTION='CAP OSCON SMD 100U 16V(20%,5*5.8)NPN';
      COMPONENT_TYPE='SMT';
      LEAD_LENGTH='';
      DFM_EXCLUSION='';
      DAY='20190627';
      PARENT_PART_TYPE='Q_CAPP';
      PARENT_PPT='Q_CAPP';
      PARENT_PPT_PART='Q_CAPP_SMLF-100UF,16V,20%,OSCON,CC71003MZ30';
  end_body;
end_primitive;
primitive 'Q_CAPP_SMLF-220UF,4V,20%,SPCAP,CH122KM8801';
  pin
    'A':
      PIN_NUMBER='(1)';
      PIN_TYPE='UNSPEC';
      NO_LOAD_CHECK='BOTH';
      NO_IO_CHECK='BOTH';
      PINUSE='UNSPEC';
    'B':
      PIN_NUMBER='(2)';
      PIN_TYPE='UNSPEC';
      NO_LOAD_CHECK='BOTH';
      NO_IO_CHECK='BOTH';
      PINUSE='UNSPEC';
  end_pin;
  body
      PART_NAME='Q_CAPP';
      PHYS_DES_PREFIX='C';
      STANDARD='';
      LIFECYCLE='';
      PART_NUMBER='CH122KM8801';
      JEDEC_TYPE='TAJ_SX';
      VALUE='220UF';
      RATED_VOLTAGE='4V';
      TOL='20%';
      CLASS='DISCRETE';
      DESCRIPTION='CAP CHIP 220U 4V(20%,7343,SPCAP)MAT';
      COMPONENT_TYPE='SMT';
      LEAD_LENGTH='';
      DFM_EXCLUSION='';
      DAY='20211108';
      PARENT_PART_TYPE='Q_CAPP';
      PARENT_PPT='Q_CAPP';
      PARENT_PPT_PART='Q_CAPP_SMLF-220UF,4V,20%,SPCAP,CH122KM8801';
  end_body;
end_primitive;
primitive 'Q_CAPP_SMLF-220UF,6.3V,20%,ALUM,CC72201MZ28';
  pin
    'A':
      PIN_NUMBER='(1)';
      PIN_TYPE='UNSPEC';
      NO_LOAD_CHECK='BOTH';
      NO_IO_CHECK='BOTH';
      PINUSE='UNSPEC';
    'B':
      PIN_NUMBER='(2)';
      PIN_TYPE='UNSPEC';
      NO_LOAD_CHECK='BOTH';
      NO_IO_CHECK='BOTH';
      PINUSE='UNSPEC';
  end_pin;
  body
      PART_NAME='Q_CAPP';
      PHYS_DES_PREFIX='C';
      STANDARD='';
      LIFECYCLE='';
      PART_NUMBER='CC72201MZ28';
      JEDEC_TYPE='EC56_197_229SXA';
      VALUE='220UF';
      RATED_VOLTAGE='6.3V';
      TOL='20%';
      CLASS='DISCRETE';
      DESCRIPTION='CAP OSCON SMD 220U 6.3V(20%,5*5.8)NPN';
      COMPONENT_TYPE='SMT';
      LEAD_LENGTH='';
      DFM_EXCLUSION='';
      DAY='20170503';
      PARENT_PART_TYPE='Q_CAPP';
      PARENT_PPT='Q_CAPP';
      PARENT_PPT_PART='Q_CAPP_SMLF-220UF,6.3V,20%,ALUM,CC72201MZ28';
  end_body;
end_primitive;
primitive 'Q_CAPP_SMLF-270UF,16V,20%,OSCON,CC72703MZ11';
  pin
    'A':
      PIN_NUMBER='(1)';
      PIN_TYPE='UNSPEC';
      NO_LOAD_CHECK='BOTH';
      NO_IO_CHECK='BOTH';
      PINUSE='UNSPEC';
    'B':
      PIN_NUMBER='(2)';
      PIN_TYPE='UNSPEC';
      NO_LOAD_CHECK='BOTH';
      NO_IO_CHECK='BOTH';
      PINUSE='UNSPEC';
  end_pin;
  body
      PART_NAME='Q_CAPP';
      PHYS_DES_PREFIX='C';
      STANDARD='';
      LIFECYCLE='';
      PART_NUMBER='CC72703MZ11';
      JEDEC_TYPE='EC75_248_304S';
      VALUE='270UF';
      RATED_VOLTAGE='16V';
      TOL='20%';
      CLASS='DISCRETE';
      DESCRIPTION='CAP OSCON SMD 270U 16V(20%,6.3*7.7)NPN';
      COMPONENT_TYPE='SMT';
      LEAD_LENGTH='';
      DFM_EXCLUSION='';
      DAY='20201209';
      PARENT_PART_TYPE='Q_CAPP';
      PARENT_PPT='Q_CAPP';
      PARENT_PPT_PART='Q_CAPP_SMLF-270UF,16V,20%,OSCON,CC72703MZ11';
  end_body;
end_primitive;
primitive 'Q_CAPP_SMLF-390UF,2.5V,20%,ALUM,CC7390JMZ13';
  pin
    'A':
      PIN_NUMBER='(1)';
      PIN_TYPE='UNSPEC';
      NO_LOAD_CHECK='BOTH';
      NO_IO_CHECK='BOTH';
      PINUSE='UNSPEC';
    'B':
      PIN_NUMBER='(2)';
      PIN_TYPE='UNSPEC';
      NO_LOAD_CHECK='BOTH';
      NO_IO_CHECK='BOTH';
      PINUSE='UNSPEC';
  end_pin;
  body
      PART_NAME='Q_CAPP';
      PHYS_DES_PREFIX='C';
      STANDARD='';
      LIFECYCLE='';
      PART_NUMBER='CC7390JMZ13';
      JEDEC_TYPE='EC56_197_229SXA';
      VALUE='390UF';
      RATED_VOLTAGE='2.5V';
      TOL='20%';
      CLASS='DISCRETE';
      DESCRIPTION='CAP OSCON SMD 390U 2.5V(20%,5*5.8)NPN';
      COMPONENT_TYPE='SMT';
      LEAD_LENGTH='';
      DFM_EXCLUSION='';
      DAY='20170503';
      PARENT_PART_TYPE='Q_CAPP';
      PARENT_PPT='Q_CAPP';
      PARENT_PPT_PART='Q_CAPP_SMLF-390UF,2.5V,20%,ALUM,CC7390JMZ13';
  end_body;
end_primitive;
primitive 'Q_CAPP_SMLF-470UF,2.5V,20%,EMPTY,CH747LM8825';
  pin
    'A':
      PIN_NUMBER='(1)';
      PIN_TYPE='UNSPEC';
      NO_LOAD_CHECK='BOTH';
      NO_IO_CHECK='BOTH';
      PINUSE='UNSPEC';
    'B':
      PIN_NUMBER='(2)';
      PIN_TYPE='UNSPEC';
      NO_LOAD_CHECK='BOTH';
      NO_IO_CHECK='BOTH';
      PINUSE='UNSPEC';
  end_pin;
  body
      PART_NAME='Q_CAPP';
      PHYS_DES_PREFIX='C';
      STANDARD='';
      LIFECYCLE='';
      PART_NUMBER='CH747LM8825';
      JEDEC_TYPE='TAJ_SX';
      VALUE='470UF';
      RATED_VOLTAGE='2.5V';
      TOL='20%';
      CLASS='IO';
      DESCRIPTION='CAPCHIP 470U 2.5V(20%,SP,ESR4.5,7343)MAT';
      COMPONENT_TYPE='SMT';
      LEAD_LENGTH='';
      DFM_EXCLUSION='';
      DAY='20201120';
      PARENT_PART_TYPE='Q_CAPP';
      PARENT_PPT='Q_CAPP';
      PARENT_PPT_PART='Q_CAPP_SMLF-470UF,2.5V,20%,EMPTY,CH747LM8825';
  end_body;
end_primitive;
primitive 'Q_CAPP_SMLF-470UF,2.5V,20%,SPCAP,CH747LM8818';
  pin
    'A':
      PIN_NUMBER='(1)';
      PIN_TYPE='UNSPEC';
      NO_LOAD_CHECK='BOTH';
      NO_IO_CHECK='BOTH';
      PINUSE='UNSPEC';
    'B':
      PIN_NUMBER='(2)';
      PIN_TYPE='UNSPEC';
      NO_LOAD_CHECK='BOTH';
      NO_IO_CHECK='BOTH';
      PINUSE='UNSPEC';
  end_pin;
  body
      PART_NAME='Q_CAPP';
      PHYS_DES_PREFIX='C';
      STANDARD='';
      LIFECYCLE='';
      PART_NUMBER='CH747LM8818';
      JEDEC_TYPE='TAJ_DXC';
      VALUE='470UF';
      RATED_VOLTAGE='2.5V';
      TOL='20%';
      CLASS='DISCRETE';
      DESCRIPTION='CAP CHIP 470U 2.5V(+-20%,7343,SPCAP)MAT';
      COMPONENT_TYPE='SMT';
      LEAD_LENGTH='';
      DFM_EXCLUSION='';
      DAY='20200318';
      PARENT_PART_TYPE='Q_CAPP';
      PARENT_PPT='Q_CAPP';
      PARENT_PPT_PART='Q_CAPP_SMLF-470UF,2.5V,20%,SPCAP,CH747LM8818';
  end_body;
end_primitive;
primitive 'Q_CAPP_SMLF-470UF,2.5V,20%,SPCAP,CH747LM8825';
  pin
    'A':
      PIN_NUMBER='(1)';
      PIN_TYPE='UNSPEC';
      NO_LOAD_CHECK='BOTH';
      NO_IO_CHECK='BOTH';
      PINUSE='UNSPEC';
    'B':
      PIN_NUMBER='(2)';
      PIN_TYPE='UNSPEC';
      NO_LOAD_CHECK='BOTH';
      NO_IO_CHECK='BOTH';
      PINUSE='UNSPEC';
  end_pin;
  body
      PART_NAME='Q_CAPP';
      PHYS_DES_PREFIX='C';
      STANDARD='';
      LIFECYCLE='';
      PART_NUMBER='CH747LM8825';
      JEDEC_TYPE='TAJ_SX';
      VALUE='470UF';
      RATED_VOLTAGE='2.5V';
      TOL='20%';
      CLASS='DISCRETE';
      DESCRIPTION='CAPCHIP 470U 2.5V(20%,SP,ESR4.5,7343)MAT';
      COMPONENT_TYPE='SMT';
      LEAD_LENGTH='';
      DFM_EXCLUSION='';
      DAY='20201120';
      PARENT_PART_TYPE='Q_CAPP';
      PARENT_PPT='Q_CAPP';
      PARENT_PPT_PART='Q_CAPP_SMLF-470UF,2.5V,20%,SPCAP,CH747LM8825';
  end_body;
end_primitive;
primitive 'Q_CAPP_THLF-270UF,16V,20%,OSCON,CC72703MD38';
  pin
    'A':
      PIN_NUMBER='(1)';
      PIN_TYPE='UNSPEC';
      NO_LOAD_CHECK='BOTH';
      NO_IO_CHECK='BOTH';
      PINUSE='UNSPEC';
    'B':
      PIN_NUMBER='(2)';
      PIN_TYPE='UNSPEC';
      NO_LOAD_CHECK='BOTH';
      NO_IO_CHECK='BOTH';
      PINUSE='UNSPEC';
  end_pin;
  body
      PART_NAME='Q_CAPP';
      PHYS_DES_PREFIX='C';
      STANDARD='';
      LIFECYCLE='';
      PART_NUMBER='CC72703MD38';
      JEDEC_TYPE='EC2-5_6-8_9-2';
      VALUE='270UF';
      RATED_VOLTAGE='16V';
      TOL='20%';
      CLASS='DISCRETE';
      DESCRIPTION='CAPOSCON DIP 270U16V(20%,ESR10,6.3*8)NPN';
      COMPONENT_TYPE='DIP';
      LEAD_LENGTH='';
      DFM_EXCLUSION='';
      DAY='20190701';
      PARENT_PART_TYPE='Q_CAPP';
      PARENT_PPT='Q_CAPP';
      PARENT_PPT_PART='Q_CAPP_THLF-270UF,16V,20%,OSCON,CC72703MD38';
  end_body;
end_primitive;
primitive 'Q_CAPP_THLF-560UF,6.3V,20%,OSCON,CC75601MD16';
  pin
    'A':
      PIN_NUMBER='(1)';
      PIN_TYPE='UNSPEC';
      NO_LOAD_CHECK='BOTH';
      NO_IO_CHECK='BOTH';
      PINUSE='UNSPEC';
    'B':
      PIN_NUMBER='(2)';
      PIN_TYPE='UNSPEC';
      NO_LOAD_CHECK='BOTH';
      NO_IO_CHECK='BOTH';
      PINUSE='UNSPEC';
  end_pin;
  body
      PART_NAME='Q_CAPP';
      PHYS_DES_PREFIX='C';
      STANDARD='';
      LIFECYCLE='';
      PART_NUMBER='CC75601MD16';
      JEDEC_TYPE='EC2-5_6-8_9-5';
      VALUE='560UF';
      RATED_VOLTAGE='6.3V';
      TOL='20%';
      CLASS='DISCRETE';
      DESCRIPTION='CAP OSCON DIP 560U 6.3V(+-20%,6.3*8)NPN';
      COMPONENT_TYPE='DIP';
      LEAD_LENGTH='';
      DFM_EXCLUSION='';
      DAY='20190701';
      PARENT_PART_TYPE='Q_CAPP';
      PARENT_PPT='Q_CAPP';
      PARENT_PPT_PART='Q_CAPP_THLF-560UF,6.3V,20%,OSCON,CC75601MD16';
  end_body;
end_primitive;
primitive 'Q_CAP_0201-1UF,4V,20%,X6S,CH-10KMEE00';
  pin
    'A':
      PIN_NUMBER='(1)';
      PINUSE='UNSPEC';
      NO_LOAD_CHECK='BOTH';
      NO_IO_CHECK='BOTH';
      ALLOW_CONNECT='TRUE';
      PIN_GROUP='1';
    'B':
      PIN_NUMBER='(2)';
      PINUSE='UNSPEC';
      NO_LOAD_CHECK='BOTH';
      NO_IO_CHECK='BOTH';
      ALLOW_CONNECT='TRUE';
      PIN_GROUP='1';
  end_pin;
  body
      PART_NAME='Q_CAP';
      PHYS_DES_PREFIX='C';
      STANDARD='End of Design';
      LIFECYCLE='Comp-Approve';
      ASS_PART='';
      PART_NUMBER='CH-10KMEE00';
      JEDEC_TYPE='C0201';
      ALT_SYMBOLS='(SMC0201AW)';
      VALUE='1UF';
      RATED_VOLTAGE='4V';
      TOL='20%';
      CLASS='DISCRETE';
      DESCRIPTION='CAP CHIP 1U 4V(+-20%,X6S,0201)';
      COMPONENT_TYPE='CHIP0201';
      LEAD_LENGTH='';
      LPID='';
      DATE='20150713';
      PARENT_PART_TYPE='Q_CAP';
      PARENT_PPT='Q_CAP';
      PARENT_PPT_PART='Q_CAP_0201-1UF,4V,20%,X6S,CH-10KMEE00';
  end_body;
end_primitive;
primitive 'Q_CAP_0402-0.022UF,25V,10%,X7R,CH3224K1B01';
  pin
    'A':
      PIN_NUMBER='(1)';
      PINUSE='UNSPEC';
      NO_LOAD_CHECK='BOTH';
      NO_IO_CHECK='BOTH';
      ALLOW_CONNECT='TRUE';
      PIN_GROUP='1';
    'B':
      PIN_NUMBER='(2)';
      PINUSE='UNSPEC';
      NO_LOAD_CHECK='BOTH';
      NO_IO_CHECK='BOTH';
      ALLOW_CONNECT='TRUE';
      PIN_GROUP='1';
  end_pin;
  body
      PART_NAME='Q_CAP';
      PHYS_DES_PREFIX='C';
      STANDARD='';
      LIFECYCLE='';
      ASS_PART='';
      PART_NUMBER='CH3224K1B01';
      JEDEC_TYPE='C0402';
      ALT_SYMBOLS='(C0402_OCTAGONXA,C0402-0201)';
      VALUE='0.022UF';
      RATED_VOLTAGE='25V';
      TOL='10%';
      CLASS='DISCRETE';
      DESCRIPTION='CAP CHIP 0.022U 25V(+-10%,X7R,0402)';
      COMPONENT_TYPE='CHIP0402';
      LEAD_LENGTH='';
      LPID='';
      DATE='20110413';
      PARENT_PART_TYPE='Q_CAP';
      PARENT_PPT='Q_CAP';
      PARENT_PPT_PART='Q_CAP_0402-0.022UF,25V,10%,X7R,CH3224K1B01';
  end_body;
end_primitive;
primitive 'Q_CAP_0402-0.068UF,16V,10%,X7R,CH3683K1B09';
  pin
    'A':
      PIN_NUMBER='(1)';
      PINUSE='UNSPEC';
      NO_LOAD_CHECK='BOTH';
      NO_IO_CHECK='BOTH';
      ALLOW_CONNECT='TRUE';
      PIN_GROUP='1';
    'B':
      PIN_NUMBER='(2)';
      PINUSE='UNSPEC';
      NO_LOAD_CHECK='BOTH';
      NO_IO_CHECK='BOTH';
      ALLOW_CONNECT='TRUE';
      PIN_GROUP='1';
  end_pin;
  body
      PART_NAME='Q_CAP';
      PHYS_DES_PREFIX='C';
      STANDARD='';
      LIFECYCLE='';
      ASS_PART='';
      PART_NUMBER='CH3683K1B09';
      JEDEC_TYPE='C0402';
      ALT_SYMBOLS='(C0402-0201)';
      VALUE='0.068UF';
      RATED_VOLTAGE='16V';
      TOL='10%';
      CLASS='DISCRETE';
      DESCRIPTION='CAP CHIP 0.068UF 16V(+-10%,X7R 0402)';
      COMPONENT_TYPE='CHIP0402';
      LEAD_LENGTH='';
      LPID='';
      DATE='20100630';
      PARENT_PART_TYPE='Q_CAP';
      PARENT_PPT='Q_CAP';
      PARENT_PPT_PART='Q_CAP_0402-0.068UF,16V,10%,X7R,CH3683K1B09';
  end_body;
end_primitive;
primitive 'Q_CAP_0402-0.1UF,25V,10%,EMPTY,CH4104K1B00';
  pin
    'A':
      PIN_NUMBER='(1)';
      PINUSE='UNSPEC';
      NO_LOAD_CHECK='BOTH';
      NO_IO_CHECK='BOTH';
      ALLOW_CONNECT='TRUE';
      PIN_GROUP='1';
    'B':
      PIN_NUMBER='(2)';
      PINUSE='UNSPEC';
      NO_LOAD_CHECK='BOTH';
      NO_IO_CHECK='BOTH';
      ALLOW_CONNECT='TRUE';
      PIN_GROUP='1';
  end_pin;
  body
      PART_NAME='Q_CAP';
      PHYS_DES_PREFIX='C';
      STANDARD='';
      LIFECYCLE='';
      ASS_PART='';
      PART_NUMBER='CH4104K1B00';
      JEDEC_TYPE='C0402';
      ALT_SYMBOLS='(C0402_OCTAGONXA,C0402-0201)';
      VALUE='NA';
      RATED_VOLTAGE='25V';
      TOL='10%';
      CLASS='IO';
      DESCRIPTION='CAP CHIP 0.1U 25V(+-10%,X7R,0402)';
      COMPONENT_TYPE='CHIP0402';
      LEAD_LENGTH='';
      LPID='';
      DATE='20160113';
      PARENT_PART_TYPE='Q_CAP';
      PARENT_PPT='Q_CAP';
      PARENT_PPT_PART='Q_CAP_0402-0.1UF,25V,10%,EMPTY,CH4104K1B00';
  end_body;
end_primitive;
primitive 'Q_CAP_0402-0.1UF,25V,10%,X7R,CH4104K1B00';
  pin
    'A':
      PIN_NUMBER='(1)';
      PINUSE='UNSPEC';
      NO_LOAD_CHECK='BOTH';
      NO_IO_CHECK='BOTH';
      ALLOW_CONNECT='TRUE';
      PIN_GROUP='1';
    'B':
      PIN_NUMBER='(2)';
      PINUSE='UNSPEC';
      NO_LOAD_CHECK='BOTH';
      NO_IO_CHECK='BOTH';
      ALLOW_CONNECT='TRUE';
      PIN_GROUP='1';
  end_pin;
  body
      PART_NAME='Q_CAP';
      PHYS_DES_PREFIX='C';
      STANDARD='';
      LIFECYCLE='';
      ASS_PART='';
      PART_NUMBER='CH4104K1B00';
      JEDEC_TYPE='C0402';
      ALT_SYMBOLS='(C0402_OCTAGONXA,C0402-0201)';
      VALUE='0.1UF';
      RATED_VOLTAGE='25V';
      TOL='10%';
      CLASS='DISCRETE';
      DESCRIPTION='CAP CHIP 0.1U 25V(+-10%,X7R,0402)';
      COMPONENT_TYPE='CHIP0402';
      LEAD_LENGTH='';
      LPID='';
      DATE='20160113';
      PARENT_PART_TYPE='Q_CAP';
      PARENT_PPT='Q_CAP';
      PARENT_PPT_PART='Q_CAP_0402-0.1UF,25V,10%,X7R,CH4104K1B00';
  end_body;
end_primitive;
primitive 'Q_CAP_0402-0.22UF,16V,10%,X7R,CH4223K1B00';
  pin
    'A':
      PIN_NUMBER='(1)';
      PINUSE='UNSPEC';
      NO_LOAD_CHECK='BOTH';
      NO_IO_CHECK='BOTH';
      ALLOW_CONNECT='TRUE';
      PIN_GROUP='1';
    'B':
      PIN_NUMBER='(2)';
      PINUSE='UNSPEC';
      NO_LOAD_CHECK='BOTH';
      NO_IO_CHECK='BOTH';
      ALLOW_CONNECT='TRUE';
      PIN_GROUP='1';
  end_pin;
  body
      PART_NAME='Q_CAP';
      PHYS_DES_PREFIX='C';
      STANDARD='End of Design';
      LIFECYCLE='Comp-Approve';
      ASS_PART='';
      PART_NUMBER='CH4223K1B00';
      JEDEC_TYPE='C0402';
      ALT_SYMBOLS='(C0402_OCTAGONXA,C0402-0201)';
      VALUE='0.22UF';
      RATED_VOLTAGE='16V';
      TOL='10%';
      CLASS='DISCRETE';
      DESCRIPTION='CAP CHIP 0.22U 16V(10%,X7R,0402)';
      COMPONENT_TYPE='CHIP0402';
      LEAD_LENGTH='';
      LPID='';
      DATE='20100916';
      PARENT_PART_TYPE='Q_CAP';
      PARENT_PPT='Q_CAP';
      PARENT_PPT_PART='Q_CAP_0402-0.22UF,16V,10%,X7R,CH4223K1B00';
  end_body;
end_primitive;
primitive 'Q_CAP_0402-1000PF,50V,5%,EMPTY,TMP_QCH21006JB10';
  pin
    'A':
      PIN_NUMBER='(1)';
      PINUSE='UNSPEC';
      NO_LOAD_CHECK='BOTH';
      NO_IO_CHECK='BOTH';
      ALLOW_CONNECT='TRUE';
      PIN_GROUP='1';
    'B':
      PIN_NUMBER='(2)';
      PINUSE='UNSPEC';
      NO_LOAD_CHECK='BOTH';
      NO_IO_CHECK='BOTH';
      ALLOW_CONNECT='TRUE';
      PIN_GROUP='1';
  end_pin;
  body
      PART_NAME='Q_CAP';
      PHYS_DES_PREFIX='C';
      STANDARD='';
      LIFECYCLE='';
      ASS_PART='';
      PART_NUMBER='CH21006JB10';
      JEDEC_TYPE='C0402';
      ALT_SYMBOLS='(C0402-0201,C0402_OCTAGONXA)';
      VALUE='NA';
      RATED_VOLTAGE='50V';
      TOL='5%';
      CLASS='IO';
      DESCRIPTION='CAP CHIP 1000P 50V(+-5%,X7R,0402)';
      COMPONENT_TYPE='CHIP0402';
      LEAD_LENGTH='';
      LPID='';
      DATE='20100528';
      PARENT_PART_TYPE='Q_CAP';
      PARENT_PPT='Q_CAP';
      PARENT_PPT_PART='Q_CAP_0402-1000PF,50V,5%,EMPTY,TMP_QCH21006JB10';
  end_body;
end_primitive;
primitive 'Q_CAP_0402-1000PF,50V,5%,X7R,TMP_QCH21006JB10';
  pin
    'A':
      PIN_NUMBER='(1)';
      PINUSE='UNSPEC';
      NO_LOAD_CHECK='BOTH';
      NO_IO_CHECK='BOTH';
      ALLOW_CONNECT='TRUE';
      PIN_GROUP='1';
    'B':
      PIN_NUMBER='(2)';
      PINUSE='UNSPEC';
      NO_LOAD_CHECK='BOTH';
      NO_IO_CHECK='BOTH';
      ALLOW_CONNECT='TRUE';
      PIN_GROUP='1';
  end_pin;
  body
      PART_NAME='Q_CAP';
      PHYS_DES_PREFIX='C';
      STANDARD='';
      LIFECYCLE='';
      ASS_PART='';
      PART_NUMBER='CH21006JB10';
      JEDEC_TYPE='C0402';
      ALT_SYMBOLS='(C0402-0201,C0402_OCTAGONXA)';
      VALUE='1000PF';
      RATED_VOLTAGE='50V';
      TOL='5%';
      CLASS='DISCRETE';
      DESCRIPTION='CAP CHIP 1000P 50V(+-5%,X7R,0402)';
      COMPONENT_TYPE='CHIP0402';
      LEAD_LENGTH='';
      LPID='';
      DATE='20100528';
      PARENT_PART_TYPE='Q_CAP';
      PARENT_PPT='Q_CAP';
      PARENT_PPT_PART='Q_CAP_0402-1000PF,50V,5%,X7R,TMP_QCH21006JB10';
  end_body;
end_primitive;
primitive 'Q_CAP_0402-100PF,50V,5%,EMPTY,CH11006JB18';
  pin
    'A':
      PIN_NUMBER='(1)';
      PINUSE='UNSPEC';
      NO_LOAD_CHECK='BOTH';
      NO_IO_CHECK='BOTH';
      ALLOW_CONNECT='TRUE';
      PIN_GROUP='1';
    'B':
      PIN_NUMBER='(2)';
      PINUSE='UNSPEC';
      NO_LOAD_CHECK='BOTH';
      NO_IO_CHECK='BOTH';
      ALLOW_CONNECT='TRUE';
      PIN_GROUP='1';
  end_pin;
  body
      PART_NAME='Q_CAP';
      PHYS_DES_PREFIX='C';
      STANDARD='End of Design';
      LIFECYCLE='Comp-Approve';
      ASS_PART='';
      PART_NUMBER='CH11006JB18';
      JEDEC_TYPE='C0402';
      ALT_SYMBOLS='(C0402-0201)';
      VALUE='NA';
      RATED_VOLTAGE='50V';
      TOL='5%';
      CLASS='IO';
      DESCRIPTION='CAP CHIP 100P 50V(+-5%.X7R.0402)';
      COMPONENT_TYPE='CHIP0402';
      LEAD_LENGTH='';
      LPID='';
      DATE='20100929';
      PARENT_PART_TYPE='Q_CAP';
      PARENT_PPT='Q_CAP';
      PARENT_PPT_PART='Q_CAP_0402-100PF,50V,5%,EMPTY,CH11006JB18';
  end_body;
end_primitive;
primitive 'Q_CAP_0402-100PF,50V,5%,NPO,CH11006JB00';
  pin
    'A':
      PIN_NUMBER='(1)';
      PINUSE='UNSPEC';
      NO_LOAD_CHECK='BOTH';
      NO_IO_CHECK='BOTH';
      ALLOW_CONNECT='TRUE';
      PIN_GROUP='1';
    'B':
      PIN_NUMBER='(2)';
      PINUSE='UNSPEC';
      NO_LOAD_CHECK='BOTH';
      NO_IO_CHECK='BOTH';
      ALLOW_CONNECT='TRUE';
      PIN_GROUP='1';
  end_pin;
  body
      PART_NAME='Q_CAP';
      PHYS_DES_PREFIX='C';
      STANDARD='';
      LIFECYCLE='';
      ASS_PART='';
      PART_NUMBER='CH11006JB00';
      JEDEC_TYPE='C0402';
      ALT_SYMBOLS='(C0402-0201)';
      VALUE='100PF';
      RATED_VOLTAGE='50V';
      TOL='5%';
      CLASS='DISCRETE';
      DESCRIPTION='CAP CHIP 100P 50V(+-5%,NPO,0402)';
      COMPONENT_TYPE='CHIP0402';
      LEAD_LENGTH='';
      LPID='';
      DATE='20100618';
      PARENT_PART_TYPE='Q_CAP';
      PARENT_PPT='Q_CAP';
      PARENT_PPT_PART='Q_CAP_0402-100PF,50V,5%,NPO,CH11006JB00';
  end_body;
end_primitive;
primitive 'Q_CAP_0402-100PF,50V,5%,X7R,CH11006JB18';
  pin
    'A':
      PIN_NUMBER='(1)';
      PINUSE='UNSPEC';
      NO_LOAD_CHECK='BOTH';
      NO_IO_CHECK='BOTH';
      ALLOW_CONNECT='TRUE';
      PIN_GROUP='1';
    'B':
      PIN_NUMBER='(2)';
      PINUSE='UNSPEC';
      NO_LOAD_CHECK='BOTH';
      NO_IO_CHECK='BOTH';
      ALLOW_CONNECT='TRUE';
      PIN_GROUP='1';
  end_pin;
  body
      PART_NAME='Q_CAP';
      PHYS_DES_PREFIX='C';
      STANDARD='End of Design';
      LIFECYCLE='Comp-Approve';
      ASS_PART='';
      PART_NUMBER='CH11006JB18';
      JEDEC_TYPE='C0402';
      ALT_SYMBOLS='(C0402-0201)';
      VALUE='100PF';
      RATED_VOLTAGE='50V';
      TOL='5%';
      CLASS='DISCRETE';
      DESCRIPTION='CAP CHIP 100P 50V(+-5%.X7R.0402)';
      COMPONENT_TYPE='CHIP0402';
      LEAD_LENGTH='';
      LPID='';
      DATE='20100929';
      PARENT_PART_TYPE='Q_CAP';
      PARENT_PPT='Q_CAP';
      PARENT_PPT_PART='Q_CAP_0402-100PF,50V,5%,X7R,CH11006JB18';
  end_body;
end_primitive;
primitive 'Q_CAP_0402-10PF,50V,1%,NPO,TMP_QCH0106F0B00';
  pin
    'A':
      PIN_NUMBER='(1)';
      PINUSE='UNSPEC';
      NO_LOAD_CHECK='BOTH';
      NO_IO_CHECK='BOTH';
      ALLOW_CONNECT='TRUE';
      PIN_GROUP='1';
    'B':
      PIN_NUMBER='(2)';
      PINUSE='UNSPEC';
      NO_LOAD_CHECK='BOTH';
      NO_IO_CHECK='BOTH';
      ALLOW_CONNECT='TRUE';
      PIN_GROUP='1';
  end_pin;
  body
      PART_NAME='Q_CAP';
      PHYS_DES_PREFIX='C';
      STANDARD='';
      LIFECYCLE='';
      ASS_PART='';
      PART_NUMBER='CH0106F0B00';
      JEDEC_TYPE='C0402';
      ALT_SYMBOLS='(C0402-0201)';
      VALUE='10PF';
      RATED_VOLTAGE='50V';
      TOL='1%';
      CLASS='DISCRETE';
      DESCRIPTION='CHIP0402';
      COMPONENT_TYPE='CHIP0402';
      LEAD_LENGTH='';
      LPID='';
      DATE='';
      PARENT_PART_TYPE='Q_CAP';
      PARENT_PPT='Q_CAP';
      PARENT_PPT_PART='Q_CAP_0402-10PF,50V,1%,NPO,TMP_QCH0106F0B00';
  end_body;
end_primitive;
primitive 'Q_CAP_0402-10PF,50V,5%,EMPTY,CH01006JB08';
  pin
    'A':
      PIN_NUMBER='(1)';
      PINUSE='UNSPEC';
      NO_LOAD_CHECK='BOTH';
      NO_IO_CHECK='BOTH';
      ALLOW_CONNECT='TRUE';
      PIN_GROUP='1';
    'B':
      PIN_NUMBER='(2)';
      PINUSE='UNSPEC';
      NO_LOAD_CHECK='BOTH';
      NO_IO_CHECK='BOTH';
      ALLOW_CONNECT='TRUE';
      PIN_GROUP='1';
  end_pin;
  body
      PART_NAME='Q_CAP';
      PHYS_DES_PREFIX='C';
      STANDARD='';
      LIFECYCLE='';
      ASS_PART='';
      PART_NUMBER='CH01006JB08';
      JEDEC_TYPE='C0402';
      ALT_SYMBOLS='(C0402-0201)';
      VALUE='NA';
      RATED_VOLTAGE='50V';
      TOL='5%';
      CLASS='IO';
      DESCRIPTION='CAP CHIP 10P 50V(+-5%,C0G,0402)';
      COMPONENT_TYPE='CHIP0402';
      LEAD_LENGTH='';
      LPID='';
      DATE='20101013';
      PARENT_PART_TYPE='Q_CAP';
      PARENT_PPT='Q_CAP';
      PARENT_PPT_PART='Q_CAP_0402-10PF,50V,5%,EMPTY,CH01006JB08';
  end_body;
end_primitive;
primitive 'Q_CAP_0402-150PF,50V,5%,NPO,TMP_QCH11506JB08';
  pin
    'A':
      PIN_NUMBER='(1)';
      PINUSE='UNSPEC';
      NO_LOAD_CHECK='BOTH';
      NO_IO_CHECK='BOTH';
      ALLOW_CONNECT='TRUE';
      PIN_GROUP='1';
    'B':
      PIN_NUMBER='(2)';
      PINUSE='UNSPEC';
      NO_LOAD_CHECK='BOTH';
      NO_IO_CHECK='BOTH';
      ALLOW_CONNECT='TRUE';
      PIN_GROUP='1';
  end_pin;
  body
      PART_NAME='Q_CAP';
      PHYS_DES_PREFIX='C';
      STANDARD='';
      LIFECYCLE='';
      ASS_PART='';
      PART_NUMBER='CH11506JB08';
      JEDEC_TYPE='C0402';
      ALT_SYMBOLS='(C0402-0201)';
      VALUE='150PF';
      RATED_VOLTAGE='50V';
      TOL='5%';
      CLASS='DISCRETE';
      DESCRIPTION='CHIP0402';
      COMPONENT_TYPE='CHIP0402';
      LEAD_LENGTH='';
      LPID='';
      DATE='';
      PARENT_PART_TYPE='Q_CAP';
      PARENT_PPT='Q_CAP';
      PARENT_PPT_PART='Q_CAP_0402-150PF,50V,5%,NPO,TMP_QCH11506JB08';
  end_body;
end_primitive;
primitive 'Q_CAP_0402-15PF,50V,5%,C0G,CH01506JB06';
  pin
    'A':
      PIN_NUMBER='(1)';
      PINUSE='UNSPEC';
      NO_LOAD_CHECK='BOTH';
      NO_IO_CHECK='BOTH';
      ALLOW_CONNECT='TRUE';
      PIN_GROUP='1';
    'B':
      PIN_NUMBER='(2)';
      PINUSE='UNSPEC';
      NO_LOAD_CHECK='BOTH';
      NO_IO_CHECK='BOTH';
      ALLOW_CONNECT='TRUE';
      PIN_GROUP='1';
  end_pin;
  body
      PART_NAME='Q_CAP';
      PHYS_DES_PREFIX='C';
      STANDARD='';
      LIFECYCLE='';
      ASS_PART='';
      PART_NUMBER='CH01506JB06';
      JEDEC_TYPE='C0402';
      ALT_SYMBOLS='(C0402-0201)';
      VALUE='15PF';
      RATED_VOLTAGE='50V';
      TOL='5%';
      CLASS='DISCRETE';
      DESCRIPTION='CAP CHIP 15P 50V(+-5% C0G 0402)';
      COMPONENT_TYPE='CHIP0402';
      LEAD_LENGTH='';
      LPID='';
      DATE='20110207';
      PARENT_PART_TYPE='Q_CAP';
      PARENT_PPT='Q_CAP';
      PARENT_PPT_PART='Q_CAP_0402-15PF,50V,5%,C0G,CH01506JB06';
  end_body;
end_primitive;
primitive 'Q_CAP_0402-1NF,50V,10%,EMPTY,CH21006KB16';
  pin
    'A':
      PIN_NUMBER='(1)';
      PINUSE='UNSPEC';
      NO_LOAD_CHECK='BOTH';
      NO_IO_CHECK='BOTH';
      ALLOW_CONNECT='TRUE';
      PIN_GROUP='1';
    'B':
      PIN_NUMBER='(2)';
      PINUSE='UNSPEC';
      NO_LOAD_CHECK='BOTH';
      NO_IO_CHECK='BOTH';
      ALLOW_CONNECT='TRUE';
      PIN_GROUP='1';
  end_pin;
  body
      PART_NAME='Q_CAP';
      PHYS_DES_PREFIX='C';
      STANDARD='';
      LIFECYCLE='';
      ASS_PART='';
      PART_NUMBER='CH21006KB16';
      JEDEC_TYPE='C0402';
      ALT_SYMBOLS='(C0402-0201)';
      VALUE='NA';
      RATED_VOLTAGE='50V';
      TOL='10%';
      CLASS='IO';
      DESCRIPTION='CAP CHIP 1N 50V(+-10%,X7R,0402)EP';
      COMPONENT_TYPE='CHIP0402';
      LEAD_LENGTH='';
      LPID='';
      DATE='20100811';
      PARENT_PART_TYPE='Q_CAP';
      PARENT_PPT='Q_CAP';
      PARENT_PPT_PART='Q_CAP_0402-1NF,50V,10%,EMPTY,CH21006KB16';
  end_body;
end_primitive;
primitive 'Q_CAP_0402-1UF,6.3V,10%,X7R,CH5101K1B01';
  pin
    'A':
      PIN_NUMBER='(1)';
      PINUSE='UNSPEC';
      NO_LOAD_CHECK='BOTH';
      NO_IO_CHECK='BOTH';
      ALLOW_CONNECT='TRUE';
      PIN_GROUP='1';
    'B':
      PIN_NUMBER='(2)';
      PINUSE='UNSPEC';
      NO_LOAD_CHECK='BOTH';
      NO_IO_CHECK='BOTH';
      ALLOW_CONNECT='TRUE';
      PIN_GROUP='1';
  end_pin;
  body
      PART_NAME='Q_CAP';
      PHYS_DES_PREFIX='C';
      STANDARD='';
      LIFECYCLE='';
      ASS_PART='';
      PART_NUMBER='CH5101K1B01';
      JEDEC_TYPE='C0402';
      ALT_SYMBOLS='(C0402_OCTAGONXA,C0402-0201)';
      VALUE='1UF';
      RATED_VOLTAGE='6.3V';
      TOL='10%';
      CLASS='DISCRETE';
      DESCRIPTION='CAP CHIP 1U,6.3V(+-10%,X7R,0402)';
      COMPONENT_TYPE='CHIP0402';
      LEAD_LENGTH='';
      LPID='';
      DATE='20150410';
      PARENT_PART_TYPE='Q_CAP';
      PARENT_PPT='Q_CAP';
      PARENT_PPT_PART='Q_CAP_0402-1UF,6.3V,10%,X7R,CH5101K1B01';
  end_body;
end_primitive;
primitive 'Q_CAP_0402-220PF,50V,10%,EMPTY,TMP_QCH12206KB14';
  pin
    'A':
      PIN_NUMBER='(1)';
      PINUSE='UNSPEC';
      NO_LOAD_CHECK='BOTH';
      NO_IO_CHECK='BOTH';
      ALLOW_CONNECT='TRUE';
      PIN_GROUP='1';
    'B':
      PIN_NUMBER='(2)';
      PINUSE='UNSPEC';
      NO_LOAD_CHECK='BOTH';
      NO_IO_CHECK='BOTH';
      ALLOW_CONNECT='TRUE';
      PIN_GROUP='1';
  end_pin;
  body
      PART_NAME='Q_CAP';
      PHYS_DES_PREFIX='C';
      STANDARD='';
      LIFECYCLE='';
      ASS_PART='';
      PART_NUMBER='CH12206KB14';
      JEDEC_TYPE='C0402';
      ALT_SYMBOLS='(C0402-0201)';
      VALUE='NA';
      RATED_VOLTAGE='50V';
      TOL='10%';
      CLASS='IO';
      DESCRIPTION='CAP CHIP 220P 50V(+-10%,X7R,0402)';
      COMPONENT_TYPE='CHIP0402';
      LEAD_LENGTH='';
      LPID='';
      DATE='';
      PARENT_PART_TYPE='Q_CAP';
      PARENT_PPT='Q_CAP';
      PARENT_PPT_PART='Q_CAP_0402-220PF,50V,10%,EMPTY,TMP_QCH12206KB14';
  end_body;
end_primitive;
primitive 'Q_CAP_0402-220PF,50V,10%,X7R,TMP_QCH12206KB14';
  pin
    'A':
      PIN_NUMBER='(1)';
      PINUSE='UNSPEC';
      NO_LOAD_CHECK='BOTH';
      NO_IO_CHECK='BOTH';
      ALLOW_CONNECT='TRUE';
      PIN_GROUP='1';
    'B':
      PIN_NUMBER='(2)';
      PINUSE='UNSPEC';
      NO_LOAD_CHECK='BOTH';
      NO_IO_CHECK='BOTH';
      ALLOW_CONNECT='TRUE';
      PIN_GROUP='1';
  end_pin;
  body
      PART_NAME='Q_CAP';
      PHYS_DES_PREFIX='C';
      STANDARD='';
      LIFECYCLE='';
      ASS_PART='';
      PART_NUMBER='CH12206KB14';
      JEDEC_TYPE='C0402';
      ALT_SYMBOLS='(C0402-0201)';
      VALUE='220PF';
      RATED_VOLTAGE='50V';
      TOL='10%';
      CLASS='DISCRETE';
      DESCRIPTION='CAP CHIP 220P 50V(+-10%,X7R,0402)';
      COMPONENT_TYPE='CHIP0402';
      LEAD_LENGTH='';
      LPID='';
      DATE='';
      PARENT_PART_TYPE='Q_CAP';
      PARENT_PPT='Q_CAP';
      PARENT_PPT_PART='Q_CAP_0402-220PF,50V,10%,X7R,TMP_QCH12206KB14';
  end_body;
end_primitive;
primitive 'Q_CAP_0402-27PF,50V,5%,NPO,CH02706JB06';
  pin
    'A':
      PIN_NUMBER='(1)';
      PINUSE='UNSPEC';
      NO_LOAD_CHECK='BOTH';
      NO_IO_CHECK='BOTH';
      ALLOW_CONNECT='TRUE';
      PIN_GROUP='1';
    'B':
      PIN_NUMBER='(2)';
      PINUSE='UNSPEC';
      NO_LOAD_CHECK='BOTH';
      NO_IO_CHECK='BOTH';
      ALLOW_CONNECT='TRUE';
      PIN_GROUP='1';
  end_pin;
  body
      PART_NAME='Q_CAP';
      PHYS_DES_PREFIX='C';
      STANDARD='';
      LIFECYCLE='';
      ASS_PART='';
      PART_NUMBER='CH02706JB06';
      JEDEC_TYPE='C0402';
      ALT_SYMBOLS='(C0402-0201)';
      VALUE='27PF';
      RATED_VOLTAGE='50V';
      TOL='5%';
      CLASS='DISCRETE';
      DESCRIPTION='CAP CHIP 27P 50V(+-5% NPO 0402)';
      COMPONENT_TYPE='CHIP0402';
      LEAD_LENGTH='';
      LPID='';
      DATE='20100811';
      PARENT_PART_TYPE='Q_CAP';
      PARENT_PPT='Q_CAP';
      PARENT_PPT_PART='Q_CAP_0402-27PF,50V,5%,NPO,CH02706JB06';
  end_body;
end_primitive;
primitive 'Q_CAP_0402-3300PF,50V,10%,X7R,TMP_QCH2336K1B12';
  pin
    'A':
      PIN_NUMBER='(1)';
      PINUSE='UNSPEC';
      NO_LOAD_CHECK='BOTH';
      NO_IO_CHECK='BOTH';
      ALLOW_CONNECT='TRUE';
      PIN_GROUP='1';
    'B':
      PIN_NUMBER='(2)';
      PINUSE='UNSPEC';
      NO_LOAD_CHECK='BOTH';
      NO_IO_CHECK='BOTH';
      ALLOW_CONNECT='TRUE';
      PIN_GROUP='1';
  end_pin;
  body
      PART_NAME='Q_CAP';
      PHYS_DES_PREFIX='C';
      STANDARD='';
      LIFECYCLE='';
      ASS_PART='';
      PART_NUMBER='CH2336K1B12';
      JEDEC_TYPE='C0402';
      ALT_SYMBOLS='(C0402-0201)';
      VALUE='3300PF';
      RATED_VOLTAGE='50V';
      TOL='10%';
      CLASS='DISCRETE';
      DESCRIPTION='CHIP0402';
      COMPONENT_TYPE='CHIP0402';
      LEAD_LENGTH='';
      LPID='';
      DATE='';
      PARENT_PART_TYPE='Q_CAP';
      PARENT_PPT='Q_CAP';
      PARENT_PPT_PART='Q_CAP_0402-3300PF,50V,10%,X7R,TMP_QCH2336K1B12';
  end_body;
end_primitive;
primitive 'Q_CAP_0402-330PF,50V,10%,X7R,CH1336K1B02';
  pin
    'A':
      PIN_NUMBER='(1)';
      PINUSE='UNSPEC';
      NO_LOAD_CHECK='BOTH';
      NO_IO_CHECK='BOTH';
      ALLOW_CONNECT='TRUE';
      PIN_GROUP='1';
    'B':
      PIN_NUMBER='(2)';
      PINUSE='UNSPEC';
      NO_LOAD_CHECK='BOTH';
      NO_IO_CHECK='BOTH';
      ALLOW_CONNECT='TRUE';
      PIN_GROUP='1';
  end_pin;
  body
      PART_NAME='Q_CAP';
      PHYS_DES_PREFIX='C';
      STANDARD='';
      LIFECYCLE='';
      ASS_PART='';
      PART_NUMBER='CH1336K1B02';
      JEDEC_TYPE='C0402';
      ALT_SYMBOLS='(C0402-0201)';
      VALUE='330PF';
      RATED_VOLTAGE='50V';
      TOL='10%';
      CLASS='DISCRETE';
      DESCRIPTION='CAP CHIP 330P 50V(+-10%,X7R,0402)';
      COMPONENT_TYPE='CHIP0402';
      LEAD_LENGTH='';
      LPID='';
      DATE='20100623';
      PARENT_PART_TYPE='Q_CAP';
      PARENT_PPT='Q_CAP';
      PARENT_PPT_PART='Q_CAP_0402-330PF,50V,10%,X7R,CH1336K1B02';
  end_body;
end_primitive;
primitive 'Q_CAP_0402-33PF,50V,5%,NPO,TMP_QCH03306JB04';
  pin
    'A':
      PIN_NUMBER='(1)';
      PINUSE='UNSPEC';
      NO_LOAD_CHECK='BOTH';
      NO_IO_CHECK='BOTH';
      ALLOW_CONNECT='TRUE';
      PIN_GROUP='1';
    'B':
      PIN_NUMBER='(2)';
      PINUSE='UNSPEC';
      NO_LOAD_CHECK='BOTH';
      NO_IO_CHECK='BOTH';
      ALLOW_CONNECT='TRUE';
      PIN_GROUP='1';
  end_pin;
  body
      PART_NAME='Q_CAP';
      PHYS_DES_PREFIX='C';
      STANDARD='';
      LIFECYCLE='';
      ASS_PART='';
      PART_NUMBER='CH03306JB04';
      JEDEC_TYPE='C0402';
      ALT_SYMBOLS='(C0402-0201)';
      VALUE='33PF';
      RATED_VOLTAGE='50V';
      TOL='15%';
      CLASS='DISCRETE';
      DESCRIPTION='CHIP0402';
      COMPONENT_TYPE='CHIP0402';
      LEAD_LENGTH='';
      LPID='';
      DATE='';
      PARENT_PART_TYPE='Q_CAP';
      PARENT_PPT='Q_CAP';
      PARENT_PPT_PART='Q_CAP_0402-33PF,50V,5%,NPO,TMP_QCH03306JB04';
  end_body;
end_primitive;
primitive 'Q_CAP_0402-39PF,50V,5%,NPO,CH03906JB06';
  pin
    'A':
      PIN_NUMBER='(1)';
      PINUSE='UNSPEC';
      NO_LOAD_CHECK='BOTH';
      NO_IO_CHECK='BOTH';
      ALLOW_CONNECT='TRUE';
      PIN_GROUP='1';
    'B':
      PIN_NUMBER='(2)';
      PINUSE='UNSPEC';
      NO_LOAD_CHECK='BOTH';
      NO_IO_CHECK='BOTH';
      ALLOW_CONNECT='TRUE';
      PIN_GROUP='1';
  end_pin;
  body
      PART_NAME='Q_CAP';
      PHYS_DES_PREFIX='C';
      STANDARD='';
      LIFECYCLE='';
      ASS_PART='';
      PART_NUMBER='CH03906JB06';
      JEDEC_TYPE='C0402';
      ALT_SYMBOLS='(C0402-0201)';
      VALUE='39PF';
      RATED_VOLTAGE='50V';
      TOL='5%';
      CLASS='DISCRETE';
      DESCRIPTION='CAP CHIP 39P 50V(+-5%.NPO.0402)';
      COMPONENT_TYPE='CHIP0402';
      LEAD_LENGTH='';
      LPID='';
      DATE='20110628';
      PARENT_PART_TYPE='Q_CAP';
      PARENT_PPT='Q_CAP';
      PARENT_PPT_PART='Q_CAP_0402-39PF,50V,5%,NPO,CH03906JB06';
  end_body;
end_primitive;
primitive 'Q_CAP_0402-4.7UF,6.3V,20%,X6S,CH5471MEB01';
  pin
    'A':
      PIN_NUMBER='(1)';
      PINUSE='UNSPEC';
      NO_LOAD_CHECK='BOTH';
      NO_IO_CHECK='BOTH';
      ALLOW_CONNECT='TRUE';
      PIN_GROUP='1';
    'B':
      PIN_NUMBER='(2)';
      PINUSE='UNSPEC';
      NO_LOAD_CHECK='BOTH';
      NO_IO_CHECK='BOTH';
      ALLOW_CONNECT='TRUE';
      PIN_GROUP='1';
  end_pin;
  body
      PART_NAME='Q_CAP';
      PHYS_DES_PREFIX='C';
      STANDARD='';
      LIFECYCLE='';
      ASS_PART='';
      PART_NUMBER='CH5471MEB01';
      JEDEC_TYPE='C0402';
      ALT_SYMBOLS='(C0402_OCTAGON,C0402_OCTAGONXA,C0402-0201)';
      VALUE='4.7UF';
      RATED_VOLTAGE='6.3V';
      TOL='20%';
      CLASS='DISCRETE';
      DESCRIPTION='CAP CHIP 4.7UF 6.3V(+-20%,X6S,0402)';
      COMPONENT_TYPE='CHIP0402';
      LEAD_LENGTH='';
      LPID='';
      DATE='20151211';
      PARENT_PART_TYPE='Q_CAP';
      PARENT_PPT='Q_CAP';
      PARENT_PPT_PART='Q_CAP_0402-4.7UF,6.3V,20%,X6S,CH5471MEB01';
  end_body;
end_primitive;
primitive 'Q_CAP_0402-470PF,50V,10%,X7R,TMP_QCH14706KB18';
  pin
    'A':
      PIN_NUMBER='(1)';
      PINUSE='UNSPEC';
      NO_LOAD_CHECK='BOTH';
      NO_IO_CHECK='BOTH';
      ALLOW_CONNECT='TRUE';
      PIN_GROUP='1';
    'B':
      PIN_NUMBER='(2)';
      PINUSE='UNSPEC';
      NO_LOAD_CHECK='BOTH';
      NO_IO_CHECK='BOTH';
      ALLOW_CONNECT='TRUE';
      PIN_GROUP='1';
  end_pin;
  body
      PART_NAME='Q_CAP';
      PHYS_DES_PREFIX='C';
      STANDARD='';
      LIFECYCLE='';
      ASS_PART='';
      PART_NUMBER='CH14706KB18';
      JEDEC_TYPE='C0402';
      ALT_SYMBOLS='(C0402-0201)';
      VALUE='470PF';
      RATED_VOLTAGE='50V';
      TOL='10%';
      CLASS='DISCRETE';
      DESCRIPTION='CHIP0402';
      COMPONENT_TYPE='CHIP0402';
      LEAD_LENGTH='';
      LPID='';
      DATE='';
      PARENT_PART_TYPE='Q_CAP';
      PARENT_PPT='Q_CAP';
      PARENT_PPT_PART='Q_CAP_0402-470PF,50V,10%,X7R,TMP_QCH14706KB18';
  end_body;
end_primitive;
primitive 'Q_CAP_0402-47PF,50V,5%,NPO,TMP_QCH04706JB01';
  pin
    'A':
      PIN_NUMBER='(1)';
      PINUSE='UNSPEC';
      NO_LOAD_CHECK='BOTH';
      NO_IO_CHECK='BOTH';
      ALLOW_CONNECT='TRUE';
      PIN_GROUP='1';
    'B':
      PIN_NUMBER='(2)';
      PINUSE='UNSPEC';
      NO_LOAD_CHECK='BOTH';
      NO_IO_CHECK='BOTH';
      ALLOW_CONNECT='TRUE';
      PIN_GROUP='1';
  end_pin;
  body
      PART_NAME='Q_CAP';
      PHYS_DES_PREFIX='C';
      STANDARD='';
      LIFECYCLE='';
      ASS_PART='';
      PART_NUMBER='CH04706JB01';
      JEDEC_TYPE='C0402';
      ALT_SYMBOLS='(C0402-0201)';
      VALUE='47PF';
      RATED_VOLTAGE='50V';
      TOL='5%';
      CLASS='DISCRETE';
      DESCRIPTION='CHIP0402';
      COMPONENT_TYPE='CHIP0402';
      LEAD_LENGTH='';
      LPID='';
      DATE='';
      PARENT_PART_TYPE='Q_CAP';
      PARENT_PPT='Q_CAP';
      PARENT_PPT_PART='Q_CAP_0402-47PF,50V,5%,NPO,TMP_QCH04706JB01';
  end_body;
end_primitive;
primitive 'Q_CAP_0603-1000PF,50V,10%,X7R,TMP_QCH21006K917';
  pin
    'A':
      PIN_NUMBER='(1)';
      PINUSE='UNSPEC';
      NO_LOAD_CHECK='BOTH';
      NO_IO_CHECK='BOTH';
      ALLOW_CONNECT='TRUE';
      PIN_GROUP='1';
    'B':
      PIN_NUMBER='(2)';
      PINUSE='UNSPEC';
      NO_LOAD_CHECK='BOTH';
      NO_IO_CHECK='BOTH';
      ALLOW_CONNECT='TRUE';
      PIN_GROUP='1';
  end_pin;
  body
      PART_NAME='Q_CAP';
      PHYS_DES_PREFIX='C';
      STANDARD='End of Design';
      LIFECYCLE='Comp-Approve';
      ASS_PART='';
      PART_NUMBER='CH21006K917';
      JEDEC_TYPE='C0603';
      ALT_SYMBOLS='(SMC0603AW)';
      VALUE='1000PF';
      RATED_VOLTAGE='50V';
      TOL='10%';
      CLASS='DISCRETE';
      DESCRIPTION='CAP CHIP 1000P 50V(+-10%,X7R,0603)';
      COMPONENT_TYPE='CHIP0603';
      LEAD_LENGTH='';
      LPID='';
      DATE='20100528';
      PARENT_PART_TYPE='Q_CAP';
      PARENT_PPT='Q_CAP';
      PARENT_PPT_PART='Q_CAP_0603-1000PF,50V,10%,X7R,TMP_QCH21006K917';
  end_body;
end_primitive;
primitive 'Q_CAP_0603-1UF,16V,10%,X7R,TMP_QCH5103K1900';
  pin
    'A':
      PIN_NUMBER='(1)';
      PINUSE='UNSPEC';
      NO_LOAD_CHECK='BOTH';
      NO_IO_CHECK='BOTH';
      ALLOW_CONNECT='TRUE';
      PIN_GROUP='1';
    'B':
      PIN_NUMBER='(2)';
      PINUSE='UNSPEC';
      NO_LOAD_CHECK='BOTH';
      NO_IO_CHECK='BOTH';
      ALLOW_CONNECT='TRUE';
      PIN_GROUP='1';
  end_pin;
  body
      PART_NAME='Q_CAP';
      PHYS_DES_PREFIX='C';
      STANDARD='End of Design';
      LIFECYCLE='Comp-Approve';
      ASS_PART='';
      PART_NUMBER='CH5103K1900';
      JEDEC_TYPE='C0603';
      ALT_SYMBOLS='(SMC0603AW)';
      VALUE='1UF';
      RATED_VOLTAGE='16V';
      TOL='10%';
      CLASS='DISCRETE';
      DESCRIPTION='CHIP0603';
      COMPONENT_TYPE='CHIP0603';
      LEAD_LENGTH='';
      LPID='';
      DATE='';
      PARENT_PART_TYPE='Q_CAP';
      PARENT_PPT='Q_CAP';
      PARENT_PPT_PART='Q_CAP_0603-1UF,16V,10%,X7R,TMP_QCH5103K1900';
  end_body;
end_primitive;
primitive 'Q_CAP_C0201-0.1UF,10V,10%,X7S,CH4102K6E00';
  pin
    'A':
      PIN_NUMBER='(1)';
      PINUSE='UNSPEC';
      NO_LOAD_CHECK='BOTH';
      NO_IO_CHECK='BOTH';
      ALLOW_CONNECT='TRUE';
      PIN_GROUP='1';
    'B':
      PIN_NUMBER='(2)';
      PINUSE='UNSPEC';
      NO_LOAD_CHECK='BOTH';
      NO_IO_CHECK='BOTH';
      ALLOW_CONNECT='TRUE';
      PIN_GROUP='1';
  end_pin;
  body
      PART_NAME='Q_CAP';
      PHYS_DES_PREFIX='C';
      STANDARD='End of Design';
      LIFECYCLE='Comp-Approve';
      ASS_PART='';
      PART_NUMBER='CH4102K6E00';
      JEDEC_TYPE='C0201';
      ALT_SYMBOLS='(SMC0201AW)';
      VALUE='0.1UF';
      RATED_VOLTAGE='10V';
      TOL='10%';
      CLASS='DISCRETE';
      DESCRIPTION='CAP CHIP 0.1U 10V(+-10%,X7S,0201)';
      COMPONENT_TYPE='CHIP0201';
      LEAD_LENGTH='';
      LPID='';
      DATE='20221017';
      PARENT_PART_TYPE='Q_CAP';
      PARENT_PPT='Q_CAP';
      PARENT_PPT_PART='Q_CAP_C0201-0.1UF,10V,10%,X7S,CH4102K6E00';
  end_body;
end_primitive;
primitive 'Q_CAP_C0402-0.001UF,50V,10%,EMPTY,CH30106KB19';
  pin
    'A':
      PIN_NUMBER='(1)';
      PINUSE='UNSPEC';
      NO_LOAD_CHECK='BOTH';
      NO_IO_CHECK='BOTH';
      ALLOW_CONNECT='TRUE';
      PIN_GROUP='1';
    'B':
      PIN_NUMBER='(2)';
      PINUSE='UNSPEC';
      NO_LOAD_CHECK='BOTH';
      NO_IO_CHECK='BOTH';
      ALLOW_CONNECT='TRUE';
      PIN_GROUP='1';
  end_pin;
  body
      PART_NAME='Q_CAP';
      PHYS_DES_PREFIX='C';
      STANDARD='End of Design';
      LIFECYCLE='Comp-Release Qty';
      ASS_PART='';
      PART_NUMBER='CH30106KB19';
      JEDEC_TYPE='C0402';
      ALT_SYMBOLS='(C0402-0201)';
      VALUE='NA';
      RATED_VOLTAGE='50V';
      TOL='10%';
      CLASS='IO';
      DESCRIPTION='CAP CHIP 0.001U 50V(10%,X7R,0402)';
      COMPONENT_TYPE='CHIP0402';
      LEAD_LENGTH='';
      LPID='';
      DATE='20200218';
      PARENT_PART_TYPE='Q_CAP';
      PARENT_PPT='Q_CAP';
      PARENT_PPT_PART='Q_CAP_C0402-0.001UF,50V,10%,EMPTY,CH30106KB19';
  end_body;
end_primitive;
primitive 'Q_CAP_C0402-0.001UF,50V,10%,X7R,CH30106KB19';
  pin
    'A':
      PIN_NUMBER='(1)';
      PINUSE='UNSPEC';
      NO_LOAD_CHECK='BOTH';
      NO_IO_CHECK='BOTH';
      ALLOW_CONNECT='TRUE';
      PIN_GROUP='1';
    'B':
      PIN_NUMBER='(2)';
      PINUSE='UNSPEC';
      NO_LOAD_CHECK='BOTH';
      NO_IO_CHECK='BOTH';
      ALLOW_CONNECT='TRUE';
      PIN_GROUP='1';
  end_pin;
  body
      PART_NAME='Q_CAP';
      PHYS_DES_PREFIX='C';
      STANDARD='End of Design';
      LIFECYCLE='Comp-Release Qty';
      ASS_PART='';
      PART_NUMBER='CH30106KB19';
      JEDEC_TYPE='C0402';
      ALT_SYMBOLS='(C0402-0201)';
      VALUE='0.001UF';
      RATED_VOLTAGE='50V';
      TOL='10%';
      CLASS='DISCRETE';
      DESCRIPTION='CAP CHIP 0.001U 50V(10%,X7R,0402)';
      COMPONENT_TYPE='CHIP0402';
      LEAD_LENGTH='';
      LPID='';
      DATE='20200218';
      PARENT_PART_TYPE='Q_CAP';
      PARENT_PPT='Q_CAP';
      PARENT_PPT_PART='Q_CAP_C0402-0.001UF,50V,10%,X7R,CH30106KB19';
  end_body;
end_primitive;
primitive 'Q_CAP_C0402-0.01UF,25V,10%,EMPTY,CH3104K1B11';
  pin
    'A':
      PIN_NUMBER='(1)';
      PINUSE='UNSPEC';
      NO_LOAD_CHECK='BOTH';
      NO_IO_CHECK='BOTH';
      ALLOW_CONNECT='TRUE';
      PIN_GROUP='1';
    'B':
      PIN_NUMBER='(2)';
      PINUSE='UNSPEC';
      NO_LOAD_CHECK='BOTH';
      NO_IO_CHECK='BOTH';
      ALLOW_CONNECT='TRUE';
      PIN_GROUP='1';
  end_pin;
  body
      PART_NAME='Q_CAP';
      PHYS_DES_PREFIX='C';
      STANDARD='';
      LIFECYCLE='';
      ASS_PART='';
      PART_NUMBER='CH3104K1B11';
      JEDEC_TYPE='C0402';
      ALT_SYMBOLS='(C0402-0201)';
      VALUE='NA';
      RATED_VOLTAGE='25V';
      TOL='10%';
      CLASS='IO';
      DESCRIPTION='CAP CHIP 0.01U 25V(+-10%,X7R,0402)MUR';
      COMPONENT_TYPE='CHIP0402';
      LEAD_LENGTH='';
      LPID='';
      DATE='20150614';
      PARENT_PART_TYPE='Q_CAP';
      PARENT_PPT='Q_CAP';
      PARENT_PPT_PART='Q_CAP_C0402-0.01UF,25V,10%,EMPTY,CH3104K1B11';
  end_body;
end_primitive;
primitive 'Q_CAP_C0402-0.01UF,50V,10%,EMPTY,CH31006KB18';
  pin
    'A':
      PIN_NUMBER='(1)';
      PINUSE='UNSPEC';
      NO_LOAD_CHECK='BOTH';
      NO_IO_CHECK='BOTH';
      ALLOW_CONNECT='TRUE';
      PIN_GROUP='1';
    'B':
      PIN_NUMBER='(2)';
      PINUSE='UNSPEC';
      NO_LOAD_CHECK='BOTH';
      NO_IO_CHECK='BOTH';
      ALLOW_CONNECT='TRUE';
      PIN_GROUP='1';
  end_pin;
  body
      PART_NAME='Q_CAP';
      PHYS_DES_PREFIX='C';
      STANDARD='';
      LIFECYCLE='';
      ASS_PART='';
      PART_NUMBER='CH31006KB18';
      JEDEC_TYPE='C0402';
      ALT_SYMBOLS='(C0402_OCTAGONXA,C0402-0201)';
      VALUE='NA';
      RATED_VOLTAGE='50V';
      TOL='10%';
      CLASS='IO';
      DESCRIPTION='CAP CHIP 0.01U 50V(+-10%,X7R,0402)';
      COMPONENT_TYPE='CHIP0402';
      LEAD_LENGTH='';
      LPID='';
      DATE='20120326';
      PARENT_PART_TYPE='Q_CAP';
      PARENT_PPT='Q_CAP';
      PARENT_PPT_PART='Q_CAP_C0402-0.01UF,50V,10%,EMPTY,CH31006KB18';
  end_body;
end_primitive;
primitive 'Q_CAP_C0402-0.01UF,50V,10%,X7R,CH31006KB18';
  pin
    'A':
      PIN_NUMBER='(1)';
      PINUSE='UNSPEC';
      NO_LOAD_CHECK='BOTH';
      NO_IO_CHECK='BOTH';
      ALLOW_CONNECT='TRUE';
      PIN_GROUP='1';
    'B':
      PIN_NUMBER='(2)';
      PINUSE='UNSPEC';
      NO_LOAD_CHECK='BOTH';
      NO_IO_CHECK='BOTH';
      ALLOW_CONNECT='TRUE';
      PIN_GROUP='1';
  end_pin;
  body
      PART_NAME='Q_CAP';
      PHYS_DES_PREFIX='C';
      STANDARD='';
      LIFECYCLE='';
      ASS_PART='';
      PART_NUMBER='CH31006KB18';
      JEDEC_TYPE='C0402';
      ALT_SYMBOLS='(C0402_OCTAGONXA,C0402-0201)';
      VALUE='0.01UF';
      RATED_VOLTAGE='50V';
      TOL='10%';
      CLASS='DISCRETE';
      DESCRIPTION='CAP CHIP 0.01U 50V(+-10%,X7R,0402)';
      COMPONENT_TYPE='CHIP0402';
      LEAD_LENGTH='';
      LPID='';
      DATE='20120326';
      PARENT_PART_TYPE='Q_CAP';
      PARENT_PPT='Q_CAP';
      PARENT_PPT_PART='Q_CAP_C0402-0.01UF,50V,10%,X7R,CH31006KB18';
  end_body;
end_primitive;
primitive 'Q_CAP_C0402-0.047UF,25V,10%,X7R,CH3474K1B04';
  pin
    'A':
      PIN_NUMBER='(1)';
      PINUSE='UNSPEC';
      NO_LOAD_CHECK='BOTH';
      NO_IO_CHECK='BOTH';
      ALLOW_CONNECT='TRUE';
      PIN_GROUP='1';
    'B':
      PIN_NUMBER='(2)';
      PINUSE='UNSPEC';
      NO_LOAD_CHECK='BOTH';
      NO_IO_CHECK='BOTH';
      ALLOW_CONNECT='TRUE';
      PIN_GROUP='1';
  end_pin;
  body
      PART_NAME='Q_CAP';
      PHYS_DES_PREFIX='C';
      STANDARD='';
      LIFECYCLE='';
      ASS_PART='';
      PART_NUMBER='CH3474K1B04';
      JEDEC_TYPE='C0402';
      ALT_SYMBOLS='(C0402_OCTAGONXA,C0402-0201)';
      VALUE='0.047UF';
      RATED_VOLTAGE='25V';
      TOL='10%';
      CLASS='DISCRETE';
      DESCRIPTION='CAP CHIP 0.047U 25V(+-10% X7R 0402)';
      COMPONENT_TYPE='CHIP0402';
      LEAD_LENGTH='';
      LPID='';
      DATE='20140325';
      PARENT_PART_TYPE='Q_CAP';
      PARENT_PPT='Q_CAP';
      PARENT_PPT_PART='Q_CAP_C0402-0.047UF,25V,10%,X7R,CH3474K1B04';
  end_body;
end_primitive;
primitive 'Q_CAP_C0402-0.1UF,16V,10%,X7R,CH4103K1B08';
  pin
    'A':
      PIN_NUMBER='(1)';
      PINUSE='UNSPEC';
      NO_LOAD_CHECK='BOTH';
      NO_IO_CHECK='BOTH';
      ALLOW_CONNECT='TRUE';
      PIN_GROUP='1';
    'B':
      PIN_NUMBER='(2)';
      PINUSE='UNSPEC';
      NO_LOAD_CHECK='BOTH';
      NO_IO_CHECK='BOTH';
      ALLOW_CONNECT='TRUE';
      PIN_GROUP='1';
  end_pin;
  body
      PART_NAME='Q_CAP';
      PHYS_DES_PREFIX='C';
      STANDARD='';
      LIFECYCLE='';
      ASS_PART='';
      PART_NUMBER='CH4103K1B08';
      JEDEC_TYPE='C0402';
      ALT_SYMBOLS='(C0402_OCTAGONXA,C0402_OCTAGON,C0402-0201)';
      VALUE='0.1UF';
      RATED_VOLTAGE='16V';
      TOL='10%';
      CLASS='DISCRETE';
      DESCRIPTION='CAP CHIP 0.1U 16V(10%,X7R,0402)';
      COMPONENT_TYPE='CHIP0402';
      LEAD_LENGTH='';
      LPID='';
      DATE='20150911';
      PARENT_PART_TYPE='Q_CAP';
      PARENT_PPT='Q_CAP';
      PARENT_PPT_PART='Q_CAP_C0402-0.1UF,16V,10%,X7R,CH4103K1B08';
  end_body;
end_primitive;
primitive 'Q_CAP_C0402-0.1UF,25V,10%,EMPTY,CH4104KEB00';
  pin
    'A':
      PIN_NUMBER='(1)';
      PINUSE='UNSPEC';
      NO_LOAD_CHECK='BOTH';
      NO_IO_CHECK='BOTH';
      ALLOW_CONNECT='TRUE';
      PIN_GROUP='1';
    'B':
      PIN_NUMBER='(2)';
      PINUSE='UNSPEC';
      NO_LOAD_CHECK='BOTH';
      NO_IO_CHECK='BOTH';
      ALLOW_CONNECT='TRUE';
      PIN_GROUP='1';
  end_pin;
  body
      PART_NAME='Q_CAP';
      PHYS_DES_PREFIX='C';
      STANDARD='End of Design';
      LIFECYCLE='Comp-Approve';
      ASS_PART='';
      PART_NUMBER='CH4104KEB00';
      JEDEC_TYPE='C0402';
      ALT_SYMBOLS='(C0402-0201)';
      VALUE='NA';
      RATED_VOLTAGE='25V';
      TOL='10%';
      CLASS='IO';
      DESCRIPTION='CAP CHIP 0.1U 25V(+-10%,X6S,0402)';
      COMPONENT_TYPE='CHIP0402';
      LEAD_LENGTH='';
      LPID='';
      DATE='20171221';
      PARENT_PART_TYPE='Q_CAP';
      PARENT_PPT='Q_CAP';
      PARENT_PPT_PART='Q_CAP_C0402-0.1UF,25V,10%,EMPTY,CH4104KEB00';
  end_body;
end_primitive;
primitive 'Q_CAP_C0402-0.1UF,25V,10%,X6S,CH4104KEB00';
  pin
    'A':
      PIN_NUMBER='(1)';
      PINUSE='UNSPEC';
      NO_LOAD_CHECK='BOTH';
      NO_IO_CHECK='BOTH';
      ALLOW_CONNECT='TRUE';
      PIN_GROUP='1';
    'B':
      PIN_NUMBER='(2)';
      PINUSE='UNSPEC';
      NO_LOAD_CHECK='BOTH';
      NO_IO_CHECK='BOTH';
      ALLOW_CONNECT='TRUE';
      PIN_GROUP='1';
  end_pin;
  body
      PART_NAME='Q_CAP';
      PHYS_DES_PREFIX='C';
      STANDARD='End of Design';
      LIFECYCLE='Comp-Approve';
      ASS_PART='';
      PART_NUMBER='CH4104KEB00';
      JEDEC_TYPE='C0402';
      ALT_SYMBOLS='(C0402-0201)';
      VALUE='0.1UF';
      RATED_VOLTAGE='25V';
      TOL='10%';
      CLASS='DISCRETE';
      DESCRIPTION='CAP CHIP 0.1U 25V(+-10%,X6S,0402)';
      COMPONENT_TYPE='CHIP0402';
      LEAD_LENGTH='';
      LPID='';
      DATE='20171221';
      PARENT_PART_TYPE='Q_CAP';
      PARENT_PPT='Q_CAP';
      PARENT_PPT_PART='Q_CAP_C0402-0.1UF,25V,10%,X6S,CH4104KEB00';
  end_body;
end_primitive;
primitive 'Q_CAP_C0402-0.22UF,25V,10%,X7R,CH4224K1B01';
  pin
    'A':
      PIN_NUMBER='(1)';
      PINUSE='UNSPEC';
      NO_LOAD_CHECK='BOTH';
      NO_IO_CHECK='BOTH';
      ALLOW_CONNECT='TRUE';
      PIN_GROUP='1';
    'B':
      PIN_NUMBER='(2)';
      PINUSE='UNSPEC';
      NO_LOAD_CHECK='BOTH';
      NO_IO_CHECK='BOTH';
      ALLOW_CONNECT='TRUE';
      PIN_GROUP='1';
  end_pin;
  body
      PART_NAME='Q_CAP';
      PHYS_DES_PREFIX='C';
      STANDARD='End of Design';
      LIFECYCLE='Comp-Release Qty';
      ASS_PART='';
      PART_NUMBER='CH4224K1B01';
      JEDEC_TYPE='C0402';
      ALT_SYMBOLS='(C0402_OCTAGONXA,C0402-0201)';
      VALUE='0.22UF';
      RATED_VOLTAGE='25V';
      TOL='10%';
      CLASS='DISCRETE';
      DESCRIPTION='CAP CHIP 0.22U 25V(10%,X7R,0402)';
      COMPONENT_TYPE='CHIP0402';
      LEAD_LENGTH='';
      LPID='';
      DATE='20171109';
      PARENT_PART_TYPE='Q_CAP';
      PARENT_PPT='Q_CAP';
      PARENT_PPT_PART='Q_CAP_C0402-0.22UF,25V,10%,X7R,CH4224K1B01';
  end_body;
end_primitive;
primitive 'Q_CAP_C0402-100NF,50V,10%,EMPTY,CH4106K1B01';
  pin
    'A':
      PIN_NUMBER='(1)';
      PINUSE='UNSPEC';
      NO_LOAD_CHECK='BOTH';
      NO_IO_CHECK='BOTH';
      ALLOW_CONNECT='TRUE';
      PIN_GROUP='1';
    'B':
      PIN_NUMBER='(2)';
      PINUSE='UNSPEC';
      NO_LOAD_CHECK='BOTH';
      NO_IO_CHECK='BOTH';
      ALLOW_CONNECT='TRUE';
      PIN_GROUP='1';
  end_pin;
  body
      PART_NAME='Q_CAP';
      PHYS_DES_PREFIX='C';
      STANDARD='';
      LIFECYCLE='';
      ASS_PART='';
      PART_NUMBER='CH4106K1B01';
      JEDEC_TYPE='C0402';
      ALT_SYMBOLS='(C0402_OCTAGONXA,C0402-0201)';
      VALUE='NA';
      RATED_VOLTAGE='50V';
      TOL='10%';
      CLASS='IO';
      DESCRIPTION='CAP CHIP 100NF 50V(+-10%,X7R,0402)';
      COMPONENT_TYPE='CHIP0402';
      LEAD_LENGTH='';
      LPID='';
      DATE='20171109';
      PARENT_PART_TYPE='Q_CAP';
      PARENT_PPT='Q_CAP';
      PARENT_PPT_PART='Q_CAP_C0402-100NF,50V,10%,EMPTY,CH4106K1B01';
  end_body;
end_primitive;
primitive 'Q_CAP_C0402-100NF,50V,10%,X7R,CH4106K1B01';
  pin
    'A':
      PIN_NUMBER='(1)';
      PINUSE='UNSPEC';
      NO_LOAD_CHECK='BOTH';
      NO_IO_CHECK='BOTH';
      ALLOW_CONNECT='TRUE';
      PIN_GROUP='1';
    'B':
      PIN_NUMBER='(2)';
      PINUSE='UNSPEC';
      NO_LOAD_CHECK='BOTH';
      NO_IO_CHECK='BOTH';
      ALLOW_CONNECT='TRUE';
      PIN_GROUP='1';
  end_pin;
  body
      PART_NAME='Q_CAP';
      PHYS_DES_PREFIX='C';
      STANDARD='';
      LIFECYCLE='';
      ASS_PART='';
      PART_NUMBER='CH4106K1B01';
      JEDEC_TYPE='C0402';
      ALT_SYMBOLS='(C0402_OCTAGONXA,C0402-0201)';
      VALUE='100NF';
      RATED_VOLTAGE='50V';
      TOL='10%';
      CLASS='DISCRETE';
      DESCRIPTION='CAP CHIP 100NF 50V(+-10%,X7R,0402)';
      COMPONENT_TYPE='CHIP0402';
      LEAD_LENGTH='';
      LPID='';
      DATE='20171109';
      PARENT_PART_TYPE='Q_CAP';
      PARENT_PPT='Q_CAP';
      PARENT_PPT_PART='Q_CAP_C0402-100NF,50V,10%,X7R,CH4106K1B01';
  end_body;
end_primitive;
primitive 'Q_CAP_C0402-10UF,6.3V,20%,EMPTY,CH6101MEB01';
  pin
    'A':
      PIN_NUMBER='(1)';
      PINUSE='UNSPEC';
      NO_LOAD_CHECK='BOTH';
      NO_IO_CHECK='BOTH';
      ALLOW_CONNECT='TRUE';
      PIN_GROUP='1';
    'B':
      PIN_NUMBER='(2)';
      PINUSE='UNSPEC';
      NO_LOAD_CHECK='BOTH';
      NO_IO_CHECK='BOTH';
      ALLOW_CONNECT='TRUE';
      PIN_GROUP='1';
  end_pin;
  body
      PART_NAME='Q_CAP';
      PHYS_DES_PREFIX='C';
      STANDARD='';
      LIFECYCLE='';
      ASS_PART='';
      PART_NUMBER='CH6101MEB01';
      JEDEC_TYPE='C0402';
      ALT_SYMBOLS='(C0402_OCTAGONXA,C0402-0201)';
      VALUE='NA';
      RATED_VOLTAGE='6.3V';
      TOL='20%';
      CLASS='IO';
      DESCRIPTION='CAP CHIP 10UF 6.3V(+-20%,X6S,0402)';
      COMPONENT_TYPE='CHIP0402';
      LEAD_LENGTH='';
      LPID='';
      DATE='20170330';
      PARENT_PART_TYPE='Q_CAP';
      PARENT_PPT='Q_CAP';
      PARENT_PPT_PART='Q_CAP_C0402-10UF,6.3V,20%,EMPTY,CH6101MEB01';
  end_body;
end_primitive;
primitive 'Q_CAP_C0402-10UF,6.3V,20%,X6S,CH6101MEB01';
  pin
    'A':
      PIN_NUMBER='(1)';
      PINUSE='UNSPEC';
      NO_LOAD_CHECK='BOTH';
      NO_IO_CHECK='BOTH';
      ALLOW_CONNECT='TRUE';
      PIN_GROUP='1';
    'B':
      PIN_NUMBER='(2)';
      PINUSE='UNSPEC';
      NO_LOAD_CHECK='BOTH';
      NO_IO_CHECK='BOTH';
      ALLOW_CONNECT='TRUE';
      PIN_GROUP='1';
  end_pin;
  body
      PART_NAME='Q_CAP';
      PHYS_DES_PREFIX='C';
      STANDARD='';
      LIFECYCLE='';
      ASS_PART='';
      PART_NUMBER='CH6101MEB01';
      JEDEC_TYPE='C0402';
      ALT_SYMBOLS='(C0402_OCTAGONXA,C0402-0201)';
      VALUE='10UF';
      RATED_VOLTAGE='6.3V';
      TOL='20%';
      CLASS='DISCRETE';
      DESCRIPTION='CAP CHIP 10UF 6.3V(+-20%,X6S,0402)';
      COMPONENT_TYPE='CHIP0402';
      LEAD_LENGTH='';
      LPID='';
      DATE='20170330';
      PARENT_PART_TYPE='Q_CAP';
      PARENT_PPT='Q_CAP';
      PARENT_PPT_PART='Q_CAP_C0402-10UF,6.3V,20%,X6S,CH6101MEB01';
  end_body;
end_primitive;
primitive 'Q_CAP_C0402-10UF,6.3V,20%,X6S,CH6101MEB03';
  pin
    'A':
      PIN_NUMBER='(1)';
      PINUSE='UNSPEC';
      NO_LOAD_CHECK='BOTH';
      NO_IO_CHECK='BOTH';
      ALLOW_CONNECT='TRUE';
      PIN_GROUP='1';
    'B':
      PIN_NUMBER='(2)';
      PINUSE='UNSPEC';
      NO_LOAD_CHECK='BOTH';
      NO_IO_CHECK='BOTH';
      ALLOW_CONNECT='TRUE';
      PIN_GROUP='1';
  end_pin;
  body
      PART_NAME='Q_CAP';
      PHYS_DES_PREFIX='C';
      STANDARD='';
      LIFECYCLE='';
      ASS_PART='';
      PART_NUMBER='CH6101MEB03';
      JEDEC_TYPE='C0402';
      ALT_SYMBOLS='(C0402_OCTAGONXA,C0402-0201)';
      VALUE='10UF';
      RATED_VOLTAGE='6.3V';
      TOL='20%';
      CLASS='DISCRETE';
      DESCRIPTION='CAP CHIP 10UF 6.3V(+-20%,X6S,0402)MUR';
      COMPONENT_TYPE='CHIP0402';
      LEAD_LENGTH='';
      LPID='';
      DATE='20160111';
      PARENT_PART_TYPE='Q_CAP';
      PARENT_PPT='Q_CAP';
      PARENT_PPT_PART='Q_CAP_C0402-10UF,6.3V,20%,X6S,CH6101MEB03';
  end_body;
end_primitive;
primitive 'Q_CAP_C0402-12PF,50V,5%,C0G,CH01206JB05';
  pin
    'A':
      PIN_NUMBER='(1)';
      PINUSE='UNSPEC';
      NO_LOAD_CHECK='BOTH';
      NO_IO_CHECK='BOTH';
      ALLOW_CONNECT='TRUE';
      PIN_GROUP='1';
    'B':
      PIN_NUMBER='(2)';
      PINUSE='UNSPEC';
      NO_LOAD_CHECK='BOTH';
      NO_IO_CHECK='BOTH';
      ALLOW_CONNECT='TRUE';
      PIN_GROUP='1';
  end_pin;
  body
      PART_NAME='Q_CAP';
      PHYS_DES_PREFIX='C';
      STANDARD='';
      LIFECYCLE='';
      ASS_PART='';
      PART_NUMBER='CH01206JB05';
      JEDEC_TYPE='C0402';
      ALT_SYMBOLS='(C0402-0201)';
      VALUE='12PF';
      RATED_VOLTAGE='50V';
      TOL='5%';
      CLASS='DISCRETE';
      DESCRIPTION='CAP CHIP 12P 50V(+-5%.C0G.0402)';
      COMPONENT_TYPE='CHIP0402';
      LEAD_LENGTH='';
      LPID='';
      DATE='20130703';
      PARENT_PART_TYPE='Q_CAP';
      PARENT_PPT='Q_CAP';
      PARENT_PPT_PART='Q_CAP_C0402-12PF,50V,5%,C0G,CH01206JB05';
  end_body;
end_primitive;
primitive 'Q_CAP_C0402-1PF,50V,0.05P,COG,CH-106T0B00';
  pin
    'A':
      PIN_NUMBER='(1)';
      PINUSE='UNSPEC';
      NO_LOAD_CHECK='BOTH';
      NO_IO_CHECK='BOTH';
      ALLOW_CONNECT='TRUE';
      PIN_GROUP='1';
    'B':
      PIN_NUMBER='(2)';
      PINUSE='UNSPEC';
      NO_LOAD_CHECK='BOTH';
      NO_IO_CHECK='BOTH';
      ALLOW_CONNECT='TRUE';
      PIN_GROUP='1';
  end_pin;
  body
      PART_NAME='Q_CAP';
      PHYS_DES_PREFIX='C';
      STANDARD='';
      LIFECYCLE='';
      ASS_PART='';
      PART_NUMBER='CH-106T0B00';
      JEDEC_TYPE='C0402';
      ALT_SYMBOLS='(C0402-0201)';
      VALUE='1PF';
      RATED_VOLTAGE='50V';
      TOL='0.05P';
      CLASS='DISCRETE';
      DESCRIPTION='CAP CHIP 1P 50V(+-0.05P,COG,0402)';
      COMPONENT_TYPE='CHIP0402';
      LEAD_LENGTH='';
      LPID='';
      DATE='20140812';
      PARENT_PART_TYPE='Q_CAP';
      PARENT_PPT='Q_CAP';
      PARENT_PPT_PART='Q_CAP_C0402-1PF,50V,0.05P,COG,CH-106T0B00';
  end_body;
end_primitive;
primitive 'Q_CAP_C0402-1UF,16V,10%,X6S,CH5103KEB01';
  pin
    'A':
      PIN_NUMBER='(1)';
      PINUSE='UNSPEC';
      NO_LOAD_CHECK='BOTH';
      NO_IO_CHECK='BOTH';
      ALLOW_CONNECT='TRUE';
      PIN_GROUP='1';
    'B':
      PIN_NUMBER='(2)';
      PINUSE='UNSPEC';
      NO_LOAD_CHECK='BOTH';
      NO_IO_CHECK='BOTH';
      ALLOW_CONNECT='TRUE';
      PIN_GROUP='1';
  end_pin;
  body
      PART_NAME='Q_CAP';
      PHYS_DES_PREFIX='C';
      STANDARD='';
      LIFECYCLE='';
      ASS_PART='';
      PART_NUMBER='CH5103KEB01';
      JEDEC_TYPE='C0402';
      ALT_SYMBOLS='(C0402_OCTAGONXA,C0402-0201)';
      VALUE='1UF';
      RATED_VOLTAGE='16V';
      TOL='10%';
      CLASS='DISCRETE';
      DESCRIPTION='CAP CHIP 1UF 16V(10%,X6S,0402)';
      COMPONENT_TYPE='CHIP0402';
      LEAD_LENGTH='';
      LPID='';
      DATE='20140828';
      PARENT_PART_TYPE='Q_CAP';
      PARENT_PPT='Q_CAP';
      PARENT_PPT_PART='Q_CAP_C0402-1UF,16V,10%,X6S,CH5103KEB01';
  end_body;
end_primitive;
primitive 'Q_CAP_C0402-1UF,25V,10%,EMPTY,CH5104KEB02';
  pin
    'A':
      PIN_NUMBER='(1)';
      PINUSE='UNSPEC';
      NO_LOAD_CHECK='BOTH';
      NO_IO_CHECK='BOTH';
      ALLOW_CONNECT='TRUE';
      PIN_GROUP='1';
    'B':
      PIN_NUMBER='(2)';
      PINUSE='UNSPEC';
      NO_LOAD_CHECK='BOTH';
      NO_IO_CHECK='BOTH';
      ALLOW_CONNECT='TRUE';
      PIN_GROUP='1';
  end_pin;
  body
      PART_NAME='Q_CAP';
      PHYS_DES_PREFIX='C';
      STANDARD='';
      LIFECYCLE='';
      ASS_PART='';
      PART_NUMBER='CH5104KEB02';
      JEDEC_TYPE='C0402';
      ALT_SYMBOLS='(C0402_OCTAGONXA,C0402-0201)';
      VALUE='NA';
      RATED_VOLTAGE='25V';
      TOL='10%';
      CLASS='IO';
      DESCRIPTION='CAP CHIP 1UF 25V(+-10%,X6S,0402)';
      COMPONENT_TYPE='CHIP0402';
      LEAD_LENGTH='';
      LPID='';
      DATE='20140327';
      PARENT_PART_TYPE='Q_CAP';
      PARENT_PPT='Q_CAP';
      PARENT_PPT_PART='Q_CAP_C0402-1UF,25V,10%,EMPTY,CH5104KEB02';
  end_body;
end_primitive;
primitive 'Q_CAP_C0402-1UF,25V,10%,X6S,CH5104KEB02';
  pin
    'A':
      PIN_NUMBER='(1)';
      PINUSE='UNSPEC';
      NO_LOAD_CHECK='BOTH';
      NO_IO_CHECK='BOTH';
      ALLOW_CONNECT='TRUE';
      PIN_GROUP='1';
    'B':
      PIN_NUMBER='(2)';
      PINUSE='UNSPEC';
      NO_LOAD_CHECK='BOTH';
      NO_IO_CHECK='BOTH';
      ALLOW_CONNECT='TRUE';
      PIN_GROUP='1';
  end_pin;
  body
      PART_NAME='Q_CAP';
      PHYS_DES_PREFIX='C';
      STANDARD='';
      LIFECYCLE='';
      ASS_PART='';
      PART_NUMBER='CH5104KEB02';
      JEDEC_TYPE='C0402';
      ALT_SYMBOLS='(C0402_OCTAGONXA,C0402-0201)';
      VALUE='1UF';
      RATED_VOLTAGE='25V';
      TOL='10%';
      CLASS='DISCRETE';
      DESCRIPTION='CAP CHIP 1UF 25V(+-10%,X6S,0402)';
      COMPONENT_TYPE='CHIP0402';
      LEAD_LENGTH='';
      LPID='';
      DATE='20140327';
      PARENT_PART_TYPE='Q_CAP';
      PARENT_PPT='Q_CAP';
      PARENT_PPT_PART='Q_CAP_C0402-1UF,25V,10%,X6S,CH5104KEB02';
  end_body;
end_primitive;
primitive 'Q_CAP_C0402-2.2UF,10V,10%,X6S,CH5222KEB01';
  pin
    'A':
      PIN_NUMBER='(1)';
      PINUSE='UNSPEC';
      NO_LOAD_CHECK='BOTH';
      NO_IO_CHECK='BOTH';
      ALLOW_CONNECT='TRUE';
      PIN_GROUP='1';
    'B':
      PIN_NUMBER='(2)';
      PINUSE='UNSPEC';
      NO_LOAD_CHECK='BOTH';
      NO_IO_CHECK='BOTH';
      ALLOW_CONNECT='TRUE';
      PIN_GROUP='1';
  end_pin;
  body
      PART_NAME='Q_CAP';
      PHYS_DES_PREFIX='C';
      STANDARD='';
      LIFECYCLE='';
      ASS_PART='';
      PART_NUMBER='CH5222KEB01';
      JEDEC_TYPE='C0402';
      ALT_SYMBOLS='(C0402_OCTAGONXA,C0402-0201)';
      VALUE='2.2UF';
      RATED_VOLTAGE='10V';
      TOL='10%';
      CLASS='DISCRETE';
      DESCRIPTION='CAP CHIP 2.2UF 10V(+-10%,X6S,0402)';
      COMPONENT_TYPE='CHIP0402';
      LEAD_LENGTH='';
      LPID='';
      DATE='20150612';
      PARENT_PART_TYPE='Q_CAP';
      PARENT_PPT='Q_CAP';
      PARENT_PPT_PART='Q_CAP_C0402-2.2UF,10V,10%,X6S,CH5222KEB01';
  end_body;
end_primitive;
primitive 'Q_CAP_C0402-2.7PF,50V,0.1PF,NPO,CH-276B0B00';
  pin
    'A':
      PIN_NUMBER='(1)';
      PINUSE='UNSPEC';
      NO_LOAD_CHECK='BOTH';
      NO_IO_CHECK='BOTH';
      ALLOW_CONNECT='TRUE';
      PIN_GROUP='1';
    'B':
      PIN_NUMBER='(2)';
      PINUSE='UNSPEC';
      NO_LOAD_CHECK='BOTH';
      NO_IO_CHECK='BOTH';
      ALLOW_CONNECT='TRUE';
      PIN_GROUP='1';
  end_pin;
  body
      PART_NAME='Q_CAP';
      PHYS_DES_PREFIX='C';
      STANDARD='';
      LIFECYCLE='';
      ASS_PART='';
      PART_NUMBER='CH-276B0B00';
      JEDEC_TYPE='C0402';
      ALT_SYMBOLS='(C0402-0201)';
      VALUE='2.7PF';
      RATED_VOLTAGE='50V';
      TOL='0.1PF';
      CLASS='DISCRETE';
      DESCRIPTION='CAP CHIP 2.7P 50V(+-0.1P,NPO,0402)';
      COMPONENT_TYPE='CHIP0402';
      LEAD_LENGTH='';
      LPID='';
      DATE='20230316';
      PARENT_PART_TYPE='Q_CAP';
      PARENT_PPT='Q_CAP';
      PARENT_PPT_PART='Q_CAP_C0402-2.7PF,50V,0.1PF,NPO,CH-276B0B00';
  end_body;
end_primitive;
primitive 'Q_CAP_C0402-220PF,50V,5%,C0G,CH12206JB00';
  pin
    'A':
      PIN_NUMBER='(1)';
      PINUSE='UNSPEC';
      NO_LOAD_CHECK='BOTH';
      NO_IO_CHECK='BOTH';
      ALLOW_CONNECT='TRUE';
      PIN_GROUP='1';
    'B':
      PIN_NUMBER='(2)';
      PINUSE='UNSPEC';
      NO_LOAD_CHECK='BOTH';
      NO_IO_CHECK='BOTH';
      ALLOW_CONNECT='TRUE';
      PIN_GROUP='1';
  end_pin;
  body
      PART_NAME='Q_CAP';
      PHYS_DES_PREFIX='C';
      STANDARD='';
      LIFECYCLE='';
      ASS_PART='';
      PART_NUMBER='CH12206JB00';
      JEDEC_TYPE='C0402';
      ALT_SYMBOLS='(C0402-0201)';
      VALUE='220PF';
      RATED_VOLTAGE='50V';
      TOL='5%';
      CLASS='DISCRETE';
      DESCRIPTION='CAP CHIP 220P 50V(+-5%.COG.0402)';
      COMPONENT_TYPE='CHIP0402';
      LEAD_LENGTH='';
      LPID='';
      DATE='20160314';
      PARENT_PART_TYPE='Q_CAP';
      PARENT_PPT='Q_CAP';
      PARENT_PPT_PART='Q_CAP_C0402-220PF,50V,5%,C0G,CH12206JB00';
  end_body;
end_primitive;
primitive 'Q_CAP_C0402-22UF,4V,20%,X6S,CH622KMEB02';
  pin
    'A':
      PIN_NUMBER='(1)';
      PINUSE='UNSPEC';
      NO_LOAD_CHECK='BOTH';
      NO_IO_CHECK='BOTH';
      ALLOW_CONNECT='TRUE';
      PIN_GROUP='1';
    'B':
      PIN_NUMBER='(2)';
      PINUSE='UNSPEC';
      NO_LOAD_CHECK='BOTH';
      NO_IO_CHECK='BOTH';
      ALLOW_CONNECT='TRUE';
      PIN_GROUP='1';
  end_pin;
  body
      PART_NAME='Q_CAP';
      PHYS_DES_PREFIX='C';
      STANDARD='End of Design';
      LIFECYCLE='Comp-Approve';
      ASS_PART='';
      PART_NUMBER='CH622KMEB02';
      JEDEC_TYPE='C0402_H32';
      ALT_SYMBOLS='(C0402-0201_H32,C0402_OCTAGONXA)';
      VALUE='22UF';
      RATED_VOLTAGE='4V';
      TOL='20%';
      CLASS='DISCRETE';
      DESCRIPTION='CAP CHIP 22UF 4V(+-20%,X6S,0402)';
      COMPONENT_TYPE='CHIP0402';
      LEAD_LENGTH='';
      LPID='';
      DATE='20180409';
      PARENT_PART_TYPE='Q_CAP';
      PARENT_PPT='Q_CAP';
      PARENT_PPT_PART='Q_CAP_C0402-22UF,4V,20%,X6S,CH622KMEB02';
  end_body;
end_primitive;
primitive 'Q_CAP_C0402-3.9P,50V,0.1P,NPO,CH-3916TB01';
  pin
    'A':
      PIN_NUMBER='(1)';
      PINUSE='UNSPEC';
      NO_LOAD_CHECK='BOTH';
      NO_IO_CHECK='BOTH';
      ALLOW_CONNECT='TRUE';
      PIN_GROUP='1';
    'B':
      PIN_NUMBER='(2)';
      PINUSE='UNSPEC';
      NO_LOAD_CHECK='BOTH';
      NO_IO_CHECK='BOTH';
      ALLOW_CONNECT='TRUE';
      PIN_GROUP='1';
  end_pin;
  body
      PART_NAME='Q_CAP';
      PHYS_DES_PREFIX='C';
      STANDARD='';
      LIFECYCLE='';
      ASS_PART='';
      PART_NUMBER='CH-3916TB01';
      JEDEC_TYPE='C0402';
      ALT_SYMBOLS='(C0402-0201)';
      VALUE='3.9P';
      RATED_VOLTAGE='50V';
      TOL='0.1P';
      CLASS='DISCRETE';
      DESCRIPTION='CAP CHIP 3.9P 50V(+-0.1P,NPO,0402)';
      COMPONENT_TYPE='CHIP0402';
      LEAD_LENGTH='';
      LPID='';
      DATE='20190426';
      PARENT_PART_TYPE='Q_CAP';
      PARENT_PPT='Q_CAP';
      PARENT_PPT_PART='Q_CAP_C0402-3.9P,50V,0.1P,NPO,CH-3916TB01';
  end_body;
end_primitive;
primitive 'Q_CAP_C0402-33NF,25V,10%,EMPTY,CH3334K1B00';
  pin
    'A':
      PIN_NUMBER='(1)';
      PINUSE='UNSPEC';
      NO_LOAD_CHECK='BOTH';
      NO_IO_CHECK='BOTH';
      ALLOW_CONNECT='TRUE';
      PIN_GROUP='1';
    'B':
      PIN_NUMBER='(2)';
      PINUSE='UNSPEC';
      NO_LOAD_CHECK='BOTH';
      NO_IO_CHECK='BOTH';
      ALLOW_CONNECT='TRUE';
      PIN_GROUP='1';
  end_pin;
  body
      PART_NAME='Q_CAP';
      PHYS_DES_PREFIX='C';
      STANDARD='';
      LIFECYCLE='';
      ASS_PART='';
      PART_NUMBER='CH3334K1B00';
      JEDEC_TYPE='C0402';
      ALT_SYMBOLS='(C0402_OCTAGONXA,C0402-0201)';
      VALUE='NA';
      RATED_VOLTAGE='25V';
      TOL='10%';
      CLASS='IO';
      DESCRIPTION='CAP CHIP 33NF 25V(+-10%,X7R,0402)';
      COMPONENT_TYPE='CHIP0402';
      LEAD_LENGTH='';
      LPID='';
      DATE='20140507';
      PARENT_PART_TYPE='Q_CAP';
      PARENT_PPT='Q_CAP';
      PARENT_PPT_PART='Q_CAP_C0402-33NF,25V,10%,EMPTY,CH3334K1B00';
  end_body;
end_primitive;
primitive 'Q_CAP_C0402-3900PF,50V,10%,X7R,CH23906KB14';
  pin
    'A':
      PIN_NUMBER='(1)';
      PINUSE='UNSPEC';
      NO_LOAD_CHECK='BOTH';
      NO_IO_CHECK='BOTH';
      ALLOW_CONNECT='TRUE';
      PIN_GROUP='1';
    'B':
      PIN_NUMBER='(2)';
      PINUSE='UNSPEC';
      NO_LOAD_CHECK='BOTH';
      NO_IO_CHECK='BOTH';
      ALLOW_CONNECT='TRUE';
      PIN_GROUP='1';
  end_pin;
  body
      PART_NAME='Q_CAP';
      PHYS_DES_PREFIX='C';
      STANDARD='';
      LIFECYCLE='';
      ASS_PART='';
      PART_NUMBER='CH23906KB14';
      JEDEC_TYPE='C0402';
      ALT_SYMBOLS='(C0402-0201)';
      VALUE='3900PF';
      RATED_VOLTAGE='50V';
      TOL='10%';
      CLASS='DISCRETE';
      DESCRIPTION='CAP CHIP 3900P 50V(+-10%,X7R,0402)';
      COMPONENT_TYPE='CHIP0402';
      LEAD_LENGTH='';
      LPID='';
      DATE='20140325';
      PARENT_PART_TYPE='Q_CAP';
      PARENT_PPT='Q_CAP';
      PARENT_PPT_PART='Q_CAP_C0402-3900PF,50V,10%,X7R,CH23906KB14';
  end_body;
end_primitive;
primitive 'Q_CAP_C0402-4.7PF,50V,0.1P,NPO,CH-4716TB06';
  pin
    'A':
      PIN_NUMBER='(1)';
      PINUSE='UNSPEC';
      NO_LOAD_CHECK='BOTH';
      NO_IO_CHECK='BOTH';
      ALLOW_CONNECT='TRUE';
      PIN_GROUP='1';
    'B':
      PIN_NUMBER='(2)';
      PINUSE='UNSPEC';
      NO_LOAD_CHECK='BOTH';
      NO_IO_CHECK='BOTH';
      ALLOW_CONNECT='TRUE';
      PIN_GROUP='1';
  end_pin;
  body
      PART_NAME='Q_CAP';
      PHYS_DES_PREFIX='C';
      STANDARD='';
      LIFECYCLE='';
      ASS_PART='';
      PART_NUMBER='CH-4716TB06';
      JEDEC_TYPE='C0402';
      ALT_SYMBOLS='(C0402-0201)';
      VALUE='4.7PF';
      RATED_VOLTAGE='50V';
      TOL='0.10%';
      CLASS='DISCRETE';
      DESCRIPTION='CAP CHIP 4.7P 50V(+-0.1P.NPO.0402)';
      COMPONENT_TYPE='CHIP0402';
      LEAD_LENGTH='';
      LPID='';
      DATE='20121216';
      PARENT_PART_TYPE='Q_CAP';
      PARENT_PPT='Q_CAP';
      PARENT_PPT_PART='Q_CAP_C0402-4.7PF,50V,0.1P,NPO,CH-4716TB06';
  end_body;
end_primitive;
primitive 'Q_CAP_C0402-560PF,50V,10%,EMPTY,CH1566K1B09';
  pin
    'A':
      PIN_NUMBER='(1)';
      PINUSE='UNSPEC';
      NO_LOAD_CHECK='BOTH';
      NO_IO_CHECK='BOTH';
      ALLOW_CONNECT='TRUE';
      PIN_GROUP='1';
    'B':
      PIN_NUMBER='(2)';
      PINUSE='UNSPEC';
      NO_LOAD_CHECK='BOTH';
      NO_IO_CHECK='BOTH';
      ALLOW_CONNECT='TRUE';
      PIN_GROUP='1';
  end_pin;
  body
      PART_NAME='Q_CAP';
      PHYS_DES_PREFIX='C';
      STANDARD='';
      LIFECYCLE='';
      ASS_PART='';
      PART_NUMBER='CH1566K1B09';
      JEDEC_TYPE='C0402';
      ALT_SYMBOLS='(C0402_OCTAGONXA,C0402-0201)';
      VALUE='NA';
      RATED_VOLTAGE='50V';
      TOL='10%';
      CLASS='IO';
      DESCRIPTION='CAP CHIP 560P 50V(+-10%,X7R,0402)';
      COMPONENT_TYPE='CHIP0402';
      LEAD_LENGTH='';
      LPID='';
      DATE='20130114';
      PARENT_PART_TYPE='Q_CAP';
      PARENT_PPT='Q_CAP';
      PARENT_PPT_PART='Q_CAP_C0402-560PF,50V,10%,EMPTY,CH1566K1B09';
  end_body;
end_primitive;
primitive 'Q_CAP_C0402-560PF,50V,10%,X7R,CH1566K1B09';
  pin
    'A':
      PIN_NUMBER='(1)';
      PINUSE='UNSPEC';
      NO_LOAD_CHECK='BOTH';
      NO_IO_CHECK='BOTH';
      ALLOW_CONNECT='TRUE';
      PIN_GROUP='1';
    'B':
      PIN_NUMBER='(2)';
      PINUSE='UNSPEC';
      NO_LOAD_CHECK='BOTH';
      NO_IO_CHECK='BOTH';
      ALLOW_CONNECT='TRUE';
      PIN_GROUP='1';
  end_pin;
  body
      PART_NAME='Q_CAP';
      PHYS_DES_PREFIX='C';
      STANDARD='';
      LIFECYCLE='';
      ASS_PART='';
      PART_NUMBER='CH1566K1B09';
      JEDEC_TYPE='C0402';
      ALT_SYMBOLS='(C0402_OCTAGONXA,C0402-0201)';
      VALUE='560PF';
      RATED_VOLTAGE='50V';
      TOL='10%';
      CLASS='DISCRETE';
      DESCRIPTION='CAP CHIP 560P 50V(+-10%,X7R,0402)';
      COMPONENT_TYPE='CHIP0402';
      LEAD_LENGTH='';
      LPID='';
      DATE='20130114';
      PARENT_PART_TYPE='Q_CAP';
      PARENT_PPT='Q_CAP';
      PARENT_PPT_PART='Q_CAP_C0402-560PF,50V,10%,X7R,CH1566K1B09';
  end_body;
end_primitive;
primitive 'Q_CAP_C0402-6800PF,50V,10%,X7R,CH2686K1B01';
  pin
    'A':
      PIN_NUMBER='(1)';
      PINUSE='UNSPEC';
      NO_LOAD_CHECK='BOTH';
      NO_IO_CHECK='BOTH';
      ALLOW_CONNECT='TRUE';
      PIN_GROUP='1';
    'B':
      PIN_NUMBER='(2)';
      PINUSE='UNSPEC';
      NO_LOAD_CHECK='BOTH';
      NO_IO_CHECK='BOTH';
      ALLOW_CONNECT='TRUE';
      PIN_GROUP='1';
  end_pin;
  body
      PART_NAME='Q_CAP';
      PHYS_DES_PREFIX='C';
      STANDARD='';
      LIFECYCLE='';
      ASS_PART='';
      PART_NUMBER='CH2686K1B01';
      JEDEC_TYPE='C0402';
      ALT_SYMBOLS='(C0402-0201)';
      VALUE='6800PF';
      RATED_VOLTAGE='50V';
      TOL='10%';
      CLASS='DISCRETE';
      DESCRIPTION='CAP CHIP 6800P 50V(+-10%,X7R,0402)';
      COMPONENT_TYPE='CHIP0402';
      LEAD_LENGTH='';
      LPID='';
      DATE='20120113';
      PARENT_PART_TYPE='Q_CAP';
      PARENT_PPT='Q_CAP';
      PARENT_PPT_PART='Q_CAP_C0402-6800PF,50V,10%,X7R,CH2686K1B01';
  end_body;
end_primitive;
primitive 'Q_CAP_C0402-8.2PF,50V,0.1P,NP0,CH-8216TB09';
  pin
    'A':
      PIN_NUMBER='(1)';
      PINUSE='UNSPEC';
      NO_LOAD_CHECK='BOTH';
      NO_IO_CHECK='BOTH';
      ALLOW_CONNECT='TRUE';
      PIN_GROUP='1';
    'B':
      PIN_NUMBER='(2)';
      PINUSE='UNSPEC';
      NO_LOAD_CHECK='BOTH';
      NO_IO_CHECK='BOTH';
      ALLOW_CONNECT='TRUE';
      PIN_GROUP='1';
  end_pin;
  body
      PART_NAME='Q_CAP';
      PHYS_DES_PREFIX='C';
      STANDARD='';
      LIFECYCLE='';
      ASS_PART='';
      PART_NUMBER='CH-8216TB09';
      JEDEC_TYPE='C0402';
      ALT_SYMBOLS='(C0402-0201)';
      VALUE='8.2PF';
      RATED_VOLTAGE='50V';
      TOL='0.1P';
      CLASS='DISCRETE';
      DESCRIPTION='CAP CHIP 8.2P 50V (+-0.1P NP0 0402)';
      COMPONENT_TYPE='CHIP0402';
      LEAD_LENGTH='';
      LPID='';
      DATE='20140326';
      PARENT_PART_TYPE='Q_CAP';
      PARENT_PPT='Q_CAP';
      PARENT_PPT_PART='Q_CAP_C0402-8.2PF,50V,0.1P,NP0,CH-8216TB09';
  end_body;
end_primitive;
primitive 'Q_CAP_C0603-2.2UF,16V,10%,X6S,CH5223KE901';
  pin
    'A':
      PIN_NUMBER='(1)';
      PINUSE='UNSPEC';
      NO_LOAD_CHECK='BOTH';
      NO_IO_CHECK='BOTH';
      ALLOW_CONNECT='TRUE';
      PIN_GROUP='1';
    'B':
      PIN_NUMBER='(2)';
      PINUSE='UNSPEC';
      NO_LOAD_CHECK='BOTH';
      NO_IO_CHECK='BOTH';
      ALLOW_CONNECT='TRUE';
      PIN_GROUP='1';
  end_pin;
  body
      PART_NAME='Q_CAP';
      PHYS_DES_PREFIX='C';
      STANDARD='';
      LIFECYCLE='';
      ASS_PART='';
      PART_NUMBER='CH5223KE901';
      JEDEC_TYPE='C0603';
      ALT_SYMBOLS='(SMC0603AW)';
      VALUE='2.2UF';
      RATED_VOLTAGE='16V';
      TOL='10%';
      CLASS='DISCRETE';
      DESCRIPTION='CAP CHIP 2.2U 16V(+-10%,X6S,0603)';
      COMPONENT_TYPE='CHIP0603';
      LEAD_LENGTH='';
      LPID='';
      DATE='20140327';
      PARENT_PART_TYPE='Q_CAP';
      PARENT_PPT='Q_CAP';
      PARENT_PPT_PART='Q_CAP_C0603-2.2UF,16V,10%,X6S,CH5223KE901';
  end_body;
end_primitive;
primitive 'Q_CAP_C0603-2.2UF,16V,20%,X7R,CH5223M1900';
  pin
    'A':
      PIN_NUMBER='(1)';
      PINUSE='UNSPEC';
      NO_LOAD_CHECK='BOTH';
      NO_IO_CHECK='BOTH';
      ALLOW_CONNECT='TRUE';
      PIN_GROUP='1';
    'B':
      PIN_NUMBER='(2)';
      PINUSE='UNSPEC';
      NO_LOAD_CHECK='BOTH';
      NO_IO_CHECK='BOTH';
      ALLOW_CONNECT='TRUE';
      PIN_GROUP='1';
  end_pin;
  body
      PART_NAME='Q_CAP';
      PHYS_DES_PREFIX='C';
      STANDARD='';
      LIFECYCLE='';
      ASS_PART='';
      PART_NUMBER='CH5223M1900';
      JEDEC_TYPE='C0603_H40';
      ALT_SYMBOLS='(SMC0603AW)';
      VALUE='2.2UF';
      RATED_VOLTAGE='16V';
      TOL='20%';
      CLASS='DISCRETE';
      DESCRIPTION='CAP CHIP 2.2UF 16V(20%,X7R,0603)';
      COMPONENT_TYPE='CHIP0603';
      LEAD_LENGTH='';
      LPID='';
      DATE='20191216';
      PARENT_PART_TYPE='Q_CAP';
      PARENT_PPT='Q_CAP';
      PARENT_PPT_PART='Q_CAP_C0603-2.2UF,16V,20%,X7R,CH5223M1900';
  end_body;
end_primitive;
primitive 'Q_CAP_C0603-22UF,6.3V,20%,X6S,CH6221ME900';
  pin
    'A':
      PIN_NUMBER='(1)';
      PINUSE='UNSPEC';
      NO_LOAD_CHECK='BOTH';
      NO_IO_CHECK='BOTH';
      ALLOW_CONNECT='TRUE';
      PIN_GROUP='1';
    'B':
      PIN_NUMBER='(2)';
      PINUSE='UNSPEC';
      NO_LOAD_CHECK='BOTH';
      NO_IO_CHECK='BOTH';
      ALLOW_CONNECT='TRUE';
      PIN_GROUP='1';
  end_pin;
  body
      PART_NAME='Q_CAP';
      PHYS_DES_PREFIX='C';
      STANDARD='';
      LIFECYCLE='';
      ASS_PART='';
      PART_NUMBER='CH6221ME900';
      JEDEC_TYPE='C0603';
      ALT_SYMBOLS='(SMC0603AW)';
      VALUE='22UF';
      RATED_VOLTAGE='6.3V';
      TOL='20%';
      CLASS='DISCRETE';
      DESCRIPTION='CAP CHIP 22U 6.3V(+-20%,X6S,0603)';
      COMPONENT_TYPE='CHIP0603';
      LEAD_LENGTH='';
      LPID='';
      DATE='20140327';
      PARENT_PART_TYPE='Q_CAP';
      PARENT_PPT='Q_CAP';
      PARENT_PPT_PART='Q_CAP_C0603-22UF,6.3V,20%,X6S,CH6221ME900';
  end_body;
end_primitive;
primitive 'Q_CAP_C0603-4.7UF,16V,10%,X6S,CH5473KE902';
  pin
    'A':
      PIN_NUMBER='(1)';
      PINUSE='UNSPEC';
      NO_LOAD_CHECK='BOTH';
      NO_IO_CHECK='BOTH';
      ALLOW_CONNECT='TRUE';
      PIN_GROUP='1';
    'B':
      PIN_NUMBER='(2)';
      PINUSE='UNSPEC';
      NO_LOAD_CHECK='BOTH';
      NO_IO_CHECK='BOTH';
      ALLOW_CONNECT='TRUE';
      PIN_GROUP='1';
  end_pin;
  body
      PART_NAME='Q_CAP';
      PHYS_DES_PREFIX='C';
      STANDARD='';
      LIFECYCLE='';
      ASS_PART='';
      PART_NUMBER='CH5473KE902';
      JEDEC_TYPE='C0603_H40';
      ALT_SYMBOLS='(SMC0603AW)';
      VALUE='4.7UF';
      RATED_VOLTAGE='16V';
      TOL='10%';
      CLASS='DISCRETE';
      DESCRIPTION='CAP CHIP 4.7UF 16V(+-10%,X6S,0603)';
      COMPONENT_TYPE='CHIP0603';
      LEAD_LENGTH='';
      LPID='';
      DATE='20180627';
      PARENT_PART_TYPE='Q_CAP';
      PARENT_PPT='Q_CAP';
      PARENT_PPT_PART='Q_CAP_C0603-4.7UF,16V,10%,X6S,CH5473KE902';
  end_body;
end_primitive;
primitive 'Q_CAP_C0805-100UF,4V,20%,X6S,CH710KMEA01';
  pin
    'A':
      PIN_NUMBER='(1)';
      PINUSE='UNSPEC';
      NO_LOAD_CHECK='BOTH';
      NO_IO_CHECK='BOTH';
      ALLOW_CONNECT='TRUE';
      PIN_GROUP='1';
    'B':
      PIN_NUMBER='(2)';
      PINUSE='UNSPEC';
      NO_LOAD_CHECK='BOTH';
      NO_IO_CHECK='BOTH';
      ALLOW_CONNECT='TRUE';
      PIN_GROUP='1';
  end_pin;
  body
      PART_NAME='Q_CAP';
      PHYS_DES_PREFIX='C';
      STANDARD='';
      LIFECYCLE='';
      ASS_PART='';
      PART_NUMBER='CH710KMEA01';
      JEDEC_TYPE='C0805_H61';
      ALT_SYMBOLS='(SMC0805AW)';
      VALUE='100UF';
      RATED_VOLTAGE='4V';
      TOL='20%';
      CLASS='DISCRETE';
      DESCRIPTION='CAP CHIP 100U 4V(+-20%,X6S,0805)MUR';
      COMPONENT_TYPE='CHIP0805';
      LEAD_LENGTH='';
      LPID='';
      DATE='20150615';
      PARENT_PART_TYPE='Q_CAP';
      PARENT_PPT='Q_CAP';
      PARENT_PPT_PART='Q_CAP_C0805-100UF,4V,20%,X6S,CH710KMEA01';
  end_body;
end_primitive;
primitive 'Q_CAP_C0805-10UF,16V,10%,EMPTY,CH6103KEA00';
  pin
    'A':
      PIN_NUMBER='(1)';
      PINUSE='UNSPEC';
      NO_LOAD_CHECK='BOTH';
      NO_IO_CHECK='BOTH';
      ALLOW_CONNECT='TRUE';
      PIN_GROUP='1';
    'B':
      PIN_NUMBER='(2)';
      PINUSE='UNSPEC';
      NO_LOAD_CHECK='BOTH';
      NO_IO_CHECK='BOTH';
      ALLOW_CONNECT='TRUE';
      PIN_GROUP='1';
  end_pin;
  body
      PART_NAME='Q_CAP';
      PHYS_DES_PREFIX='C';
      STANDARD='';
      LIFECYCLE='';
      ASS_PART='';
      PART_NUMBER='CH6103KEA00';
      JEDEC_TYPE='C0805_H57';
      ALT_SYMBOLS='(SMC0805AW)';
      VALUE='NA';
      RATED_VOLTAGE='16V';
      TOL='10%';
      CLASS='IO';
      DESCRIPTION='CAP CHIP 10UF 16V(+-10%,X6S,0805)';
      COMPONENT_TYPE='CHIP0805';
      LEAD_LENGTH='';
      LPID='';
      DATE='20180706';
      PARENT_PART_TYPE='Q_CAP';
      PARENT_PPT='Q_CAP';
      PARENT_PPT_PART='Q_CAP_C0805-10UF,16V,10%,EMPTY,CH6103KEA00';
  end_body;
end_primitive;
primitive 'Q_CAP_C0805-10UF,16V,10%,X6S,CH6103KEA00';
  pin
    'A':
      PIN_NUMBER='(1)';
      PINUSE='UNSPEC';
      NO_LOAD_CHECK='BOTH';
      NO_IO_CHECK='BOTH';
      ALLOW_CONNECT='TRUE';
      PIN_GROUP='1';
    'B':
      PIN_NUMBER='(2)';
      PINUSE='UNSPEC';
      NO_LOAD_CHECK='BOTH';
      NO_IO_CHECK='BOTH';
      ALLOW_CONNECT='TRUE';
      PIN_GROUP='1';
  end_pin;
  body
      PART_NAME='Q_CAP';
      PHYS_DES_PREFIX='C';
      STANDARD='';
      LIFECYCLE='';
      ASS_PART='';
      PART_NUMBER='CH6103KEA00';
      JEDEC_TYPE='C0805_H57';
      ALT_SYMBOLS='(SMC0805AW)';
      VALUE='10UF';
      RATED_VOLTAGE='16V';
      TOL='10%';
      CLASS='DISCRETE';
      DESCRIPTION='CAP CHIP 10UF 16V(+-10%,X6S,0805)';
      COMPONENT_TYPE='CHIP0805';
      LEAD_LENGTH='';
      LPID='';
      DATE='20180706';
      PARENT_PART_TYPE='Q_CAP';
      PARENT_PPT='Q_CAP';
      PARENT_PPT_PART='Q_CAP_C0805-10UF,16V,10%,X6S,CH6103KEA00';
  end_body;
end_primitive;
primitive 'Q_CAP_C0805-10UF,16V,10%,X6S,CH6103KEA01';
  pin
    'A':
      PIN_NUMBER='(1)';
      PINUSE='UNSPEC';
      NO_LOAD_CHECK='BOTH';
      NO_IO_CHECK='BOTH';
      ALLOW_CONNECT='TRUE';
      PIN_GROUP='1';
    'B':
      PIN_NUMBER='(2)';
      PINUSE='UNSPEC';
      NO_LOAD_CHECK='BOTH';
      NO_IO_CHECK='BOTH';
      ALLOW_CONNECT='TRUE';
      PIN_GROUP='1';
  end_pin;
  body
      PART_NAME='Q_CAP';
      PHYS_DES_PREFIX='C';
      STANDARD='';
      LIFECYCLE='';
      ASS_PART='';
      PART_NUMBER='CH6103KEA01';
      JEDEC_TYPE='C0805_H57';
      ALT_SYMBOLS='(SMC0805AW)';
      VALUE='10UF';
      RATED_VOLTAGE='16V';
      TOL='10%';
      CLASS='DISCRETE';
      DESCRIPTION='CAP CHIP 10UF 16V(+-10%,X6S,0805)MUR';
      COMPONENT_TYPE='CHIP0805';
      LEAD_LENGTH='';
      LPID='';
      DATE='20181128';
      PARENT_PART_TYPE='Q_CAP';
      PARENT_PPT='Q_CAP';
      PARENT_PPT_PART='Q_CAP_C0805-10UF,16V,10%,X6S,CH6103KEA01';
  end_body;
end_primitive;
primitive 'Q_CAP_C0805-10UF,25V,10%,X6S,CH6104KEA00';
  pin
    'A':
      PIN_NUMBER='(1)';
      PINUSE='UNSPEC';
      NO_LOAD_CHECK='BOTH';
      NO_IO_CHECK='BOTH';
      ALLOW_CONNECT='TRUE';
      PIN_GROUP='1';
    'B':
      PIN_NUMBER='(2)';
      PINUSE='UNSPEC';
      NO_LOAD_CHECK='BOTH';
      NO_IO_CHECK='BOTH';
      ALLOW_CONNECT='TRUE';
      PIN_GROUP='1';
  end_pin;
  body
      PART_NAME='Q_CAP';
      PHYS_DES_PREFIX='C';
      STANDARD='';
      LIFECYCLE='';
      ASS_PART='';
      PART_NUMBER='CH6104KEA00';
      JEDEC_TYPE='C0805_H61';
      ALT_SYMBOLS='(SMC0805AW)';
      VALUE='10UF';
      RATED_VOLTAGE='25V';
      TOL='10%';
      CLASS='DISCRETE';
      DESCRIPTION='CAP CHIP 10U 25V(+-10%,X6S,0805,H1.25)';
      COMPONENT_TYPE='CHIP0805';
      LEAD_LENGTH='';
      LPID='';
      DATE='20140327';
      PARENT_PART_TYPE='Q_CAP';
      PARENT_PPT='Q_CAP';
      PARENT_PPT_PART='Q_CAP_C0805-10UF,25V,10%,X6S,CH6104KEA00';
  end_body;
end_primitive;
primitive 'Q_CAP_C0805-22UF,10V,20%,X6S,CH6222MEA01';
  pin
    'A':
      PIN_NUMBER='(1)';
      PINUSE='UNSPEC';
      NO_LOAD_CHECK='BOTH';
      NO_IO_CHECK='BOTH';
      ALLOW_CONNECT='TRUE';
      PIN_GROUP='1';
    'B':
      PIN_NUMBER='(2)';
      PINUSE='UNSPEC';
      NO_LOAD_CHECK='BOTH';
      NO_IO_CHECK='BOTH';
      ALLOW_CONNECT='TRUE';
      PIN_GROUP='1';
  end_pin;
  body
      PART_NAME='Q_CAP';
      PHYS_DES_PREFIX='C';
      STANDARD='';
      LIFECYCLE='';
      ASS_PART='';
      PART_NUMBER='CH6222MEA01';
      JEDEC_TYPE='C0805_H61';
      ALT_SYMBOLS='(SMC0805AW)';
      VALUE='22UF';
      RATED_VOLTAGE='10V';
      TOL='20%';
      CLASS='DISCRETE';
      DESCRIPTION='CAP CHIP 22U 10V(+-20%,X6S,0805)MUR';
      COMPONENT_TYPE='CHIP0805';
      LEAD_LENGTH='';
      LPID='';
      DATE='20150615';
      PARENT_PART_TYPE='Q_CAP';
      PARENT_PPT='Q_CAP';
      PARENT_PPT_PART='Q_CAP_C0805-22UF,10V,20%,X6S,CH6222MEA01';
  end_body;
end_primitive;
primitive 'Q_CAP_C0805-22UF,16V,20%,EMPTY,CH6223MEA00';
  pin
    'A':
      PIN_NUMBER='(1)';
      PINUSE='UNSPEC';
      NO_LOAD_CHECK='BOTH';
      NO_IO_CHECK='BOTH';
      ALLOW_CONNECT='TRUE';
      PIN_GROUP='1';
    'B':
      PIN_NUMBER='(2)';
      PINUSE='UNSPEC';
      NO_LOAD_CHECK='BOTH';
      NO_IO_CHECK='BOTH';
      ALLOW_CONNECT='TRUE';
      PIN_GROUP='1';
  end_pin;
  body
      PART_NAME='Q_CAP';
      PHYS_DES_PREFIX='C';
      STANDARD='';
      LIFECYCLE='';
      ASS_PART='';
      PART_NUMBER='CH6223MEA00';
      JEDEC_TYPE='C0805_H57';
      ALT_SYMBOLS='(SMC0805AW)';
      VALUE='NA';
      RATED_VOLTAGE='16V';
      TOL='20%';
      CLASS='IO';
      DESCRIPTION='CAP CHIP 22U 16V(+-20%,X6S,0805)';
      COMPONENT_TYPE='CHIP0805';
      LEAD_LENGTH='';
      LPID='';
      DATE='2016019';
      PARENT_PART_TYPE='Q_CAP';
      PARENT_PPT='Q_CAP';
      PARENT_PPT_PART='Q_CAP_C0805-22UF,16V,20%,EMPTY,CH6223MEA00';
  end_body;
end_primitive;
primitive 'Q_CAP_C0805-22UF,16V,20%,X6S,CH6223MEA00';
  pin
    'A':
      PIN_NUMBER='(1)';
      PINUSE='UNSPEC';
      NO_LOAD_CHECK='BOTH';
      NO_IO_CHECK='BOTH';
      ALLOW_CONNECT='TRUE';
      PIN_GROUP='1';
    'B':
      PIN_NUMBER='(2)';
      PINUSE='UNSPEC';
      NO_LOAD_CHECK='BOTH';
      NO_IO_CHECK='BOTH';
      ALLOW_CONNECT='TRUE';
      PIN_GROUP='1';
  end_pin;
  body
      PART_NAME='Q_CAP';
      PHYS_DES_PREFIX='C';
      STANDARD='';
      LIFECYCLE='';
      ASS_PART='';
      PART_NUMBER='CH6223MEA00';
      JEDEC_TYPE='C0805_H57';
      ALT_SYMBOLS='(SMC0805AW)';
      VALUE='22UF';
      RATED_VOLTAGE='16V';
      TOL='20%';
      CLASS='DISCRETE';
      DESCRIPTION='CAP CHIP 22U 16V(+-20%,X6S,0805)';
      COMPONENT_TYPE='CHIP0805';
      LEAD_LENGTH='';
      LPID='';
      DATE='2016019';
      PARENT_PART_TYPE='Q_CAP';
      PARENT_PPT='Q_CAP';
      PARENT_PPT_PART='Q_CAP_C0805-22UF,16V,20%,X6S,CH6223MEA00';
  end_body;
end_primitive;
primitive 'Q_CAP_C0805-22UF,16V,20%,X6S,CH6223MEA01';
  pin
    'A':
      PIN_NUMBER='(1)';
      PINUSE='UNSPEC';
      NO_LOAD_CHECK='BOTH';
      NO_IO_CHECK='BOTH';
      ALLOW_CONNECT='TRUE';
      PIN_GROUP='1';
    'B':
      PIN_NUMBER='(2)';
      PINUSE='UNSPEC';
      NO_LOAD_CHECK='BOTH';
      NO_IO_CHECK='BOTH';
      ALLOW_CONNECT='TRUE';
      PIN_GROUP='1';
  end_pin;
  body
      PART_NAME='Q_CAP';
      PHYS_DES_PREFIX='C';
      STANDARD='';
      LIFECYCLE='';
      ASS_PART='';
      PART_NUMBER='CH6223MEA01';
      JEDEC_TYPE='C0805_H57';
      ALT_SYMBOLS='(SMC0805AW)';
      VALUE='22UF';
      RATED_VOLTAGE='16V';
      TOL='20%';
      CLASS='DISCRETE';
      DESCRIPTION='CAP CHIP 22UF 16V(+-20%,X6S,0805)MUR';
      COMPONENT_TYPE='CHIP0805';
      LEAD_LENGTH='';
      LPID='';
      DATE='20171127';
      PARENT_PART_TYPE='Q_CAP';
      PARENT_PPT='Q_CAP';
      PARENT_PPT_PART='Q_CAP_C0805-22UF,16V,20%,X6S,CH6223MEA01';
  end_body;
end_primitive;
primitive 'Q_CAP_C0805-22UF,4V,20%,EMPTY,CH622KMEA03';
  pin
    'A':
      PIN_NUMBER='(1)';
      PINUSE='UNSPEC';
      NO_LOAD_CHECK='BOTH';
      NO_IO_CHECK='BOTH';
      ALLOW_CONNECT='TRUE';
      PIN_GROUP='1';
    'B':
      PIN_NUMBER='(2)';
      PINUSE='UNSPEC';
      NO_LOAD_CHECK='BOTH';
      NO_IO_CHECK='BOTH';
      ALLOW_CONNECT='TRUE';
      PIN_GROUP='1';
  end_pin;
  body
      PART_NAME='Q_CAP';
      PHYS_DES_PREFIX='C';
      STANDARD='';
      LIFECYCLE='';
      ASS_PART='';
      PART_NUMBER='CH622KMEA03';
      JEDEC_TYPE='C0805_H61';
      ALT_SYMBOLS='(SMC0805AW)';
      VALUE='NA';
      RATED_VOLTAGE='4V';
      TOL='20%';
      CLASS='IO';
      DESCRIPTION='CAP CHIP 22U 4V(+-20%,X6S,0805)MUR';
      COMPONENT_TYPE='CHIP0805';
      LEAD_LENGTH='';
      LPID='';
      DATE='20150615';
      PARENT_PART_TYPE='Q_CAP';
      PARENT_PPT='Q_CAP';
      PARENT_PPT_PART='Q_CAP_C0805-22UF,4V,20%,EMPTY,CH622KMEA03';
  end_body;
end_primitive;
primitive 'Q_CAP_C0805-22UF,4V,20%,X6S,CH622KMEA03';
  pin
    'A':
      PIN_NUMBER='(1)';
      PINUSE='UNSPEC';
      NO_LOAD_CHECK='BOTH';
      NO_IO_CHECK='BOTH';
      ALLOW_CONNECT='TRUE';
      PIN_GROUP='1';
    'B':
      PIN_NUMBER='(2)';
      PINUSE='UNSPEC';
      NO_LOAD_CHECK='BOTH';
      NO_IO_CHECK='BOTH';
      ALLOW_CONNECT='TRUE';
      PIN_GROUP='1';
  end_pin;
  body
      PART_NAME='Q_CAP';
      PHYS_DES_PREFIX='C';
      STANDARD='';
      LIFECYCLE='';
      ASS_PART='';
      PART_NUMBER='CH622KMEA03';
      JEDEC_TYPE='C0805_H61';
      ALT_SYMBOLS='(SMC0805AW)';
      VALUE='22UF';
      RATED_VOLTAGE='4V';
      TOL='20%';
      CLASS='DISCRETE';
      DESCRIPTION='CAP CHIP 22U 4V(+-20%,X6S,0805)MUR';
      COMPONENT_TYPE='CHIP0805';
      LEAD_LENGTH='';
      LPID='';
      DATE='20150615';
      PARENT_PART_TYPE='Q_CAP';
      PARENT_PPT='Q_CAP';
      PARENT_PPT_PART='Q_CAP_C0805-22UF,4V,20%,X6S,CH622KMEA03';
  end_body;
end_primitive;
primitive 'Q_CAP_C0805-47UF,4V,20%,X6S,CH647KMEA04';
  pin
    'A':
      PIN_NUMBER='(1)';
      PINUSE='UNSPEC';
      NO_LOAD_CHECK='BOTH';
      NO_IO_CHECK='BOTH';
      ALLOW_CONNECT='TRUE';
      PIN_GROUP='1';
    'B':
      PIN_NUMBER='(2)';
      PINUSE='UNSPEC';
      NO_LOAD_CHECK='BOTH';
      NO_IO_CHECK='BOTH';
      ALLOW_CONNECT='TRUE';
      PIN_GROUP='1';
  end_pin;
  body
      PART_NAME='Q_CAP';
      PHYS_DES_PREFIX='C';
      STANDARD='';
      LIFECYCLE='';
      ASS_PART='';
      PART_NUMBER='CH647KMEA04';
      JEDEC_TYPE='C0805_H57';
      ALT_SYMBOLS='(C0805_H57_M,C0805_BHS)';
      VALUE='47UF';
      RATED_VOLTAGE='4V';
      TOL='20%';
      CLASS='DISCRETE';
      DESCRIPTION='CAP CHIP 47U 4V(+-20%,X6S,0805)MUR';
      COMPONENT_TYPE='CHIP0805';
      LEAD_LENGTH='';
      LPID='';
      DATE='20160616';
      PARENT_PART_TYPE='Q_CAP';
      PARENT_PPT='Q_CAP';
      PARENT_PPT_PART='Q_CAP_C0805-47UF,4V,20%,X6S,CH647KMEA04';
  end_body;
end_primitive;
primitive 'Q_CAP_DIFFBUS_C0201-DIFF BUS_0.22UF,6.3V,20%,X6S,SA';
  pin
    '1':
      PIN_NUMBER='(1)';
      BIDIRECTIONAL='TRUE';
      INPUT_LOAD='(-0.01,0.01)';
      OUTPUT_LOAD='(1.0,-1.0)';
      PINUSE='BI';
    '2':
      PIN_NUMBER='(2)';
      BIDIRECTIONAL='TRUE';
      INPUT_LOAD='(-0.01,0.01)';
      OUTPUT_LOAD='(1.0,-1.0)';
      PINUSE='BI';
  end_pin;
  body
      PART_NAME='Q_CAP_DIFFBUS';
      BODY_NAME='Q_CAP_DIFFBUS';
      PHYS_DES_PREFIX='C';
      CLASS='DISCRETE';
      STANDARD='';
      LIFECYCLE='';
      ASS_PART='';
      PART_NUMBER='CH4221MEE01';
      JEDEC_TYPE='C0201_DIFF-BUS';
      DESCRIPTION='CAP CHIP 0.22UF 6.3V(20%,X6S,0201)_DIFF BUS';
      MANUFTR='TDK';
      MANUF_PN='C0603X6S0J224MT-A';
      RD_CMPLS_LVL='EP(V1)';
      CMPLS_LVL='EP(V1)';
      DIP_SMD='';
      FROM_PJ='CJ2A-KEVIN';
      DATA='AC Coupling.msg';
      FP_ECN='DCN-all 0201 RCL part.doc';
      EE_CHECK_LIST='';
      PSL='';
      STATUS='';
      CREATOR='';
      CREATEDAY='20150629';
      PARENT_PART_TYPE='Q_CAP_DIFFBUS';
      PARENT_PPT='Q_CAP_DIFFBUS';
      PARENT_PPT_PART='Q_CAP_DIFFBUS_C0201-DIFF BUS_0.22UF,6.3V,20%,X6S,SP_CH4221MEE01';
  end_body;
end_primitive;
primitive 'Q_CAP_DIFFBUS_C0402-DIFF BUS_0.33UF,6.3V,10%,X6S,SA';
  pin
    '1':
      PIN_NUMBER='(1)';
      BIDIRECTIONAL='TRUE';
      INPUT_LOAD='(-0.01,0.01)';
      OUTPUT_LOAD='(1.0,-1.0)';
      PINUSE='BI';
    '2':
      PIN_NUMBER='(2)';
      BIDIRECTIONAL='TRUE';
      INPUT_LOAD='(-0.01,0.01)';
      OUTPUT_LOAD='(1.0,-1.0)';
      PINUSE='BI';
  end_pin;
  body
      PART_NAME='Q_CAP_DIFFBUS';
      BODY_NAME='Q_CAP_DIFFBUS';
      PHYS_DES_PREFIX='C';
      CLASS='DISCRETE';
      STANDARD='End of Design';
      LIFECYCLE='Comp-Approve';
      ASS_PART='';
      PART_NUMBER='CH4331KEB01';
      JEDEC_TYPE='C0402_DIFF-BUS';
      DESCRIPTION='CAP CHIP 0.33UF 6.3V(10%,X6S,0402)_FOR DIFF BUS';
      MANUFTR='MUR';
      MANUF_PN='GRM155C80J334K';
      RD_CMPLS_LVL='EP(V1)';
      CMPLS_LVL='EP(V1)';
      DIP_SMD='';
      FROM_PJ='S5R-ROGER';
      DATA='';
      FP_ECN='';
      EE_CHECK_LIST='';
      PSL='';
      STATUS='';
      CREATOR='';
      CREATEDAY='20180504';
      PARENT_PART_TYPE='Q_CAP_DIFFBUS';
      PARENT_PPT='Q_CAP_DIFFBUS';
      PARENT_PPT_PART='Q_CAP_DIFFBUS_C0402-DIFF BUS_0.33UF,6.3V,10%,X6S,SP_CH4331KEB01';
  end_body;
end_primitive;
primitive 'Q_CRYSTAL_SMLF-32.768KHZ,EMPTY,BG632768012';
  pin
    '1':
      PIN_NUMBER='(1)';
      INPUT_LOAD='(-0.01,0.01)';
      OUTPUT_LOAD='(1.0,-1.0)';
      BIDIRECTIONAL='TRUE';
      PINUSE='BI';
    '2':
      PIN_NUMBER='(2)';
      INPUT_LOAD='(-0.01,0.01)';
      OUTPUT_LOAD='(1.0,-1.0)';
      BIDIRECTIONAL='TRUE';
      PINUSE='BI';
  end_pin;
  body
      CLASS='IO';
      PART_NAME='Q_CRYSTAL';
      PHYS_DES_PREFIX='Y';
      STANDARD='End of Design';
      LIFECYCLE='Comp-Approve';
      PART_NUMBER='BG632768012';
      JEDEC_TYPE='X_2S_XTL721';
      DESCRIPTION='CRYSTAL SMD 32.768KHZ(+-20PPM,12.5PF)';
      COMPONENT_TYPE='SMTOTHER';
      LEAD_LENGTH='';
      DAY='20141103';
      PARENT_PART_TYPE='Q_CRYSTAL';
      PARENT_PPT='Q_CRYSTAL';
      PARENT_PPT_PART='Q_CRYSTAL_SMLF-32.768KHZ,EMPTY,BG632768012';
  end_body;
end_primitive;
primitive 'Q_CRYSTAL_SMLF-32.768KHZ,IC,BG632768012';
  pin
    '1':
      PIN_NUMBER='(1)';
      INPUT_LOAD='(-0.01,0.01)';
      OUTPUT_LOAD='(1.0,-1.0)';
      BIDIRECTIONAL='TRUE';
      PINUSE='BI';
    '2':
      PIN_NUMBER='(2)';
      INPUT_LOAD='(-0.01,0.01)';
      OUTPUT_LOAD='(1.0,-1.0)';
      BIDIRECTIONAL='TRUE';
      PINUSE='BI';
  end_pin;
  body
      CLASS='IC';
      PART_NAME='Q_CRYSTAL';
      PHYS_DES_PREFIX='Y';
      STANDARD='End of Design';
      LIFECYCLE='Comp-Approve';
      PART_NUMBER='BG632768012';
      JEDEC_TYPE='X_2S_XTL721';
      DESCRIPTION='CRYSTAL SMD 32.768KHZ(+-20PPM,12.5PF)';
      COMPONENT_TYPE='SMTOTHER';
      LEAD_LENGTH='';
      DAY='20141103';
      PARENT_PART_TYPE='Q_CRYSTAL';
      PARENT_PPT='Q_CRYSTAL';
      PARENT_PPT_PART='Q_CRYSTAL_SMLF-32.768KHZ,IC,BG632768012';
  end_body;
end_primitive;
primitive 'Q_FUSE_SMLF-20A/125V,IC,DKK00XFU000';
  pin
    '1':
      PIN_NUMBER='(1)';
      INPUT_LOAD='(-0.01,0.01)';
      OUTPUT_LOAD='(1.0,-1.0)';
      BIDIRECTIONAL='TRUE';
      PINUSE='BI';
    '2':
      PIN_NUMBER='(2)';
      INPUT_LOAD='(-0.01,0.01)';
      OUTPUT_LOAD='(1.0,-1.0)';
      BIDIRECTIONAL='TRUE';
      PINUSE='BI';
  end_pin;
  body
      CLASS='IC';
      PART_NAME='Q_FUSE';
      PHYS_DES_PREFIX='FS';
      STANDARD='';
      LIFECYCLE='';
      PART_NUMBER='DKK00XFU000';
      JEDEC_TYPE='F4012';
      DESCRIPTION='FUSE SMD 20A/125V(FAST,UL/CSA)';
      COMPONENT_TYPE='CHIP';
      LEAD_LENGTH='';
      LPID='';
      DAY='20211207';
      PARENT_PART_TYPE='Q_FUSE';
      PARENT_PPT='Q_FUSE';
      PARENT_PPT_PART='Q_FUSE_SMLF-20A/125V,IC,DKK00XFU000';
  end_body;
end_primitive;
primitive 'Q_INDUCTOR4P_14-150NH,SMLF,IND,CV+15^0TZ04';
  pin
    '2':
      PIN_NUMBER='(2)';
      BIDIRECTIONAL='TRUE';
      INPUT_LOAD='(-0.01,0.01)';
      OUTPUT_LOAD='(1.0,-1.0)';
      PINUSE='BI';
    '3':
      PIN_NUMBER='(3)';
      BIDIRECTIONAL='TRUE';
      INPUT_LOAD='(-0.01,0.01)';
      OUTPUT_LOAD='(1.0,-1.0)';
      PINUSE='BI';
    '4':
      PIN_NUMBER='(4)';
      BIDIRECTIONAL='TRUE';
      INPUT_LOAD='(-0.01,0.01)';
      OUTPUT_LOAD='(1.0,-1.0)';
      PINUSE='BI';
    '1':
      PIN_NUMBER='(1)';
      BIDIRECTIONAL='TRUE';
      INPUT_LOAD='(-0.01,0.01)';
      OUTPUT_LOAD='(1.0,-1.0)';
      PINUSE='BI';
  end_pin;
  body
      PART_NAME='Q_INDUCTOR4P_14';
      BODY_NAME='Q_INDUCTOR4P_14';
      PHYS_DES_PREFIX='L';
      CLASS='DISCRETE';
      STANDARD='End of Design';
      LIFECYCLE='Comp-Approve';
      PART_NUMBER='CV+15^0TZ04';
      JEDEC_TYPE='L_TLM117513Q-151QL_11X7-5XA';
      CURRENT='82A';
      DESCRIPTION='IND SMD 150NH 15% 82A(PGL6303.151HLT)';
      MANUFTR='PLE';
      MANUF_PN='PGL6303.151HLT';
      RD_CMPLS_LVL='EP(V1)';
      CMPLS_LVL='';
      DIP_SMD='';
      FROM_PJ='S6X-KIMI';
      DATA='PLE_PGL6303.151HLT.pdf';
      FP_ECN='';
      EE_CHECK_LIST='';
      STATUS='';
      PREFERENCE='';
      NOT_INSERT='';
      DAY='20201026';
      PARENT_PART_TYPE='Q_INDUCTOR4P_14';
      PARENT_PPT='Q_INDUCTOR4P_14';
      PARENT_PPT_PART='Q_INDUCTOR4P_14-150NH,SMLF,IND,CV+15^0TZ04';
  end_body;
end_primitive;
primitive 'Q_INDUCTOR_SMLF-0.22UH/33A,IND,CV+22Y0EZ00';
  pin
    '2':
      PIN_NUMBER='(2)';
      BIDIRECTIONAL='TRUE';
      INPUT_LOAD='(-0.01,0.01)';
      OUTPUT_LOAD='(1.0,-1.0)';
      PINUSE='BI';
    '1':
      PIN_NUMBER='(1)';
      BIDIRECTIONAL='TRUE';
      INPUT_LOAD='(-0.01,0.01)';
      OUTPUT_LOAD='(1.0,-1.0)';
      PINUSE='BI';
  end_pin;
  body
      PART_NAME='Q_INDUCTOR';
      BODY_NAME='Q_INDUCTOR';
      PHYS_DES_PREFIX='L';
      CLASS='DISCRETE';
      STANDARD='';
      LIFECYCLE='';
      PART_NUMBER='CV+22Y0EZ00';
      JEDEC_TYPE='L_VLBU6565100T-R12L-1_6-5X6-5';
      VALUE='0.22UH/33A';
      DESCRIPTION='IND SMD 0.22UH 15% 33A(HCME656510Q-221QL';
      COMPONENT_TYPE='CHIP';
      LEAD_LENGTH='';
      LPID='';
      DAY='20210928';
      PARENT_PART_TYPE='Q_INDUCTOR';
      PARENT_PPT='Q_INDUCTOR';
      PARENT_PPT_PART='Q_INDUCTOR_SMLF-0.22UH/33A,IND,CV+22Y0EZ00';
  end_body;
end_primitive;
primitive 'Q_INDUCTOR_SMLF-1.0UH/18A,IND,CV-10I0MZ01';
  pin
    '2':
      PIN_NUMBER='(2)';
      BIDIRECTIONAL='TRUE';
      INPUT_LOAD='(-0.01,0.01)';
      OUTPUT_LOAD='(1.0,-1.0)';
      PINUSE='BI';
    '1':
      PIN_NUMBER='(1)';
      BIDIRECTIONAL='TRUE';
      INPUT_LOAD='(-0.01,0.01)';
      OUTPUT_LOAD='(1.0,-1.0)';
      PINUSE='BI';
  end_pin;
  body
      PART_NAME='Q_INDUCTOR';
      BODY_NAME='Q_INDUCTOR';
      PHYS_DES_PREFIX='L';
      CLASS='DISCRETE';
      STANDARD='';
      LIFECYCLE='';
      PART_NUMBER='CV-10I0MZ01';
      JEDEC_TYPE='L_PCMC104T';
      VALUE='1.0UH/18A';
      DESCRIPTION='IND SMD 1.0UH +-20% 18A(PCMC104T-1R0MN)';
      COMPONENT_TYPE='CHIP';
      LEAD_LENGTH='';
      LPID='';
      DAY='20130806';
      PARENT_PART_TYPE='Q_INDUCTOR';
      PARENT_PPT='Q_INDUCTOR';
      PARENT_PPT_PART='Q_INDUCTOR_SMLF-1.0UH/18A,IND,CV-10I0MZ01';
  end_body;
end_primitive;
primitive 'Q_INDUCTOR_SMLF-1.5UH,IND,CV-15I0MZ28';
  pin
    '2':
      PIN_NUMBER='(2)';
      BIDIRECTIONAL='TRUE';
      INPUT_LOAD='(-0.01,0.01)';
      OUTPUT_LOAD='(1.0,-1.0)';
      PINUSE='BI';
    '1':
      PIN_NUMBER='(1)';
      BIDIRECTIONAL='TRUE';
      INPUT_LOAD='(-0.01,0.01)';
      OUTPUT_LOAD='(1.0,-1.0)';
      PINUSE='BI';
  end_pin;
  body
      PART_NAME='Q_INDUCTOR';
      BODY_NAME='Q_INDUCTOR';
      PHYS_DES_PREFIX='L';
      CLASS='DISCRETE';
      STANDARD='';
      LIFECYCLE='';
      PART_NUMBER='CV-15I0MZ28';
      JEDEC_TYPE='L_PCMC063T';
      VALUE='1.5UH';
      DESCRIPTION='IND SMD 1.5UH+-20% 18A(PCMC063T-1R5MN)';
      COMPONENT_TYPE='CHIP';
      LEAD_LENGTH='';
      LPID='';
      DAY='20110221';
      PARENT_PART_TYPE='Q_INDUCTOR';
      PARENT_PPT='Q_INDUCTOR';
      PARENT_PPT_PART='Q_INDUCTOR_SMLF-1.5UH,IND,CV-15I0MZ28';
  end_body;
end_primitive;
primitive 'Q_INDUCTOR_SMLF-1.5UH/53A,IND,CV-15^0MZ02';
  pin
    '2':
      PIN_NUMBER='(2)';
      BIDIRECTIONAL='TRUE';
      INPUT_LOAD='(-0.01,0.01)';
      OUTPUT_LOAD='(1.0,-1.0)';
      PINUSE='BI';
    '1':
      PIN_NUMBER='(1)';
      BIDIRECTIONAL='TRUE';
      INPUT_LOAD='(-0.01,0.01)';
      OUTPUT_LOAD='(1.0,-1.0)';
      PINUSE='BI';
  end_pin;
  body
      PART_NAME='Q_INDUCTOR';
      BODY_NAME='Q_INDUCTOR';
      PHYS_DES_PREFIX='L';
      CLASS='DISCRETE';
      STANDARD='';
      LIFECYCLE='';
      PART_NUMBER='CV-15^0MZ02';
      JEDEC_TYPE='L_EM-15AM17VG1-QS_14-3X12-9';
      VALUE='1.5UH/53A';
      DESCRIPTION='IND SMD 1.5UH 20% 53A(EM-15AM17VG1-QS)';
      COMPONENT_TYPE='CHIP';
      LEAD_LENGTH='';
      LPID='';
      DAY='20201030';
      PARENT_PART_TYPE='Q_INDUCTOR';
      PARENT_PPT='Q_INDUCTOR';
      PARENT_PPT_PART='Q_INDUCTOR_SMLF-1.5UH/53A,IND,CV-15^0MZ02';
  end_body;
end_primitive;
primitive 'Q_INDUCTOR_SMLF-100NH/16A,IND,CV+10G0MZ04';
  pin
    '2':
      PIN_NUMBER='(2)';
      BIDIRECTIONAL='TRUE';
      INPUT_LOAD='(-0.01,0.01)';
      OUTPUT_LOAD='(1.0,-1.0)';
      PINUSE='BI';
    '1':
      PIN_NUMBER='(1)';
      BIDIRECTIONAL='TRUE';
      INPUT_LOAD='(-0.01,0.01)';
      OUTPUT_LOAD='(1.0,-1.0)';
      PINUSE='BI';
  end_pin;
  body
      PART_NAME='Q_INDUCTOR';
      BODY_NAME='Q_INDUCTOR';
      PHYS_DES_PREFIX='L';
      CLASS='DISCRETE';
      STANDARD='';
      LIFECYCLE='';
      PART_NUMBER='CV+10G0MZ04';
      JEDEC_TYPE='L_HCBS4545_4-5X4-5';
      VALUE='100NH/16A';
      DESCRIPTION='IND SMD 100NH 20% 16A(HCBS4545-101)';
      COMPONENT_TYPE='CHIP';
      LEAD_LENGTH='';
      LPID='';
      DAY='20150715';
      PARENT_PART_TYPE='Q_INDUCTOR';
      PARENT_PPT='Q_INDUCTOR';
      PARENT_PPT_PART='Q_INDUCTOR_SMLF-100NH/16A,IND,CV+10G0MZ04';
  end_body;
end_primitive;
primitive 'Q_INDUCTOR_SMLF-120NH/69A,IND,CV+12^0EZ03';
  pin
    '2':
      PIN_NUMBER='(2)';
      BIDIRECTIONAL='TRUE';
      INPUT_LOAD='(-0.01,0.01)';
      OUTPUT_LOAD='(1.0,-1.0)';
      PINUSE='BI';
    '1':
      PIN_NUMBER='(1)';
      BIDIRECTIONAL='TRUE';
      INPUT_LOAD='(-0.01,0.01)';
      OUTPUT_LOAD='(1.0,-1.0)';
      PINUSE='BI';
  end_pin;
  body
      PART_NAME='Q_INDUCTOR';
      BODY_NAME='Q_INDUCTOR';
      PHYS_DES_PREFIX='L';
      CLASS='DISCRETE';
      STANDARD='';
      LIFECYCLE='';
      PART_NUMBER='CV+12^0EZ03';
      JEDEC_TYPE='L_VLBU6565100T-R12L-1_6-5X6-5';
      VALUE='120NH/69A';
      DESCRIPTION='IND SMD 120NH 15% 69A(PGL6312.121AHLT)';
      COMPONENT_TYPE='CHIP';
      LEAD_LENGTH='';
      LPID='';
      DAY='20201109';
      PARENT_PART_TYPE='Q_INDUCTOR';
      PARENT_PPT='Q_INDUCTOR';
      PARENT_PPT_PART='Q_INDUCTOR_SMLF-120NH/69A,IND,CV+12^0EZ03';
  end_body;
end_primitive;
primitive 'Q_INDUCTOR_SMLF-1UH,IND,CV-10U0MZ01';
  pin
    '2':
      PIN_NUMBER='(2)';
      BIDIRECTIONAL='TRUE';
      INPUT_LOAD='(-0.01,0.01)';
      OUTPUT_LOAD='(1.0,-1.0)';
      PINUSE='BI';
    '1':
      PIN_NUMBER='(1)';
      BIDIRECTIONAL='TRUE';
      INPUT_LOAD='(-0.01,0.01)';
      OUTPUT_LOAD='(1.0,-1.0)';
      PINUSE='BI';
  end_pin;
  body
      PART_NAME='Q_INDUCTOR';
      BODY_NAME='Q_INDUCTOR';
      PHYS_DES_PREFIX='L';
      CLASS='DISCRETE';
      STANDARD='';
      LIFECYCLE='';
      PART_NUMBER='CV-10U0MZ01';
      JEDEC_TYPE='L_PCMC135T';
      VALUE='1UH';
      DESCRIPTION='IND SMD 1UH +-20% 29A(PCMC135T-1R0MF)';
      COMPONENT_TYPE='CHIP';
      LEAD_LENGTH='';
      LPID='';
      DAY='20110221';
      PARENT_PART_TYPE='Q_INDUCTOR';
      PARENT_PPT='Q_INDUCTOR';
      PARENT_PPT_PART='Q_INDUCTOR_SMLF-1UH,IND,CV-10U0MZ01';
  end_body;
end_primitive;
primitive 'Q_INDUCTOR_SMLF-2.2UH,IND,CV-2280MZ15';
  pin
    '2':
      PIN_NUMBER='(2)';
      BIDIRECTIONAL='TRUE';
      INPUT_LOAD='(-0.01,0.01)';
      OUTPUT_LOAD='(1.0,-1.0)';
      PINUSE='BI';
    '1':
      PIN_NUMBER='(1)';
      BIDIRECTIONAL='TRUE';
      INPUT_LOAD='(-0.01,0.01)';
      OUTPUT_LOAD='(1.0,-1.0)';
      PINUSE='BI';
  end_pin;
  body
      PART_NAME='Q_INDUCTOR';
      BODY_NAME='Q_INDUCTOR';
      PHYS_DES_PREFIX='L';
      CLASS='DISCRETE';
      STANDARD='';
      LIFECYCLE='';
      PART_NUMBER='CV-2280MZ15';
      JEDEC_TYPE='L_PCMC063T';
      VALUE='2.2UH';
      DESCRIPTION='IND SMD 2.2UH +-20% 8A(PCMC063T-2R2MN)';
      COMPONENT_TYPE='CHIP';
      LEAD_LENGTH='';
      LPID='';
      DAY='20110221';
      PARENT_PART_TYPE='Q_INDUCTOR';
      PARENT_PPT='Q_INDUCTOR';
      PARENT_PPT_PART='Q_INDUCTOR_SMLF-2.2UH,IND,CV-2280MZ15';
  end_body;
end_primitive;
primitive 'Q_INDUCTOR_SMLF-3.3UH/6A,IND,CV-3360MZ07';
  pin
    '2':
      PIN_NUMBER='(2)';
      BIDIRECTIONAL='TRUE';
      INPUT_LOAD='(-0.01,0.01)';
      OUTPUT_LOAD='(1.0,-1.0)';
      PINUSE='BI';
    '1':
      PIN_NUMBER='(1)';
      BIDIRECTIONAL='TRUE';
      INPUT_LOAD='(-0.01,0.01)';
      OUTPUT_LOAD='(1.0,-1.0)';
      PINUSE='BI';
  end_pin;
  body
      PART_NAME='Q_INDUCTOR';
      BODY_NAME='Q_INDUCTOR';
      PHYS_DES_PREFIX='L';
      CLASS='DISCRETE';
      STANDARD='';
      LIFECYCLE='';
      PART_NUMBER='CV-3360MZ07';
      JEDEC_TYPE='L_PCMC063T';
      VALUE='3.3UH/6A';
      DESCRIPTION='IND SMD 3.3UH,6A20%(PCMC063T-3R3MN)';
      COMPONENT_TYPE='CHIP';
      LEAD_LENGTH='';
      LPID='';
      DAY='20120921';
      PARENT_PART_TYPE='Q_INDUCTOR';
      PARENT_PPT='Q_INDUCTOR';
      PARENT_PPT_PART='Q_INDUCTOR_SMLF-3.3UH/6A,IND,CV-3360MZ07';
  end_body;
end_primitive;
primitive 'Q_INDUCTOR_SMLF-4.7UH,IND,CV-47A0MZ10';
  pin
    '2':
      PIN_NUMBER='(2)';
      BIDIRECTIONAL='TRUE';
      INPUT_LOAD='(-0.01,0.01)';
      OUTPUT_LOAD='(1.0,-1.0)';
      PINUSE='BI';
    '1':
      PIN_NUMBER='(1)';
      BIDIRECTIONAL='TRUE';
      INPUT_LOAD='(-0.01,0.01)';
      OUTPUT_LOAD='(1.0,-1.0)';
      PINUSE='BI';
  end_pin;
  body
      PART_NAME='Q_INDUCTOR';
      BODY_NAME='Q_INDUCTOR';
      PHYS_DES_PREFIX='L';
      CLASS='DISCRETE';
      STANDARD='';
      LIFECYCLE='';
      PART_NUMBER='CV-47A0MZ10';
      JEDEC_TYPE='L_PCMB104EXB';
      VALUE='4.7UH';
      DESCRIPTION='IND SMD 4.7UH +-20% 10A(PCMB104E-4R7MS)';
      COMPONENT_TYPE='CHIP';
      LEAD_LENGTH='';
      LPID='';
      DAY='20110221';
      PARENT_PART_TYPE='Q_INDUCTOR';
      PARENT_PPT='Q_INDUCTOR';
      PARENT_PPT_PART='Q_INDUCTOR_SMLF-4.7UH,IND,CV-47A0MZ10';
  end_body;
end_primitive;
primitive 'Q_INDUCTOR_SMLF-50NH/86A,IND,CVA50^0MZ09';
  pin
    '2':
      PIN_NUMBER='(2)';
      BIDIRECTIONAL='TRUE';
      INPUT_LOAD='(-0.01,0.01)';
      OUTPUT_LOAD='(1.0,-1.0)';
      PINUSE='BI';
    '1':
      PIN_NUMBER='(1)';
      BIDIRECTIONAL='TRUE';
      INPUT_LOAD='(-0.01,0.01)';
      OUTPUT_LOAD='(1.0,-1.0)';
      PINUSE='BI';
  end_pin;
  body
      PART_NAME='Q_INDUCTOR';
      BODY_NAME='Q_INDUCTOR';
      PHYS_DES_PREFIX='L';
      CLASS='DISCRETE';
      STANDARD='End of Design';
      LIFECYCLE='Comp-Approve';
      PART_NUMBER='CVA50^0MZ09';
      JEDEC_TYPE='L_MSI-600607_6-1X6';
      VALUE='50NH/86A';
      DESCRIPTION='IND SMD 50NH 20% 86A(PG2292.500HLT)';
      COMPONENT_TYPE='CHIP';
      LEAD_LENGTH='';
      LPID='';
      DAY='20200727';
      PARENT_PART_TYPE='Q_INDUCTOR';
      PARENT_PPT='Q_INDUCTOR';
      PARENT_PPT_PART='Q_INDUCTOR_SMLF-50NH/86A,IND,CVA50^0MZ09';
  end_body;
end_primitive;
primitive 'Q_INDUCTOR_SMLF-90NH/155A,IND,CVA90^0KZ13';
  pin
    '2':
      PIN_NUMBER='(2)';
      BIDIRECTIONAL='TRUE';
      INPUT_LOAD='(-0.01,0.01)';
      OUTPUT_LOAD='(1.0,-1.0)';
      PINUSE='BI';
    '1':
      PIN_NUMBER='(1)';
      BIDIRECTIONAL='TRUE';
      INPUT_LOAD='(-0.01,0.01)';
      OUTPUT_LOAD='(1.0,-1.0)';
      PINUSE='BI';
  end_pin;
  body
      PART_NAME='Q_INDUCTOR';
      BODY_NAME='Q_INDUCTOR';
      PHYS_DES_PREFIX='L';
      CLASS='DISCRETE';
      STANDARD='End of Design';
      LIFECYCLE='Comp-Approve';
      PART_NUMBER='CVA90^0KZ13';
      JEDEC_TYPE='L_HCME107512Q-900QL_10X7-7';
      VALUE='90NH/155A';
      DESCRIPTION='IND SMD 90NH 10% 155A(PG2323.900HLT)';
      COMPONENT_TYPE='CHIP';
      LEAD_LENGTH='';
      LPID='';
      DAY='20210923';
      PARENT_PART_TYPE='Q_INDUCTOR';
      PARENT_PPT='Q_INDUCTOR';
      PARENT_PPT_PART='Q_INDUCTOR_SMLF-90NH/155A,IND,CVA90^0KZ13';
  end_body;
end_primitive;
primitive 'Q_INDUCTOR_SMLF-BLM15PD121SN1D/1300MA,IND,CX5PD121A';
  pin
    '2':
      PIN_NUMBER='(2)';
      BIDIRECTIONAL='TRUE';
      INPUT_LOAD='(-0.01,0.01)';
      OUTPUT_LOAD='(1.0,-1.0)';
      PINUSE='BI';
    '1':
      PIN_NUMBER='(1)';
      BIDIRECTIONAL='TRUE';
      INPUT_LOAD='(-0.01,0.01)';
      OUTPUT_LOAD='(1.0,-1.0)';
      PINUSE='BI';
  end_pin;
  body
      PART_NAME='Q_INDUCTOR';
      BODY_NAME='Q_INDUCTOR';
      PHYS_DES_PREFIX='L';
      CLASS='DISCRETE';
      STANDARD='';
      LIFECYCLE='';
      PART_NUMBER='CX5PD121000';
      JEDEC_TYPE='L0402';
      VALUE='BLM15PD121SN1D/1300MA';
      DESCRIPTION='EMI FILTER BLM15PD121SN1D(120OHM,1300MA)';
      COMPONENT_TYPE='CHIP';
      LEAD_LENGTH='';
      LPID='';
      DAY='20171207';
      PARENT_PART_TYPE='Q_INDUCTOR';
      PARENT_PPT='Q_INDUCTOR';
      PARENT_PPT_PART='Q_INDUCTOR_SMLF-BLM15PD121SN1D/1300MA,IND,CX5PD121000';
  end_body;
end_primitive;
primitive 'Q_INDUCTOR_SMLF-BLM18PG300SN1D ,IND,TMP_QCX8PG3000A';
  pin
    '2':
      PIN_NUMBER='(2)';
      BIDIRECTIONAL='TRUE';
      INPUT_LOAD='(-0.01,0.01)';
      OUTPUT_LOAD='(1.0,-1.0)';
      PINUSE='BI';
    '1':
      PIN_NUMBER='(1)';
      BIDIRECTIONAL='TRUE';
      INPUT_LOAD='(-0.01,0.01)';
      OUTPUT_LOAD='(1.0,-1.0)';
      PINUSE='BI';
  end_pin;
  body
      PART_NAME='Q_INDUCTOR';
      BODY_NAME='Q_INDUCTOR';
      PHYS_DES_PREFIX='L';
      CLASS='DISCRETE';
      STANDARD='';
      LIFECYCLE='';
      PART_NUMBER='CX8PG300001';
      JEDEC_TYPE='L0603';
      VALUE='BLM18PG300SN1D ';
      DESCRIPTION='EMI FILTER SBK160808T-100Y-N(10,500MA)';
      COMPONENT_TYPE='CHIP';
      LEAD_LENGTH='';
      LPID='';
      DAY='';
      PARENT_PART_TYPE='Q_INDUCTOR';
      PARENT_PPT='Q_INDUCTOR';
      PARENT_PPT_PART='Q_INDUCTOR_SMLF-BLM18PG300SN1D ,IND,TMP_QCX8PG300001';
  end_body;
end_primitive;
primitive 'Q_INDUCTOR_SMLF-BLM18SN220TN1D/8000MA,IND,CX220TN1A';
  pin
    '2':
      PIN_NUMBER='(2)';
      BIDIRECTIONAL='TRUE';
      INPUT_LOAD='(-0.01,0.01)';
      OUTPUT_LOAD='(1.0,-1.0)';
      PINUSE='BI';
    '1':
      PIN_NUMBER='(1)';
      BIDIRECTIONAL='TRUE';
      INPUT_LOAD='(-0.01,0.01)';
      OUTPUT_LOAD='(1.0,-1.0)';
      PINUSE='BI';
  end_pin;
  body
      PART_NAME='Q_INDUCTOR';
      BODY_NAME='Q_INDUCTOR';
      PHYS_DES_PREFIX='L';
      CLASS='DISCRETE';
      STANDARD='End of Design';
      LIFECYCLE='Comp-Approve';
      PART_NUMBER='CX220TN1001';
      JEDEC_TYPE='L0603';
      VALUE='BLM18SN220TN1D/8000MA';
      DESCRIPTION='EMI FILTER BLM18SN220TN1D(22,8000MA)';
      COMPONENT_TYPE='CHIP';
      LEAD_LENGTH='';
      LPID='';
      DAY='20160104';
      PARENT_PART_TYPE='Q_INDUCTOR';
      PARENT_PPT='Q_INDUCTOR';
      PARENT_PPT_PART='Q_INDUCTOR_SMLF-BLM18SN220TN1D/8000MA,IND,CX220TN1001';
  end_body;
end_primitive;
primitive 'Q_INDUCTOR_SMLF-BLM21PG221SN1D,IND,CX1PG221001';
  pin
    '2':
      PIN_NUMBER='(2)';
      BIDIRECTIONAL='TRUE';
      INPUT_LOAD='(-0.01,0.01)';
      OUTPUT_LOAD='(1.0,-1.0)';
      PINUSE='BI';
    '1':
      PIN_NUMBER='(1)';
      BIDIRECTIONAL='TRUE';
      INPUT_LOAD='(-0.01,0.01)';
      OUTPUT_LOAD='(1.0,-1.0)';
      PINUSE='BI';
  end_pin;
  body
      PART_NAME='Q_INDUCTOR';
      BODY_NAME='Q_INDUCTOR';
      PHYS_DES_PREFIX='L';
      CLASS='DISCRETE';
      STANDARD='End of Design';
      LIFECYCLE='Comp-Approve';
      PART_NUMBER='CX1PG221001';
      JEDEC_TYPE='L0805';
      VALUE='BLM21PG221SN1D';
      DESCRIPTION='EMI FILTER BLM21PG221SN1D(220.100M.2A)';
      COMPONENT_TYPE='CHIP';
      LEAD_LENGTH='';
      LPID='';
      DAY='20120619';
      PARENT_PART_TYPE='Q_INDUCTOR';
      PARENT_PPT='Q_INDUCTOR';
      PARENT_PPT_PART='Q_INDUCTOR_SMLF-BLM21PG221SN1D,IND,CX1PG221001';
  end_body;
end_primitive;
primitive 'Q_INDUCTOR_SMLF-BLM21SN300SN1D/5A,IND,CX300SN1000';
  pin
    '2':
      PIN_NUMBER='(2)';
      BIDIRECTIONAL='TRUE';
      INPUT_LOAD='(-0.01,0.01)';
      OUTPUT_LOAD='(1.0,-1.0)';
      PINUSE='BI';
    '1':
      PIN_NUMBER='(1)';
      BIDIRECTIONAL='TRUE';
      INPUT_LOAD='(-0.01,0.01)';
      OUTPUT_LOAD='(1.0,-1.0)';
      PINUSE='BI';
  end_pin;
  body
      PART_NAME='Q_INDUCTOR';
      BODY_NAME='Q_INDUCTOR';
      PHYS_DES_PREFIX='L';
      CLASS='DISCRETE';
      STANDARD='';
      LIFECYCLE='';
      PART_NUMBER='CX300SN1000';
      JEDEC_TYPE='L0805';
      VALUE='BLM21SN300SN1D/5A';
      DESCRIPTION='EMI FILTER BLM21SN300SN1D(30,8.5A)';
      COMPONENT_TYPE='CHIP';
      LEAD_LENGTH='';
      LPID='';
      DAY='20221019';
      PARENT_PART_TYPE='Q_INDUCTOR';
      PARENT_PPT='Q_INDUCTOR';
      PARENT_PPT_PART='Q_INDUCTOR_SMLF-BLM21SN300SN1D/5A,IND,CX300SN1000';
  end_body;
end_primitive;
primitive 'Q_INDUCTOR_SMLF-FCM2012KF-601T/0.5A,IND,CX601T05003';
  pin
    '2':
      PIN_NUMBER='(2)';
      BIDIRECTIONAL='TRUE';
      INPUT_LOAD='(-0.01,0.01)';
      OUTPUT_LOAD='(1.0,-1.0)';
      PINUSE='BI';
    '1':
      PIN_NUMBER='(1)';
      BIDIRECTIONAL='TRUE';
      INPUT_LOAD='(-0.01,0.01)';
      OUTPUT_LOAD='(1.0,-1.0)';
      PINUSE='BI';
  end_pin;
  body
      PART_NAME='Q_INDUCTOR';
      BODY_NAME='Q_INDUCTOR';
      PHYS_DES_PREFIX='L';
      CLASS='DISCRETE';
      STANDARD='';
      LIFECYCLE='';
      PART_NUMBER='CX601T05003';
      JEDEC_TYPE='L0805';
      VALUE='FCM2012KF-601T/0.5A';
      DESCRIPTION='EMI FILTER FCM2012KF-601T05(600,0.5A)';
      COMPONENT_TYPE='CHIP';
      LEAD_LENGTH='';
      LPID='';
      DAY='20131206';
      PARENT_PART_TYPE='Q_INDUCTOR';
      PARENT_PPT='Q_INDUCTOR';
      PARENT_PPT_PART='Q_INDUCTOR_SMLF-FCM2012KF-601T/0.5A,IND,CX601T05003';
  end_body;
end_primitive;
primitive 'Q_LED_SMLF-LED_BLUE,LTST-C281TBKT-5A,IC,BEBL0172Z00';
  pin
    'A':
      PIN_NUMBER='(A)';
      INPUT_LOAD='(-0.01,0.01)';
      OUTPUT_LOAD='(1.0,-1.0)';
      BIDIRECTIONAL='TRUE';
      PINUSE='BI';
    'C':
      PIN_NUMBER='(C)';
      INPUT_LOAD='(-0.01,0.01)';
      OUTPUT_LOAD='(1.0,-1.0)';
      BIDIRECTIONAL='TRUE';
      PINUSE='BI';
  end_pin;
  body
      CLASS='IC';
      PART_NAME='Q_LED';
      PHYS_DES_PREFIX='D';
      STANDARD='';
      LIFECYCLE='';
      PART_NUMBER='BEBL0172Z00';
      JEDEC_TYPE='LED2S_0402';
      DESCRIPTION='LED SMD(2P) BLUE(LTST-C281TBKT-5A)';
      COMPONENT_TYPE='';
      LEAD_LENGTH='';
      LPID='';
      DAY='20121120';
      PARENT_PART_TYPE='Q_LED';
      PARENT_PPT='Q_LED';
      PARENT_PPT_PART='Q_LED_SMLF-LED_BLUE,LTST-C281TBKT-5A,IC,BEBL0172Z00';
  end_body;
end_primitive;
primitive 'Q_LED_SMLF-LED_YELLOW,LTST-C190KSKT-P,IC,BEYL0159ZA';
  pin
    'A':
      PIN_NUMBER='(A)';
      INPUT_LOAD='(-0.01,0.01)';
      OUTPUT_LOAD='(1.0,-1.0)';
      BIDIRECTIONAL='TRUE';
      PINUSE='BI';
    'C':
      PIN_NUMBER='(C)';
      INPUT_LOAD='(-0.01,0.01)';
      OUTPUT_LOAD='(1.0,-1.0)';
      BIDIRECTIONAL='TRUE';
      PINUSE='BI';
  end_pin;
  body
      CLASS='IC';
      PART_NAME='Q_LED';
      PHYS_DES_PREFIX='D';
      STANDARD='';
      LIFECYCLE='';
      PART_NUMBER='BEYL0159Z00';
      JEDEC_TYPE='LED_1921XA';
      DESCRIPTION='LED SMD(2P)YELLOW(LTST-C190KSKT-P)';
      COMPONENT_TYPE='';
      LEAD_LENGTH='';
      LPID='';
      DAY='20200214';
      PARENT_PART_TYPE='Q_LED';
      PARENT_PPT='Q_LED';
      PARENT_PPT_PART='Q_LED_SMLF-LED_YELLOW,LTST-C190KSKT-P,IC,BEYL0159Z00';
  end_body;
end_primitive;
primitive 'Q_OSC4P_SMLF-50MHZ,OSC,BF650000032';
  pin
    'OE':
      PIN_NUMBER='(1)';
      INPUT_LOAD='(-0.01,0.01)';
      PINUSE='IN';
    'OUT':
      PIN_NUMBER='(3)';
      OUTPUT_LOAD='(1.0,-1.0)';
      PINUSE='OUT';
    'GND':
      PIN_NUMBER='(2)';
      PINUSE='POWER';
    'VDD':
      PIN_NUMBER='(4)';
      PINUSE='POWER';
  end_pin;
  body
      CLASS='IC';
      PART_NAME='Q_OSC4P';
      PHYS_DES_PREFIX='OSC';
      STANDARD='';
      LIFECYCLE='';
      PART_NUMBER='BF650000032';
      JEDEC_TYPE='OSC4_XP';
      DESCRIPTION='OSC SMD 50MHZ(25PPM,15PF,3.3V)FK5000023';
      COMPONENT_TYPE='SMTOTHER';
      LPID='';
      CREATEDAY='20130129';
      PARENT_PART_TYPE='Q_OSC4P';
      PARENT_PPT='Q_OSC4P';
      PARENT_PPT_PART='Q_OSC4P_SMLF-50MHZ,OSC,BF650000032';
  end_body;
end_primitive;
primitive 'Q_RES_0201LF-0,5%,1/20W,CHIP,CS00001JE10';
  pin
    'A':
      PIN_GROUP='1';
      PIN_NUMBER='(1)';
      PIN_TYPE='UNSPEC';
      PINUSE='UNSPEC';
    'B':
      PIN_GROUP='1';
      PIN_NUMBER='(2)';
      PIN_TYPE='UNSPEC';
      PINUSE='UNSPEC';
  end_pin;
  body
      PART_NAME='Q_RES';
      PHYS_DES_PREFIX='R';
      STANDARD='End of Design';
      LIFECYCLE='Comp-Approve';
      PART_NUMBER='CS00001JE10';
      JEDEC_TYPE='R0201';
      ALT_SYMBOLS='(SMR0201AW)';
      VALUE='0';
      TOL='5%';
      WATTAGE='1/20W';
      CLASS='DISCRETE';
      DESCRIPTION='RES CHIP 0 1/20W +-5% (0201)EF';
      COMPONENT_TYPE='CHIP0201';
      LEAD_LENGTH='';
      DFM_EXCLUSION='';
      DAY='20180212';
      PARENT_PART_TYPE='Q_RES';
      PARENT_PPT='Q_RES';
      PARENT_PPT_PART='Q_RES_0201LF-0,5%,1/20W,CHIP,CS00001JE10';
  end_body;
end_primitive;
primitive 'Q_RES_0201LF-10K,1%,1/20W,CHIP,CS31001FE17';
  pin
    'A':
      PIN_GROUP='1';
      PIN_NUMBER='(1)';
      PIN_TYPE='UNSPEC';
      PINUSE='UNSPEC';
    'B':
      PIN_GROUP='1';
      PIN_NUMBER='(2)';
      PIN_TYPE='UNSPEC';
      PINUSE='UNSPEC';
  end_pin;
  body
      PART_NAME='Q_RES';
      PHYS_DES_PREFIX='R';
      STANDARD='';
      LIFECYCLE='';
      PART_NUMBER='CS31001FE17';
      JEDEC_TYPE='R0201';
      ALT_SYMBOLS='(SMR0201AW)';
      VALUE='10K';
      TOL='1%';
      WATTAGE='1/20W';
      CLASS='DISCRETE';
      DESCRIPTION='RES CHIP 10K 1/20W +-1%(0201)EF';
      COMPONENT_TYPE='CHIPR0201';
      LEAD_LENGTH='';
      DFM_EXCLUSION='';
      DAY='20191004';
      PARENT_PART_TYPE='Q_RES';
      PARENT_PPT='Q_RES';
      PARENT_PPT_PART='Q_RES_0201LF-10K,1%,1/20W,CHIP,CS31001FE17';
  end_body;
end_primitive;
primitive 'Q_RES_0201LF-1K,1%,1/20W,CHIP,CS21001FE07';
  pin
    'A':
      PIN_GROUP='1';
      PIN_NUMBER='(1)';
      PIN_TYPE='UNSPEC';
      PINUSE='UNSPEC';
    'B':
      PIN_GROUP='1';
      PIN_NUMBER='(2)';
      PIN_TYPE='UNSPEC';
      PINUSE='UNSPEC';
  end_pin;
  body
      PART_NAME='Q_RES';
      PHYS_DES_PREFIX='R';
      STANDARD='';
      LIFECYCLE='';
      PART_NUMBER='CS21001FE07';
      JEDEC_TYPE='R0201';
      ALT_SYMBOLS='(SMR0201AW)';
      VALUE='1K';
      TOL='1%';
      WATTAGE='1/20W';
      CLASS='DISCRETE';
      DESCRIPTION='RES CHIP 1K 1/20W +-1%(0201)EF';
      COMPONENT_TYPE='CHIP0201';
      LEAD_LENGTH='';
      DFM_EXCLUSION='';
      DAY='20180212';
      PARENT_PART_TYPE='Q_RES';
      PARENT_PPT='Q_RES';
      PARENT_PPT_PART='Q_RES_0201LF-1K,1%,1/20W,CHIP,CS21001FE07';
  end_body;
end_primitive;
primitive 'Q_RES_0201LF-1K,1%,1/20W,EMPTY,CS21001FE07';
  pin
    'A':
      PIN_GROUP='1';
      PIN_NUMBER='(1)';
      PIN_TYPE='UNSPEC';
      PINUSE='UNSPEC';
    'B':
      PIN_GROUP='1';
      PIN_NUMBER='(2)';
      PIN_TYPE='UNSPEC';
      PINUSE='UNSPEC';
  end_pin;
  body
      PART_NAME='Q_RES';
      PHYS_DES_PREFIX='R';
      STANDARD='';
      LIFECYCLE='';
      PART_NUMBER='CS21001FE07';
      JEDEC_TYPE='R0201';
      ALT_SYMBOLS='(SMR0201AW)';
      VALUE='1K';
      TOL='1%';
      WATTAGE='1/20W';
      CLASS='IO';
      DESCRIPTION='RES CHIP 1K 1/20W +-1%(0201)EF';
      COMPONENT_TYPE='CHIP0201';
      LEAD_LENGTH='';
      DFM_EXCLUSION='';
      DAY='20180212';
      PARENT_PART_TYPE='Q_RES';
      PARENT_PPT='Q_RES';
      PARENT_PPT_PART='Q_RES_0201LF-1K,1%,1/20W,EMPTY,CS21001FE07';
  end_body;
end_primitive;
primitive 'Q_RES_0201LF-200,1%,1/20W,CHIP,CS12001FE12';
  pin
    'A':
      PIN_GROUP='1';
      PIN_NUMBER='(1)';
      PIN_TYPE='UNSPEC';
      PINUSE='UNSPEC';
    'B':
      PIN_GROUP='1';
      PIN_NUMBER='(2)';
      PIN_TYPE='UNSPEC';
      PINUSE='UNSPEC';
  end_pin;
  body
      PART_NAME='Q_RES';
      PHYS_DES_PREFIX='R';
      STANDARD='';
      LIFECYCLE='';
      PART_NUMBER='CS12001FE12';
      JEDEC_TYPE='R0201';
      ALT_SYMBOLS='(SMR0201AW)';
      VALUE='200';
      TOL='1%';
      WATTAGE='1/20W';
      CLASS='DISCRETE';
      DESCRIPTION='RES CHIP 200 1/20W +-1%(0201)EF';
      COMPONENT_TYPE='CHIPR0201';
      LEAD_LENGTH='';
      DFM_EXCLUSION='';
      DAY='20221202';
      PARENT_PART_TYPE='Q_RES';
      PARENT_PPT='Q_RES';
      PARENT_PPT_PART='Q_RES_0201LF-200,1%,1/20W,CHIP,CS12001FE12';
  end_body;
end_primitive;
primitive 'Q_RES_0201LF-20K,1%,1/20W,CHIP,CS32001FE00';
  pin
    'A':
      PIN_GROUP='1';
      PIN_NUMBER='(1)';
      PIN_TYPE='UNSPEC';
      PINUSE='UNSPEC';
    'B':
      PIN_GROUP='1';
      PIN_NUMBER='(2)';
      PIN_TYPE='UNSPEC';
      PINUSE='UNSPEC';
  end_pin;
  body
      PART_NAME='Q_RES';
      PHYS_DES_PREFIX='R';
      STANDARD='';
      LIFECYCLE='';
      PART_NUMBER='CS32001FE00';
      JEDEC_TYPE='R0201';
      ALT_SYMBOLS='(SMR0201AW)';
      VALUE='20K';
      TOL='1%';
      WATTAGE='1/20W';
      CLASS='DISCRETE';
      DESCRIPTION='RES CHIP 20K 1/20W +-1%(0201)';
      COMPONENT_TYPE='CHIPR0201';
      LEAD_LENGTH='';
      DFM_EXCLUSION='';
      DAY='20180806';
      PARENT_PART_TYPE='Q_RES';
      PARENT_PPT='Q_RES';
      PARENT_PPT_PART='Q_RES_0201LF-20K,1%,1/20W,CHIP,CS32001FE00';
  end_body;
end_primitive;
primitive 'Q_RES_0201LF-22,1%,1/20W,CHIP,CS02201FE11';
  pin
    'A':
      PIN_GROUP='1';
      PIN_NUMBER='(1)';
      PIN_TYPE='UNSPEC';
      PINUSE='UNSPEC';
    'B':
      PIN_GROUP='1';
      PIN_NUMBER='(2)';
      PIN_TYPE='UNSPEC';
      PINUSE='UNSPEC';
  end_pin;
  body
      PART_NAME='Q_RES';
      PHYS_DES_PREFIX='R';
      STANDARD='';
      LIFECYCLE='';
      PART_NUMBER='CS02201FE11';
      JEDEC_TYPE='R0201';
      ALT_SYMBOLS='(SMR0201AW)';
      VALUE='22';
      TOL='1%';
      WATTAGE='1/20W';
      CLASS='DISCRETE';
      DESCRIPTION='RES CHIP 22 1/20W +-1%(0201)EF';
      COMPONENT_TYPE='CHIPR0201';
      LEAD_LENGTH='';
      DFM_EXCLUSION='';
      DAY='20230530';
      PARENT_PART_TYPE='Q_RES';
      PARENT_PPT='Q_RES';
      PARENT_PPT_PART='Q_RES_0201LF-22,1%,1/20W,CHIP,CS02201FE11';
  end_body;
end_primitive;
primitive 'Q_RES_0201LF-33.2,1%,1/20W,CHIP,CS03321FE09';
  pin
    'A':
      PIN_GROUP='1';
      PIN_NUMBER='(1)';
      PIN_TYPE='UNSPEC';
      PINUSE='UNSPEC';
    'B':
      PIN_GROUP='1';
      PIN_NUMBER='(2)';
      PIN_TYPE='UNSPEC';
      PINUSE='UNSPEC';
  end_pin;
  body
      PART_NAME='Q_RES';
      PHYS_DES_PREFIX='R';
      STANDARD='';
      LIFECYCLE='';
      PART_NUMBER='CS03321FE09';
      JEDEC_TYPE='R0201';
      ALT_SYMBOLS='(SMR0201AW)';
      VALUE='33.2';
      TOL='1%';
      WATTAGE='1/20W';
      CLASS='DISCRETE';
      DESCRIPTION='RES CHIP 33.2 1/20W +-1%(0201)EF';
      COMPONENT_TYPE='CHIPR0201';
      LEAD_LENGTH='';
      DFM_EXCLUSION='';
      DAY='20221202';
      PARENT_PART_TYPE='Q_RES';
      PARENT_PPT='Q_RES';
      PARENT_PPT_PART='Q_RES_0201LF-33.2,1%,1/20W,CHIP,CS03321FE09';
  end_body;
end_primitive;
primitive 'Q_RES_0201LF-4.7K,5%,1/20W,CHIP,CS24701JE04';
  pin
    'A':
      PIN_GROUP='1';
      PIN_NUMBER='(1)';
      PIN_TYPE='UNSPEC';
      PINUSE='UNSPEC';
    'B':
      PIN_GROUP='1';
      PIN_NUMBER='(2)';
      PIN_TYPE='UNSPEC';
      PINUSE='UNSPEC';
  end_pin;
  body
      PART_NAME='Q_RES';
      PHYS_DES_PREFIX='R';
      STANDARD='End of Design';
      LIFECYCLE='Comp-Approve';
      PART_NUMBER='CS24701JE04';
      JEDEC_TYPE='R0201';
      ALT_SYMBOLS='(SMR0201AW)';
      VALUE='4.7K';
      TOL='5%';
      WATTAGE='1/20W';
      CLASS='DISCRETE';
      DESCRIPTION='RES CHIP 4.7K 1/20W +-5%(0201)EF';
      COMPONENT_TYPE='CHIPR0201';
      LEAD_LENGTH='';
      DFM_EXCLUSION='';
      DAY='20191008';
      PARENT_PART_TYPE='Q_RES';
      PARENT_PPT='Q_RES';
      PARENT_PPT_PART='Q_RES_0201LF-4.7K,5%,1/20W,CHIP,CS24701JE04';
  end_body;
end_primitive;
primitive 'Q_RES_0201LF-4.7K,5%,1/20W,EMPTY,CS24701JE04';
  pin
    'A':
      PIN_GROUP='1';
      PIN_NUMBER='(1)';
      PIN_TYPE='UNSPEC';
      PINUSE='UNSPEC';
    'B':
      PIN_GROUP='1';
      PIN_NUMBER='(2)';
      PIN_TYPE='UNSPEC';
      PINUSE='UNSPEC';
  end_pin;
  body
      PART_NAME='Q_RES';
      PHYS_DES_PREFIX='R';
      STANDARD='End of Design';
      LIFECYCLE='Comp-Approve';
      PART_NUMBER='CS24701JE04';
      JEDEC_TYPE='R0201';
      ALT_SYMBOLS='(SMR0201AW)';
      VALUE='4.7K';
      TOL='5%';
      WATTAGE='1/20W';
      CLASS='IO';
      DESCRIPTION='RES CHIP 4.7K 1/20W +-5%(0201)EF';
      COMPONENT_TYPE='CHIPR0201';
      LEAD_LENGTH='';
      DFM_EXCLUSION='';
      DAY='20191008';
      PARENT_PART_TYPE='Q_RES';
      PARENT_PPT='Q_RES';
      PARENT_PPT_PART='Q_RES_0201LF-4.7K,5%,1/20W,EMPTY,CS24701JE04';
  end_body;
end_primitive;
primitive 'Q_RES_0201LF-49.9,1%,1/20W,CHIP,CS04991FE06';
  pin
    'A':
      PIN_GROUP='1';
      PIN_NUMBER='(1)';
      PIN_TYPE='UNSPEC';
      PINUSE='UNSPEC';
    'B':
      PIN_GROUP='1';
      PIN_NUMBER='(2)';
      PIN_TYPE='UNSPEC';
      PINUSE='UNSPEC';
  end_pin;
  body
      PART_NAME='Q_RES';
      PHYS_DES_PREFIX='R';
      STANDARD='End of Design';
      LIFECYCLE='Comp-Approve';
      PART_NUMBER='CS04991FE06';
      JEDEC_TYPE='R0201';
      ALT_SYMBOLS='(SMR0201AW)';
      VALUE='49.9';
      TOL='1%';
      WATTAGE='1/20W';
      CLASS='DISCRETE';
      DESCRIPTION='RES CHIP 49.9 1/20W +-1%(0201)EF';
      COMPONENT_TYPE='CHIPR0201';
      LEAD_LENGTH='';
      DFM_EXCLUSION='';
      DAY='20230307';
      PARENT_PART_TYPE='Q_RES';
      PARENT_PPT='Q_RES';
      PARENT_PPT_PART='Q_RES_0201LF-49.9,1%,1/20W,CHIP,CS04991FE06';
  end_body;
end_primitive;
primitive 'Q_RES_0201LF-49.9,1%,1/20W,EMPTY,CS04991FE06';
  pin
    'A':
      PIN_GROUP='1';
      PIN_NUMBER='(1)';
      PIN_TYPE='UNSPEC';
      PINUSE='UNSPEC';
    'B':
      PIN_GROUP='1';
      PIN_NUMBER='(2)';
      PIN_TYPE='UNSPEC';
      PINUSE='UNSPEC';
  end_pin;
  body
      PART_NAME='Q_RES';
      PHYS_DES_PREFIX='R';
      STANDARD='End of Design';
      LIFECYCLE='Comp-Approve';
      PART_NUMBER='CS04991FE06';
      JEDEC_TYPE='R0201';
      ALT_SYMBOLS='(SMR0201AW)';
      VALUE='49.9';
      TOL='1%';
      WATTAGE='1/20W';
      CLASS='IO';
      DESCRIPTION='RES CHIP 49.9 1/20W +-1%(0201)EF';
      COMPONENT_TYPE='CHIPR0201';
      LEAD_LENGTH='';
      DFM_EXCLUSION='';
      DAY='20230307';
      PARENT_PART_TYPE='Q_RES';
      PARENT_PPT='Q_RES';
      PARENT_PPT_PART='Q_RES_0201LF-49.9,1%,1/20W,EMPTY,CS04991FE06';
  end_body;
end_primitive;
primitive 'Q_RES_0201LF-51.1,1%,1/20W,EMPTY,CS05111FE00';
  pin
    'A':
      PIN_GROUP='1';
      PIN_NUMBER='(1)';
      PIN_TYPE='UNSPEC';
      PINUSE='UNSPEC';
    'B':
      PIN_GROUP='1';
      PIN_NUMBER='(2)';
      PIN_TYPE='UNSPEC';
      PINUSE='UNSPEC';
  end_pin;
  body
      PART_NAME='Q_RES';
      PHYS_DES_PREFIX='R';
      STANDARD='';
      LIFECYCLE='';
      PART_NUMBER='CS05111FE00';
      JEDEC_TYPE='R0201';
      ALT_SYMBOLS='(SMR0201AW)';
      VALUE='51.1';
      TOL='1%';
      WATTAGE='1/20W';
      CLASS='IO';
      DESCRIPTION='RES CHIP 51.1 1/20W +-1%(0201)';
      COMPONENT_TYPE='CHIPR0201';
      LEAD_LENGTH='';
      DFM_EXCLUSION='';
      DAY='20160725';
      PARENT_PART_TYPE='Q_RES';
      PARENT_PPT='Q_RES';
      PARENT_PPT_PART='Q_RES_0201LF-51.1,1%,1/20W,EMPTY,CS05111FE00';
  end_body;
end_primitive;
primitive 'Q_RES_0402LF-0,5%,1/16W,CHIP,CS00002JB13';
  pin
    'A':
      PIN_GROUP='1';
      PIN_NUMBER='(1)';
      PIN_TYPE='UNSPEC';
      PINUSE='UNSPEC';
    'B':
      PIN_GROUP='1';
      PIN_NUMBER='(2)';
      PIN_TYPE='UNSPEC';
      PINUSE='UNSPEC';
  end_pin;
  body
      PART_NAME='Q_RES';
      PHYS_DES_PREFIX='R';
      STANDARD='End of Design';
      LIFECYCLE='Comp-Approve';
      PART_NUMBER='CS00002JB13';
      JEDEC_TYPE='R0402';
      ALT_SYMBOLS='(R0402-0201)';
      VALUE='0';
      TOL='5%';
      WATTAGE='1/16W';
      CLASS='DISCRETE';
      DESCRIPTION='RES CHIP 0 1/16W +-5%(0402)EF';
      COMPONENT_TYPE='CHIPR0402';
      LEAD_LENGTH='';
      DFM_EXCLUSION='';
      DAY='20180208';
      PARENT_PART_TYPE='Q_RES';
      PARENT_PPT='Q_RES';
      PARENT_PPT_PART='Q_RES_0402LF-0,5%,1/16W,CHIP,CS00002JB13';
  end_body;
end_primitive;
primitive 'Q_RES_0402LF-0,5%,1/16W,EMPTY,CS00002JB13';
  pin
    'A':
      PIN_GROUP='1';
      PIN_NUMBER='(1)';
      PIN_TYPE='UNSPEC';
      PINUSE='UNSPEC';
    'B':
      PIN_GROUP='1';
      PIN_NUMBER='(2)';
      PIN_TYPE='UNSPEC';
      PINUSE='UNSPEC';
  end_pin;
  body
      PART_NAME='Q_RES';
      PHYS_DES_PREFIX='R';
      STANDARD='End of Design';
      LIFECYCLE='Comp-Approve';
      PART_NUMBER='CS00002JB13';
      JEDEC_TYPE='R0402';
      ALT_SYMBOLS='(R0402-0201)';
      VALUE='0';
      TOL='5%';
      WATTAGE='1/16W';
      CLASS='IO';
      DESCRIPTION='RES CHIP 0 1/16W +-5%(0402)EF';
      COMPONENT_TYPE='CHIPR0402';
      LEAD_LENGTH='';
      DFM_EXCLUSION='';
      DAY='20180208';
      PARENT_PART_TYPE='Q_RES';
      PARENT_PPT='Q_RES';
      PARENT_PPT_PART='Q_RES_0402LF-0,5%,1/16W,EMPTY,CS00002JB13';
  end_body;
end_primitive;
primitive 'Q_RES_0402LF-1,1%,1/16W,CHIP,CS-1002FB04';
  pin
    'A':
      PIN_GROUP='1';
      PIN_NUMBER='(1)';
      PIN_TYPE='UNSPEC';
      PINUSE='UNSPEC';
    'B':
      PIN_GROUP='1';
      PIN_NUMBER='(2)';
      PIN_TYPE='UNSPEC';
      PINUSE='UNSPEC';
  end_pin;
  body
      PART_NAME='Q_RES';
      PHYS_DES_PREFIX='R';
      STANDARD='End of Design';
      LIFECYCLE='Comp-Approve';
      PART_NUMBER='CS-1002FB04';
      JEDEC_TYPE='R0402';
      ALT_SYMBOLS='(R0402-0201)';
      VALUE='1';
      TOL='1%';
      WATTAGE='1/16W';
      CLASS='DISCRETE';
      DESCRIPTION='RES CHIP 1 1/16W +-1%(0402)EF';
      COMPONENT_TYPE='CHIPR0402';
      LEAD_LENGTH='';
      DFM_EXCLUSION='';
      DAY='20180221';
      PARENT_PART_TYPE='Q_RES';
      PARENT_PPT='Q_RES';
      PARENT_PPT_PART='Q_RES_0402LF-1,1%,1/16W,CHIP,CS-1002FB04';
  end_body;
end_primitive;
primitive 'Q_RES_0402LF-1.21K,1%,1/16W,CHIP,CS21212FB05';
  pin
    'A':
      PIN_GROUP='1';
      PIN_NUMBER='(1)';
      PIN_TYPE='UNSPEC';
      PINUSE='UNSPEC';
    'B':
      PIN_GROUP='1';
      PIN_NUMBER='(2)';
      PIN_TYPE='UNSPEC';
      PINUSE='UNSPEC';
  end_pin;
  body
      PART_NAME='Q_RES';
      PHYS_DES_PREFIX='R';
      STANDARD='End of Design';
      LIFECYCLE='Comp-Approve';
      PART_NUMBER='CS21212FB05';
      JEDEC_TYPE='R0402';
      ALT_SYMBOLS='(R0402-0201)';
      VALUE='1.21K';
      TOL='1%';
      WATTAGE='1/16W';
      CLASS='DISCRETE';
      DESCRIPTION='RES CHIP 1.21K 1/16W +-1%(0402)EF';
      COMPONENT_TYPE='CHIPR0402';
      LEAD_LENGTH='';
      DFM_EXCLUSION='';
      DAY='20180221';
      PARENT_PART_TYPE='Q_RES';
      PARENT_PPT='Q_RES';
      PARENT_PPT_PART='Q_RES_0402LF-1.21K,1%,1/16W,CHIP,CS21212FB05';
  end_body;
end_primitive;
primitive 'Q_RES_0402LF-1.33K,1%,1/16W,CHIP,CS21332FB05';
  pin
    'A':
      PIN_GROUP='1';
      PIN_NUMBER='(1)';
      PIN_TYPE='UNSPEC';
      PINUSE='UNSPEC';
    'B':
      PIN_GROUP='1';
      PIN_NUMBER='(2)';
      PIN_TYPE='UNSPEC';
      PINUSE='UNSPEC';
  end_pin;
  body
      PART_NAME='Q_RES';
      PHYS_DES_PREFIX='R';
      STANDARD='';
      LIFECYCLE='';
      PART_NUMBER='CS21332FB05';
      JEDEC_TYPE='R0402';
      ALT_SYMBOLS='(R0402-0201)';
      VALUE='1.33K';
      TOL='1%';
      WATTAGE='1/16W';
      CLASS='DISCRETE';
      DESCRIPTION='RES CHIP 1.33K 1/16W +-1%(0402)EF';
      COMPONENT_TYPE='CHIPR0402';
      LEAD_LENGTH='';
      DFM_EXCLUSION='';
      DAY='20190717';
      PARENT_PART_TYPE='Q_RES';
      PARENT_PPT='Q_RES';
      PARENT_PPT_PART='Q_RES_0402LF-1.33K,1%,1/16W,CHIP,CS21332FB05';
  end_body;
end_primitive;
primitive 'Q_RES_0402LF-1.5,1%,1/8W,EMPTY,CS-1504FB00';
  pin
    'A':
      PIN_GROUP='1';
      PIN_NUMBER='(1)';
      PIN_TYPE='UNSPEC';
      PINUSE='UNSPEC';
    'B':
      PIN_GROUP='1';
      PIN_NUMBER='(2)';
      PIN_TYPE='UNSPEC';
      PINUSE='UNSPEC';
  end_pin;
  body
      PART_NAME='Q_RES';
      PHYS_DES_PREFIX='R';
      STANDARD='';
      LIFECYCLE='';
      PART_NUMBER='CS-1504FB00';
      JEDEC_TYPE='R0402';
      ALT_SYMBOLS='(R0402-0201)';
      VALUE='1.5';
      TOL='1%';
      WATTAGE='1/8W';
      CLASS='IO';
      DESCRIPTION='RES CHIP 1.5 1/8W +-1%(0402)';
      COMPONENT_TYPE='CHIPR0402';
      LEAD_LENGTH='';
      DFM_EXCLUSION='';
      DAY='20180523';
      PARENT_PART_TYPE='Q_RES';
      PARENT_PPT='Q_RES';
      PARENT_PPT_PART='Q_RES_0402LF-1.5,1%,1/8W,EMPTY,CS-1504FB00';
  end_body;
end_primitive;
primitive 'Q_RES_0402LF-1.5K,1%,1/16W,EMPTY,CS21502FB07';
  pin
    'A':
      PIN_GROUP='1';
      PIN_NUMBER='(1)';
      PIN_TYPE='UNSPEC';
      PINUSE='UNSPEC';
    'B':
      PIN_GROUP='1';
      PIN_NUMBER='(2)';
      PIN_TYPE='UNSPEC';
      PINUSE='UNSPEC';
  end_pin;
  body
      PART_NAME='Q_RES';
      PHYS_DES_PREFIX='R';
      STANDARD='End of Design';
      LIFECYCLE='Comp-Approve';
      PART_NUMBER='CS21502FB07';
      JEDEC_TYPE='R0402';
      ALT_SYMBOLS='(R0402-0201)';
      VALUE='1.5K';
      TOL='1%';
      WATTAGE='1/16W';
      CLASS='IO';
      DESCRIPTION='RES CHIP 1.5K 1/16W +-1%(0402)EF';
      COMPONENT_TYPE='CHIPR0402';
      LEAD_LENGTH='';
      DFM_EXCLUSION='';
      DAY='20180208';
      PARENT_PART_TYPE='Q_RES';
      PARENT_PPT='Q_RES';
      PARENT_PPT_PART='Q_RES_0402LF-1.5K,1%,1/16W,EMPTY,CS21502FB07';
  end_body;
end_primitive;
primitive 'Q_RES_0402LF-1.96K,1%,1/16W,CHIP,CS21962FB05';
  pin
    'A':
      PIN_GROUP='1';
      PIN_NUMBER='(1)';
      PIN_TYPE='UNSPEC';
      PINUSE='UNSPEC';
    'B':
      PIN_GROUP='1';
      PIN_NUMBER='(2)';
      PIN_TYPE='UNSPEC';
      PINUSE='UNSPEC';
  end_pin;
  body
      PART_NAME='Q_RES';
      PHYS_DES_PREFIX='R';
      STANDARD='';
      LIFECYCLE='';
      PART_NUMBER='CS21962FB05';
      JEDEC_TYPE='R0402';
      ALT_SYMBOLS='(R0402-0201)';
      VALUE='1.96K';
      TOL='1%';
      WATTAGE='1/16W';
      CLASS='DISCRETE';
      DESCRIPTION='RES CHIP 1.96K 1/16W +-1%(0402)EF';
      COMPONENT_TYPE='CHIPR0402';
      LEAD_LENGTH='';
      DFM_EXCLUSION='';
      DAY='20220208';
      PARENT_PART_TYPE='Q_RES';
      PARENT_PPT='Q_RES';
      PARENT_PPT_PART='Q_RES_0402LF-1.96K,1%,1/16W,CHIP,CS21962FB05';
  end_body;
end_primitive;
primitive 'Q_RES_0402LF-10,1%,1/16W,CHIP,CS01002FB07';
  pin
    'A':
      PIN_GROUP='1';
      PIN_NUMBER='(1)';
      PIN_TYPE='UNSPEC';
      PINUSE='UNSPEC';
    'B':
      PIN_GROUP='1';
      PIN_NUMBER='(2)';
      PIN_TYPE='UNSPEC';
      PINUSE='UNSPEC';
  end_pin;
  body
      PART_NAME='Q_RES';
      PHYS_DES_PREFIX='R';
      STANDARD='End of Design';
      LIFECYCLE='Comp-Approve';
      PART_NUMBER='CS01002FB07';
      JEDEC_TYPE='R0402';
      ALT_SYMBOLS='(R0402-0201)';
      VALUE='10';
      TOL='1%';
      WATTAGE='1/16W';
      CLASS='DISCRETE';
      DESCRIPTION='RES CHIP 10 1/16W +-1%(0402)EF';
      COMPONENT_TYPE='CHIPR0402';
      LEAD_LENGTH='';
      DFM_EXCLUSION='';
      DAY='20180208';
      PARENT_PART_TYPE='Q_RES';
      PARENT_PPT='Q_RES';
      PARENT_PPT_PART='Q_RES_0402LF-10,1%,1/16W,CHIP,CS01002FB07';
  end_body;
end_primitive;
primitive 'Q_RES_0402LF-10,1%,1/16W,EMPTY,CS01002FB07';
  pin
    'A':
      PIN_GROUP='1';
      PIN_NUMBER='(1)';
      PIN_TYPE='UNSPEC';
      PINUSE='UNSPEC';
    'B':
      PIN_GROUP='1';
      PIN_NUMBER='(2)';
      PIN_TYPE='UNSPEC';
      PINUSE='UNSPEC';
  end_pin;
  body
      PART_NAME='Q_RES';
      PHYS_DES_PREFIX='R';
      STANDARD='End of Design';
      LIFECYCLE='Comp-Approve';
      PART_NUMBER='CS01002FB07';
      JEDEC_TYPE='R0402';
      ALT_SYMBOLS='(R0402-0201)';
      VALUE='10';
      TOL='1%';
      WATTAGE='1/16W';
      CLASS='IO';
      DESCRIPTION='RES CHIP 10 1/16W +-1%(0402)EF';
      COMPONENT_TYPE='CHIPR0402';
      LEAD_LENGTH='';
      DFM_EXCLUSION='';
      DAY='20180208';
      PARENT_PART_TYPE='Q_RES';
      PARENT_PPT='Q_RES';
      PARENT_PPT_PART='Q_RES_0402LF-10,1%,1/16W,EMPTY,CS01002FB07';
  end_body;
end_primitive;
primitive 'Q_RES_0402LF-10.5K,1%,1/16W,CHIP,CS31052FB03';
  pin
    'A':
      PIN_GROUP='1';
      PIN_NUMBER='(1)';
      PIN_TYPE='UNSPEC';
      PINUSE='UNSPEC';
    'B':
      PIN_GROUP='1';
      PIN_NUMBER='(2)';
      PIN_TYPE='UNSPEC';
      PINUSE='UNSPEC';
  end_pin;
  body
      PART_NAME='Q_RES';
      PHYS_DES_PREFIX='R';
      STANDARD='';
      LIFECYCLE='';
      PART_NUMBER='CS31052FB03';
      JEDEC_TYPE='R0402';
      ALT_SYMBOLS='(R0402-0201)';
      VALUE='10.5K';
      TOL='1%';
      WATTAGE='1/16W';
      CLASS='DISCRETE';
      DESCRIPTION='RES CHIP 10.5K 1/16W +-1%(0402)EF';
      COMPONENT_TYPE='CHIPR0402';
      LEAD_LENGTH='';
      DFM_EXCLUSION='';
      DAY='20220426';
      PARENT_PART_TYPE='Q_RES';
      PARENT_PPT='Q_RES';
      PARENT_PPT_PART='Q_RES_0402LF-10.5K,1%,1/16W,CHIP,CS31052FB03';
  end_body;
end_primitive;
primitive 'Q_RES_0402LF-100,1%,1/16W,CHIP,CS11002FB07';
  pin
    'A':
      PIN_GROUP='1';
      PIN_NUMBER='(1)';
      PIN_TYPE='UNSPEC';
      PINUSE='UNSPEC';
    'B':
      PIN_GROUP='1';
      PIN_NUMBER='(2)';
      PIN_TYPE='UNSPEC';
      PINUSE='UNSPEC';
  end_pin;
  body
      PART_NAME='Q_RES';
      PHYS_DES_PREFIX='R';
      STANDARD='End of Design';
      LIFECYCLE='Comp-Approve';
      PART_NUMBER='CS11002FB07';
      JEDEC_TYPE='R0402';
      ALT_SYMBOLS='(R0402-0201)';
      VALUE='100';
      TOL='1%';
      WATTAGE='1/16W';
      CLASS='DISCRETE';
      DESCRIPTION='RES CHIP 100 1/16W +-1%(0402)EF';
      COMPONENT_TYPE='CHIPR0402';
      LEAD_LENGTH='';
      DFM_EXCLUSION='';
      DAY='20180208';
      PARENT_PART_TYPE='Q_RES';
      PARENT_PPT='Q_RES';
      PARENT_PPT_PART='Q_RES_0402LF-100,1%,1/16W,CHIP,CS11002FB07';
  end_body;
end_primitive;
primitive 'Q_RES_0402LF-100,1%,1/16W,EMPTY,CS11002FB07';
  pin
    'A':
      PIN_GROUP='1';
      PIN_NUMBER='(1)';
      PIN_TYPE='UNSPEC';
      PINUSE='UNSPEC';
    'B':
      PIN_GROUP='1';
      PIN_NUMBER='(2)';
      PIN_TYPE='UNSPEC';
      PINUSE='UNSPEC';
  end_pin;
  body
      PART_NAME='Q_RES';
      PHYS_DES_PREFIX='R';
      STANDARD='End of Design';
      LIFECYCLE='Comp-Approve';
      PART_NUMBER='CS11002FB07';
      JEDEC_TYPE='R0402';
      ALT_SYMBOLS='(R0402-0201)';
      VALUE='100';
      TOL='1%';
      WATTAGE='1/16W';
      CLASS='IO';
      DESCRIPTION='RES CHIP 100 1/16W +-1%(0402)EF';
      COMPONENT_TYPE='CHIPR0402';
      LEAD_LENGTH='';
      DFM_EXCLUSION='';
      DAY='20180208';
      PARENT_PART_TYPE='Q_RES';
      PARENT_PPT='Q_RES';
      PARENT_PPT_PART='Q_RES_0402LF-100,1%,1/16W,EMPTY,CS11002FB07';
  end_body;
end_primitive;
primitive 'Q_RES_0402LF-100K,1%,1/16W,CHIP,CS41002FB09';
  pin
    'A':
      PIN_GROUP='1';
      PIN_NUMBER='(1)';
      PIN_TYPE='UNSPEC';
      PINUSE='UNSPEC';
    'B':
      PIN_GROUP='1';
      PIN_NUMBER='(2)';
      PIN_TYPE='UNSPEC';
      PINUSE='UNSPEC';
  end_pin;
  body
      PART_NAME='Q_RES';
      PHYS_DES_PREFIX='R';
      STANDARD='End of Design';
      LIFECYCLE='Comp-Approve';
      PART_NUMBER='CS41002FB09';
      JEDEC_TYPE='R0402';
      ALT_SYMBOLS='(R0402-0201)';
      VALUE='100K';
      TOL='1%';
      WATTAGE='1/16W';
      CLASS='DISCRETE';
      DESCRIPTION='RES CHIP 100K 1/16W +-1%(0402)EF';
      COMPONENT_TYPE='CHIPR0402';
      LEAD_LENGTH='';
      DFM_EXCLUSION='';
      DAY='20180208';
      PARENT_PART_TYPE='Q_RES';
      PARENT_PPT='Q_RES';
      PARENT_PPT_PART='Q_RES_0402LF-100K,1%,1/16W,CHIP,CS41002FB09';
  end_body;
end_primitive;
primitive 'Q_RES_0402LF-100K,1%,1/16W,EMPTY,CS41002FB09';
  pin
    'A':
      PIN_GROUP='1';
      PIN_NUMBER='(1)';
      PIN_TYPE='UNSPEC';
      PINUSE='UNSPEC';
    'B':
      PIN_GROUP='1';
      PIN_NUMBER='(2)';
      PIN_TYPE='UNSPEC';
      PINUSE='UNSPEC';
  end_pin;
  body
      PART_NAME='Q_RES';
      PHYS_DES_PREFIX='R';
      STANDARD='End of Design';
      LIFECYCLE='Comp-Approve';
      PART_NUMBER='CS41002FB09';
      JEDEC_TYPE='R0402';
      ALT_SYMBOLS='(R0402-0201)';
      VALUE='100K';
      TOL='1%';
      WATTAGE='1/16W';
      CLASS='IO';
      DESCRIPTION='RES CHIP 100K 1/16W +-1%(0402)EF';
      COMPONENT_TYPE='CHIPR0402';
      LEAD_LENGTH='';
      DFM_EXCLUSION='';
      DAY='20180208';
      PARENT_PART_TYPE='Q_RES';
      PARENT_PPT='Q_RES';
      PARENT_PPT_PART='Q_RES_0402LF-100K,1%,1/16W,EMPTY,CS41002FB09';
  end_body;
end_primitive;
primitive 'Q_RES_0402LF-10K,1%,1/16W,CHIP,CS31002FB08';
  pin
    'A':
      PIN_GROUP='1';
      PIN_NUMBER='(1)';
      PIN_TYPE='UNSPEC';
      PINUSE='UNSPEC';
    'B':
      PIN_GROUP='1';
      PIN_NUMBER='(2)';
      PIN_TYPE='UNSPEC';
      PINUSE='UNSPEC';
  end_pin;
  body
      PART_NAME='Q_RES';
      PHYS_DES_PREFIX='R';
      STANDARD='End of Design';
      LIFECYCLE='Comp-Approve';
      PART_NUMBER='CS31002FB08';
      JEDEC_TYPE='R0402';
      ALT_SYMBOLS='(R0402-0201)';
      VALUE='10K';
      TOL='1%';
      WATTAGE='1/16W';
      CLASS='DISCRETE';
      DESCRIPTION='RES CHIP 10K 1/16W +-1%(0402)EF';
      COMPONENT_TYPE='CHIPR0402';
      LEAD_LENGTH='';
      DFM_EXCLUSION='';
      DAY='20180208';
      PARENT_PART_TYPE='Q_RES';
      PARENT_PPT='Q_RES';
      PARENT_PPT_PART='Q_RES_0402LF-10K,1%,1/16W,CHIP,CS31002FB08';
  end_body;
end_primitive;
primitive 'Q_RES_0402LF-10K,1%,1/16W,EMPTY,CS31002FB08';
  pin
    'A':
      PIN_GROUP='1';
      PIN_NUMBER='(1)';
      PIN_TYPE='UNSPEC';
      PINUSE='UNSPEC';
    'B':
      PIN_GROUP='1';
      PIN_NUMBER='(2)';
      PIN_TYPE='UNSPEC';
      PINUSE='UNSPEC';
  end_pin;
  body
      PART_NAME='Q_RES';
      PHYS_DES_PREFIX='R';
      STANDARD='End of Design';
      LIFECYCLE='Comp-Approve';
      PART_NUMBER='CS31002FB08';
      JEDEC_TYPE='R0402';
      ALT_SYMBOLS='(R0402-0201)';
      VALUE='10K';
      TOL='1%';
      WATTAGE='1/16W';
      CLASS='IO';
      DESCRIPTION='RES CHIP 10K 1/16W +-1%(0402)EF';
      COMPONENT_TYPE='CHIPR0402';
      LEAD_LENGTH='';
      DFM_EXCLUSION='';
      DAY='20180208';
      PARENT_PART_TYPE='Q_RES';
      PARENT_PPT='Q_RES';
      PARENT_PPT_PART='Q_RES_0402LF-10K,1%,1/16W,EMPTY,CS31002FB08';
  end_body;
end_primitive;
primitive 'Q_RES_0402LF-10K,5%,1/16W,CHIP,CS31002JB08';
  pin
    'A':
      PIN_GROUP='1';
      PIN_NUMBER='(1)';
      PIN_TYPE='UNSPEC';
      PINUSE='UNSPEC';
    'B':
      PIN_GROUP='1';
      PIN_NUMBER='(2)';
      PIN_TYPE='UNSPEC';
      PINUSE='UNSPEC';
  end_pin;
  body
      PART_NAME='Q_RES';
      PHYS_DES_PREFIX='R';
      STANDARD='End of Design';
      LIFECYCLE='Comp-Approve';
      PART_NUMBER='CS31002JB08';
      JEDEC_TYPE='R0402';
      ALT_SYMBOLS='(R0402-0201)';
      VALUE='10K';
      TOL='5%';
      WATTAGE='1/16W';
      CLASS='DISCRETE';
      DESCRIPTION='RES CHIP 10K 1/16W +-5%(0402)EF';
      COMPONENT_TYPE='CHIPR0402';
      LEAD_LENGTH='';
      DFM_EXCLUSION='';
      DAY='20180208';
      PARENT_PART_TYPE='Q_RES';
      PARENT_PPT='Q_RES';
      PARENT_PPT_PART='Q_RES_0402LF-10K,5%,1/16W,CHIP,CS31002JB08';
  end_body;
end_primitive;
primitive 'Q_RES_0402LF-10K,5%,1/16W,EMPTY,CS31002JB08';
  pin
    'A':
      PIN_GROUP='1';
      PIN_NUMBER='(1)';
      PIN_TYPE='UNSPEC';
      PINUSE='UNSPEC';
    'B':
      PIN_GROUP='1';
      PIN_NUMBER='(2)';
      PIN_TYPE='UNSPEC';
      PINUSE='UNSPEC';
  end_pin;
  body
      PART_NAME='Q_RES';
      PHYS_DES_PREFIX='R';
      STANDARD='End of Design';
      LIFECYCLE='Comp-Approve';
      PART_NUMBER='CS31002JB08';
      JEDEC_TYPE='R0402';
      ALT_SYMBOLS='(R0402-0201)';
      VALUE='10K';
      TOL='5%';
      WATTAGE='1/16W';
      CLASS='IO';
      DESCRIPTION='RES CHIP 10K 1/16W +-5%(0402)EF';
      COMPONENT_TYPE='CHIPR0402';
      LEAD_LENGTH='';
      DFM_EXCLUSION='';
      DAY='20180208';
      PARENT_PART_TYPE='Q_RES';
      PARENT_PPT='Q_RES';
      PARENT_PPT_PART='Q_RES_0402LF-10K,5%,1/16W,EMPTY,CS31002JB08';
  end_body;
end_primitive;
primitive 'Q_RES_0402LF-10M,1%,1/16W,CHIP,CS61002FB02';
  pin
    'A':
      PIN_GROUP='1';
      PIN_NUMBER='(1)';
      PIN_TYPE='UNSPEC';
      PINUSE='UNSPEC';
    'B':
      PIN_GROUP='1';
      PIN_NUMBER='(2)';
      PIN_TYPE='UNSPEC';
      PINUSE='UNSPEC';
  end_pin;
  body
      PART_NAME='Q_RES';
      PHYS_DES_PREFIX='R';
      STANDARD='';
      LIFECYCLE='';
      PART_NUMBER='CS61002FB02';
      JEDEC_TYPE='R0402';
      ALT_SYMBOLS='(R0402-0201)';
      VALUE='10M';
      TOL='1%';
      WATTAGE='1/16W';
      CLASS='DISCRETE';
      DESCRIPTION='RES CHIP 10M 1/16W +-1%(0402)EF';
      COMPONENT_TYPE='CHIPR0402';
      LEAD_LENGTH='';
      DFM_EXCLUSION='';
      DAY='20190906';
      PARENT_PART_TYPE='Q_RES';
      PARENT_PPT='Q_RES';
      PARENT_PPT_PART='Q_RES_0402LF-10M,1%,1/16W,CHIP,CS61002FB02';
  end_body;
end_primitive;
primitive 'Q_RES_0402LF-10M,1%,1/16W,EMPTY,CS61002FB02';
  pin
    'A':
      PIN_GROUP='1';
      PIN_NUMBER='(1)';
      PIN_TYPE='UNSPEC';
      PINUSE='UNSPEC';
    'B':
      PIN_GROUP='1';
      PIN_NUMBER='(2)';
      PIN_TYPE='UNSPEC';
      PINUSE='UNSPEC';
  end_pin;
  body
      PART_NAME='Q_RES';
      PHYS_DES_PREFIX='R';
      STANDARD='';
      LIFECYCLE='';
      PART_NUMBER='CS61002FB02';
      JEDEC_TYPE='R0402';
      ALT_SYMBOLS='(R0402-0201)';
      VALUE='10M';
      TOL='1%';
      WATTAGE='1/16W';
      CLASS='IO';
      DESCRIPTION='RES CHIP 10M 1/16W +-1%(0402)EF';
      COMPONENT_TYPE='CHIPR0402';
      LEAD_LENGTH='';
      DFM_EXCLUSION='';
      DAY='20190906';
      PARENT_PART_TYPE='Q_RES';
      PARENT_PPT='Q_RES';
      PARENT_PPT_PART='Q_RES_0402LF-10M,1%,1/16W,EMPTY,CS61002FB02';
  end_body;
end_primitive;
primitive 'Q_RES_0402LF-11.5K,1%,1/16W,CHIP,CS31152FB03';
  pin
    'A':
      PIN_GROUP='1';
      PIN_NUMBER='(1)';
      PIN_TYPE='UNSPEC';
      PINUSE='UNSPEC';
    'B':
      PIN_GROUP='1';
      PIN_NUMBER='(2)';
      PIN_TYPE='UNSPEC';
      PINUSE='UNSPEC';
  end_pin;
  body
      PART_NAME='Q_RES';
      PHYS_DES_PREFIX='R';
      STANDARD='End of Design';
      LIFECYCLE='Comp-Approve';
      PART_NUMBER='CS31152FB03';
      JEDEC_TYPE='R0402';
      ALT_SYMBOLS='(R0402-0201)';
      VALUE='11.5K';
      TOL='1%';
      WATTAGE='1/16W';
      CLASS='DISCRETE';
      DESCRIPTION='RES CHIP 11.5K 1/16W +-1%(0402)EF';
      COMPONENT_TYPE='CHIPR0402';
      LEAD_LENGTH='';
      DFM_EXCLUSION='';
      DAY='20180221';
      PARENT_PART_TYPE='Q_RES';
      PARENT_PPT='Q_RES';
      PARENT_PPT_PART='Q_RES_0402LF-11.5K,1%,1/16W,CHIP,CS31152FB03';
  end_body;
end_primitive;
primitive 'Q_RES_0402LF-11.5K,1%,1/16W,EMPTY,CS31152FB03';
  pin
    'A':
      PIN_GROUP='1';
      PIN_NUMBER='(1)';
      PIN_TYPE='UNSPEC';
      PINUSE='UNSPEC';
    'B':
      PIN_GROUP='1';
      PIN_NUMBER='(2)';
      PIN_TYPE='UNSPEC';
      PINUSE='UNSPEC';
  end_pin;
  body
      PART_NAME='Q_RES';
      PHYS_DES_PREFIX='R';
      STANDARD='End of Design';
      LIFECYCLE='Comp-Approve';
      PART_NUMBER='CS31152FB03';
      JEDEC_TYPE='R0402';
      ALT_SYMBOLS='(R0402-0201)';
      VALUE='11.5K';
      TOL='1%';
      WATTAGE='1/16W';
      CLASS='IO';
      DESCRIPTION='RES CHIP 11.5K 1/16W +-1%(0402)EF';
      COMPONENT_TYPE='CHIPR0402';
      LEAD_LENGTH='';
      DFM_EXCLUSION='';
      DAY='20180221';
      PARENT_PART_TYPE='Q_RES';
      PARENT_PPT='Q_RES';
      PARENT_PPT_PART='Q_RES_0402LF-11.5K,1%,1/16W,EMPTY,CS31152FB03';
  end_body;
end_primitive;
primitive 'Q_RES_0402LF-11.8K,0.1%,1/16W,CHIP,CS31182BB06';
  pin
    'A':
      PIN_GROUP='1';
      PIN_NUMBER='(1)';
      PIN_TYPE='UNSPEC';
      PINUSE='UNSPEC';
    'B':
      PIN_GROUP='1';
      PIN_NUMBER='(2)';
      PIN_TYPE='UNSPEC';
      PINUSE='UNSPEC';
  end_pin;
  body
      PART_NAME='Q_RES';
      PHYS_DES_PREFIX='R';
      STANDARD='';
      LIFECYCLE='';
      PART_NUMBER='CS31182BB06';
      JEDEC_TYPE='R0402';
      ALT_SYMBOLS='(R0402-0201)';
      VALUE='11.8K';
      TOL='0.1%';
      WATTAGE='1/16W';
      CLASS='DISCRETE';
      DESCRIPTION='RES CHIP 11.8K 1/16W +-0.1%(0402)EF';
      COMPONENT_TYPE='CHIPR0402';
      LEAD_LENGTH='';
      DFM_EXCLUSION='';
      DAY='20210719';
      PARENT_PART_TYPE='Q_RES';
      PARENT_PPT='Q_RES';
      PARENT_PPT_PART='Q_RES_0402LF-11.8K,0.1%,1/16W,CHIP,CS31182BB06';
  end_body;
end_primitive;
primitive 'Q_RES_0402LF-12.4K,1%,1/16W,CHIP,CS31242FB02';
  pin
    'A':
      PIN_GROUP='1';
      PIN_NUMBER='(1)';
      PIN_TYPE='UNSPEC';
      PINUSE='UNSPEC';
    'B':
      PIN_GROUP='1';
      PIN_NUMBER='(2)';
      PIN_TYPE='UNSPEC';
      PINUSE='UNSPEC';
  end_pin;
  body
      PART_NAME='Q_RES';
      PHYS_DES_PREFIX='R';
      STANDARD='End of Design';
      LIFECYCLE='Comp-Approve';
      PART_NUMBER='CS31242FB02';
      JEDEC_TYPE='R0402';
      ALT_SYMBOLS='(R0402-0201)';
      VALUE='12.4K';
      TOL='1%';
      WATTAGE='1/16W';
      CLASS='DISCRETE';
      DESCRIPTION='RES CHIP 12.4K 1/16W +-1%(0402)EF';
      COMPONENT_TYPE='CHIPR0402';
      LEAD_LENGTH='';
      DFM_EXCLUSION='';
      DAY='20180221';
      PARENT_PART_TYPE='Q_RES';
      PARENT_PPT='Q_RES';
      PARENT_PPT_PART='Q_RES_0402LF-12.4K,1%,1/16W,CHIP,CS31242FB02';
  end_body;
end_primitive;
primitive 'Q_RES_0402LF-120K,1%,1/16W,CHIP,CS41202FB05';
  pin
    'A':
      PIN_GROUP='1';
      PIN_NUMBER='(1)';
      PIN_TYPE='UNSPEC';
      PINUSE='UNSPEC';
    'B':
      PIN_GROUP='1';
      PIN_NUMBER='(2)';
      PIN_TYPE='UNSPEC';
      PINUSE='UNSPEC';
  end_pin;
  body
      PART_NAME='Q_RES';
      PHYS_DES_PREFIX='R';
      STANDARD='';
      LIFECYCLE='';
      PART_NUMBER='CS41202FB05';
      JEDEC_TYPE='R0402';
      ALT_SYMBOLS='(R0402-0201)';
      VALUE='120K';
      TOL='1%';
      WATTAGE='1/16W';
      CLASS='DISCRETE';
      DESCRIPTION='RES CHIP 120K 1/16W +-1%(0402)EF';
      COMPONENT_TYPE='CHIPR0402';
      LEAD_LENGTH='';
      DFM_EXCLUSION='';
      DAY='20200225';
      PARENT_PART_TYPE='Q_RES';
      PARENT_PPT='Q_RES';
      PARENT_PPT_PART='Q_RES_0402LF-120K,1%,1/16W,CHIP,CS41202FB05';
  end_body;
end_primitive;
primitive 'Q_RES_0402LF-12K,1%,1/16W,CHIP,CS31202FB04';
  pin
    'A':
      PIN_GROUP='1';
      PIN_NUMBER='(1)';
      PIN_TYPE='UNSPEC';
      PINUSE='UNSPEC';
    'B':
      PIN_GROUP='1';
      PIN_NUMBER='(2)';
      PIN_TYPE='UNSPEC';
      PINUSE='UNSPEC';
  end_pin;
  body
      PART_NAME='Q_RES';
      PHYS_DES_PREFIX='R';
      STANDARD='End of Design';
      LIFECYCLE='Comp-Approve';
      PART_NUMBER='CS31202FB04';
      JEDEC_TYPE='R0402';
      ALT_SYMBOLS='(R0402-0201)';
      VALUE='12K';
      TOL='1%';
      WATTAGE='1/16W';
      CLASS='DISCRETE';
      DESCRIPTION='RES CHIP 12K 1/16W +-1%(0402)EF';
      COMPONENT_TYPE='CHIPR0402';
      LEAD_LENGTH='';
      DFM_EXCLUSION='';
      DAY='20180221';
      PARENT_PART_TYPE='Q_RES';
      PARENT_PPT='Q_RES';
      PARENT_PPT_PART='Q_RES_0402LF-12K,1%,1/16W,CHIP,CS31202FB04';
  end_body;
end_primitive;
primitive 'Q_RES_0402LF-13.7K,1%,1/16W,CHIP,CS31372FB03';
  pin
    'A':
      PIN_GROUP='1';
      PIN_NUMBER='(1)';
      PIN_TYPE='UNSPEC';
      PINUSE='UNSPEC';
    'B':
      PIN_GROUP='1';
      PIN_NUMBER='(2)';
      PIN_TYPE='UNSPEC';
      PINUSE='UNSPEC';
  end_pin;
  body
      PART_NAME='Q_RES';
      PHYS_DES_PREFIX='R';
      STANDARD='End of Design';
      LIFECYCLE='Comp-Approve';
      PART_NUMBER='CS31372FB03';
      JEDEC_TYPE='R0402';
      ALT_SYMBOLS='(R0402-0201)';
      VALUE='13.7K';
      TOL='1%';
      WATTAGE='1/16W';
      CLASS='DISCRETE';
      DESCRIPTION='RES CHIP 13.7K 1/16W +-1%(0402)EF';
      COMPONENT_TYPE='CHIPR0402';
      LEAD_LENGTH='';
      DFM_EXCLUSION='';
      DAY='20220622';
      PARENT_PART_TYPE='Q_RES';
      PARENT_PPT='Q_RES';
      PARENT_PPT_PART='Q_RES_0402LF-13.7K,1%,1/16W,CHIP,CS31372FB03';
  end_body;
end_primitive;
primitive 'Q_RES_0402LF-130,1%,1/16W,CHIP,CS11302FB03';
  pin
    'A':
      PIN_GROUP='1';
      PIN_NUMBER='(1)';
      PIN_TYPE='UNSPEC';
      PINUSE='UNSPEC';
    'B':
      PIN_GROUP='1';
      PIN_NUMBER='(2)';
      PIN_TYPE='UNSPEC';
      PINUSE='UNSPEC';
  end_pin;
  body
      PART_NAME='Q_RES';
      PHYS_DES_PREFIX='R';
      STANDARD='End of Design';
      LIFECYCLE='Comp-Approve';
      PART_NUMBER='CS11302FB03';
      JEDEC_TYPE='R0402';
      ALT_SYMBOLS='(R0402-0201)';
      VALUE='130';
      TOL='1%';
      WATTAGE='1/16W';
      CLASS='DISCRETE';
      DESCRIPTION='RES CHIP 130 1/16W +-1%(0402)EF';
      COMPONENT_TYPE='CHIPR0402';
      LEAD_LENGTH='';
      DFM_EXCLUSION='';
      DAY='20180221';
      PARENT_PART_TYPE='Q_RES';
      PARENT_PPT='Q_RES';
      PARENT_PPT_PART='Q_RES_0402LF-130,1%,1/16W,CHIP,CS11302FB03';
  end_body;
end_primitive;
primitive 'Q_RES_0402LF-14.3K,1%,1/16W,CHIP,CS31432FB02';
  pin
    'A':
      PIN_GROUP='1';
      PIN_NUMBER='(1)';
      PIN_TYPE='UNSPEC';
      PINUSE='UNSPEC';
    'B':
      PIN_GROUP='1';
      PIN_NUMBER='(2)';
      PIN_TYPE='UNSPEC';
      PINUSE='UNSPEC';
  end_pin;
  body
      PART_NAME='Q_RES';
      PHYS_DES_PREFIX='R';
      STANDARD='End of Design';
      LIFECYCLE='Comp-Approve';
      PART_NUMBER='CS31432FB02';
      JEDEC_TYPE='R0402';
      ALT_SYMBOLS='(R0402-0201)';
      VALUE='14.3K';
      TOL='1%';
      WATTAGE='1/16W';
      CLASS='DISCRETE';
      DESCRIPTION='RES CHIP 14.3K 1/16W +-1%(0402)EF';
      COMPONENT_TYPE='CHIPR0402';
      LEAD_LENGTH='';
      DFM_EXCLUSION='';
      DAY='20180221';
      PARENT_PART_TYPE='Q_RES';
      PARENT_PPT='Q_RES';
      PARENT_PPT_PART='Q_RES_0402LF-14.3K,1%,1/16W,CHIP,CS31432FB02';
  end_body;
end_primitive;
primitive 'Q_RES_0402LF-15,1%,1/16W,CHIP,CS01502FB03';
  pin
    'A':
      PIN_GROUP='1';
      PIN_NUMBER='(1)';
      PIN_TYPE='UNSPEC';
      PINUSE='UNSPEC';
    'B':
      PIN_GROUP='1';
      PIN_NUMBER='(2)';
      PIN_TYPE='UNSPEC';
      PINUSE='UNSPEC';
  end_pin;
  body
      PART_NAME='Q_RES';
      PHYS_DES_PREFIX='R';
      STANDARD='End of Design';
      LIFECYCLE='Comp-Approve';
      PART_NUMBER='CS01502FB03';
      JEDEC_TYPE='R0402';
      ALT_SYMBOLS='(R0402-0201)';
      VALUE='15';
      TOL='1%';
      WATTAGE='1/16W';
      CLASS='DISCRETE';
      DESCRIPTION='RES CHIP 15 1/16W +-1%(0402)EF';
      COMPONENT_TYPE='CHIPR0402';
      LEAD_LENGTH='';
      DFM_EXCLUSION='';
      DAY='20190212';
      PARENT_PART_TYPE='Q_RES';
      PARENT_PPT='Q_RES';
      PARENT_PPT_PART='Q_RES_0402LF-15,1%,1/16W,CHIP,CS01502FB03';
  end_body;
end_primitive;
primitive 'Q_RES_0402LF-15.4K,1%,1/16W,CHIP,CS31542FB02';
  pin
    'A':
      PIN_GROUP='1';
      PIN_NUMBER='(1)';
      PIN_TYPE='UNSPEC';
      PINUSE='UNSPEC';
    'B':
      PIN_GROUP='1';
      PIN_NUMBER='(2)';
      PIN_TYPE='UNSPEC';
      PINUSE='UNSPEC';
  end_pin;
  body
      PART_NAME='Q_RES';
      PHYS_DES_PREFIX='R';
      STANDARD='';
      LIFECYCLE='';
      PART_NUMBER='CS31542FB02';
      JEDEC_TYPE='R0402';
      ALT_SYMBOLS='(R0402-0201)';
      VALUE='15.4K';
      TOL='1%';
      WATTAGE='1/16W';
      CLASS='DISCRETE';
      DESCRIPTION='RES CHIP 15.4K 1/16W +-1%(0402)EF';
      COMPONENT_TYPE='CHIPR0402';
      LEAD_LENGTH='';
      DFM_EXCLUSION='';
      DAY='20210715';
      PARENT_PART_TYPE='Q_RES';
      PARENT_PPT='Q_RES';
      PARENT_PPT_PART='Q_RES_0402LF-15.4K,1%,1/16W,CHIP,CS31542FB02';
  end_body;
end_primitive;
primitive 'Q_RES_0402LF-15K,0.1%,1/16W,CHIP,CS31502BB03';
  pin
    'A':
      PIN_GROUP='1';
      PIN_NUMBER='(1)';
      PIN_TYPE='UNSPEC';
      PINUSE='UNSPEC';
    'B':
      PIN_GROUP='1';
      PIN_NUMBER='(2)';
      PIN_TYPE='UNSPEC';
      PINUSE='UNSPEC';
  end_pin;
  body
      PART_NAME='Q_RES';
      PHYS_DES_PREFIX='R';
      STANDARD='End of Design';
      LIFECYCLE='Comp-Approve';
      PART_NUMBER='CS31502BB03';
      JEDEC_TYPE='R0402';
      ALT_SYMBOLS='(R0402-0201)';
      VALUE='15K';
      TOL='0.1%';
      WATTAGE='1/16W';
      CLASS='DISCRETE';
      DESCRIPTION='RES CHIP 15K  1/16W +-0.1%(0402)EF';
      COMPONENT_TYPE='CHIPR0402';
      LEAD_LENGTH='';
      DFM_EXCLUSION='';
      DAY='20180221';
      PARENT_PART_TYPE='Q_RES';
      PARENT_PPT='Q_RES';
      PARENT_PPT_PART='Q_RES_0402LF-15K,0.1%,1/16W,CHIP,CS31502BB03';
  end_body;
end_primitive;
primitive 'Q_RES_0402LF-15K,1%,1/16W,CHIP,CS31502FB05';
  pin
    'A':
      PIN_GROUP='1';
      PIN_NUMBER='(1)';
      PIN_TYPE='UNSPEC';
      PINUSE='UNSPEC';
    'B':
      PIN_GROUP='1';
      PIN_NUMBER='(2)';
      PIN_TYPE='UNSPEC';
      PINUSE='UNSPEC';
  end_pin;
  body
      PART_NAME='Q_RES';
      PHYS_DES_PREFIX='R';
      STANDARD='End of Design';
      LIFECYCLE='Comp-Approve';
      PART_NUMBER='CS31502FB05';
      JEDEC_TYPE='R0402';
      ALT_SYMBOLS='(R0402-0201)';
      VALUE='15K';
      TOL='1%';
      WATTAGE='1/16W';
      CLASS='DISCRETE';
      DESCRIPTION='RES CHIP 15K 1/16W +-1%(0402)EF';
      COMPONENT_TYPE='CHIPR0402';
      LEAD_LENGTH='';
      DFM_EXCLUSION='';
      DAY='20191227';
      PARENT_PART_TYPE='Q_RES';
      PARENT_PPT='Q_RES';
      PARENT_PPT_PART='Q_RES_0402LF-15K,1%,1/16W,CHIP,CS31502FB05';
  end_body;
end_primitive;
primitive 'Q_RES_0402LF-16.9K,1%,1/16W,CHIP,CS31692FB03';
  pin
    'A':
      PIN_GROUP='1';
      PIN_NUMBER='(1)';
      PIN_TYPE='UNSPEC';
      PINUSE='UNSPEC';
    'B':
      PIN_GROUP='1';
      PIN_NUMBER='(2)';
      PIN_TYPE='UNSPEC';
      PINUSE='UNSPEC';
  end_pin;
  body
      PART_NAME='Q_RES';
      PHYS_DES_PREFIX='R';
      STANDARD='End of Design';
      LIFECYCLE='Comp-Approve';
      PART_NUMBER='CS31692FB03';
      JEDEC_TYPE='R0402';
      ALT_SYMBOLS='(R0402-0201)';
      VALUE='16.9K';
      TOL='1%';
      WATTAGE='1/16W';
      CLASS='DISCRETE';
      DESCRIPTION='RES CHIP 16.9K 1/16W +-1%(0402)EF';
      COMPONENT_TYPE='CHIPR0402';
      LEAD_LENGTH='';
      DFM_EXCLUSION='';
      DAY='20200615';
      PARENT_PART_TYPE='Q_RES';
      PARENT_PPT='Q_RES';
      PARENT_PPT_PART='Q_RES_0402LF-16.9K,1%,1/16W,CHIP,CS31692FB03';
  end_body;
end_primitive;
primitive 'Q_RES_0402LF-160K,1%,1/16W,CHIP,CS41602FB05';
  pin
    'A':
      PIN_GROUP='1';
      PIN_NUMBER='(1)';
      PIN_TYPE='UNSPEC';
      PINUSE='UNSPEC';
    'B':
      PIN_GROUP='1';
      PIN_NUMBER='(2)';
      PIN_TYPE='UNSPEC';
      PINUSE='UNSPEC';
  end_pin;
  body
      PART_NAME='Q_RES';
      PHYS_DES_PREFIX='R';
      STANDARD='';
      LIFECYCLE='';
      PART_NUMBER='CS41602FB05';
      JEDEC_TYPE='R0402';
      ALT_SYMBOLS='(R0402-0201)';
      VALUE='160K';
      TOL='1%';
      WATTAGE='1/16W';
      CLASS='DISCRETE';
      DESCRIPTION='RES CHIP 160K 1/16W+-1%(0402)EF';
      COMPONENT_TYPE='CHIPR0402';
      LEAD_LENGTH='';
      DFM_EXCLUSION='';
      DAY='20191113';
      PARENT_PART_TYPE='Q_RES';
      PARENT_PPT='Q_RES';
      PARENT_PPT_PART='Q_RES_0402LF-160K,1%,1/16W,CHIP,CS41602FB05';
  end_body;
end_primitive;
primitive 'Q_RES_0402LF-160K,1%,1/16W,EMPTY,CS41602FB05';
  pin
    'A':
      PIN_GROUP='1';
      PIN_NUMBER='(1)';
      PIN_TYPE='UNSPEC';
      PINUSE='UNSPEC';
    'B':
      PIN_GROUP='1';
      PIN_NUMBER='(2)';
      PIN_TYPE='UNSPEC';
      PINUSE='UNSPEC';
  end_pin;
  body
      PART_NAME='Q_RES';
      PHYS_DES_PREFIX='R';
      STANDARD='';
      LIFECYCLE='';
      PART_NUMBER='CS41602FB05';
      JEDEC_TYPE='R0402';
      ALT_SYMBOLS='(R0402-0201)';
      VALUE='160K';
      TOL='1%';
      WATTAGE='1/16W';
      CLASS='IO';
      DESCRIPTION='RES CHIP 160K 1/16W+-1%(0402)EF';
      COMPONENT_TYPE='CHIPR0402';
      LEAD_LENGTH='';
      DFM_EXCLUSION='';
      DAY='20191113';
      PARENT_PART_TYPE='Q_RES';
      PARENT_PPT='Q_RES';
      PARENT_PPT_PART='Q_RES_0402LF-160K,1%,1/16W,EMPTY,CS41602FB05';
  end_body;
end_primitive;
primitive 'Q_RES_0402LF-17.4K,1%,1/16W,CHIP,CS31742FB04';
  pin
    'A':
      PIN_GROUP='1';
      PIN_NUMBER='(1)';
      PIN_TYPE='UNSPEC';
      PINUSE='UNSPEC';
    'B':
      PIN_GROUP='1';
      PIN_NUMBER='(2)';
      PIN_TYPE='UNSPEC';
      PINUSE='UNSPEC';
  end_pin;
  body
      PART_NAME='Q_RES';
      PHYS_DES_PREFIX='R';
      STANDARD='End of Design';
      LIFECYCLE='Comp-Approve';
      PART_NUMBER='CS31742FB04';
      JEDEC_TYPE='R0402';
      ALT_SYMBOLS='(R0402-0201)';
      VALUE='17.4K';
      TOL='1%';
      WATTAGE='1/16W';
      CLASS='DISCRETE';
      DESCRIPTION='RES CHIP 17.4K 1/16W +-1%(0402)EF';
      COMPONENT_TYPE='CHIPR0402';
      LEAD_LENGTH='';
      DFM_EXCLUSION='';
      DAY='20190826';
      PARENT_PART_TYPE='Q_RES';
      PARENT_PPT='Q_RES';
      PARENT_PPT_PART='Q_RES_0402LF-17.4K,1%,1/16W,CHIP,CS31742FB04';
  end_body;
end_primitive;
primitive 'Q_RES_0402LF-17.8K,1%,1/16W,CHIP,CS31782FB04';
  pin
    'A':
      PIN_GROUP='1';
      PIN_NUMBER='(1)';
      PIN_TYPE='UNSPEC';
      PINUSE='UNSPEC';
    'B':
      PIN_GROUP='1';
      PIN_NUMBER='(2)';
      PIN_TYPE='UNSPEC';
      PINUSE='UNSPEC';
  end_pin;
  body
      PART_NAME='Q_RES';
      PHYS_DES_PREFIX='R';
      STANDARD='End of Design';
      LIFECYCLE='Comp-Approve';
      PART_NUMBER='CS31782FB04';
      JEDEC_TYPE='R0402';
      ALT_SYMBOLS='(R0402-0201)';
      VALUE='17.8K';
      TOL='1%';
      WATTAGE='1/16W';
      CLASS='DISCRETE';
      DESCRIPTION='RES CHIP 17.8K 1/16W +- 1% (0402)EF';
      COMPONENT_TYPE='CHIPR0402';
      LEAD_LENGTH='';
      DFM_EXCLUSION='';
      DAY='20190730';
      PARENT_PART_TYPE='Q_RES';
      PARENT_PPT='Q_RES';
      PARENT_PPT_PART='Q_RES_0402LF-17.8K,1%,1/16W,CHIP,CS31782FB04';
  end_body;
end_primitive;
primitive 'Q_RES_0402LF-18K,1%,1/16W,CHIP,CS31802FB04';
  pin
    'A':
      PIN_GROUP='1';
      PIN_NUMBER='(1)';
      PIN_TYPE='UNSPEC';
      PINUSE='UNSPEC';
    'B':
      PIN_GROUP='1';
      PIN_NUMBER='(2)';
      PIN_TYPE='UNSPEC';
      PINUSE='UNSPEC';
  end_pin;
  body
      PART_NAME='Q_RES';
      PHYS_DES_PREFIX='R';
      STANDARD='';
      LIFECYCLE='';
      PART_NUMBER='CS31802FB04';
      JEDEC_TYPE='R0402';
      ALT_SYMBOLS='(R0402-0201)';
      VALUE='18K';
      TOL='1%';
      WATTAGE='1/16W';
      CLASS='DISCRETE';
      DESCRIPTION='RES CHIP 18K 1/16W +-1%(0402)EF';
      COMPONENT_TYPE='CHIPR0402';
      LEAD_LENGTH='';
      DFM_EXCLUSION='';
      DAY='20210719';
      PARENT_PART_TYPE='Q_RES';
      PARENT_PPT='Q_RES';
      PARENT_PPT_PART='Q_RES_0402LF-18K,1%,1/16W,CHIP,CS31802FB04';
  end_body;
end_primitive;
primitive 'Q_RES_0402LF-1K,1%,1/16W,CHIP,CS21002FB06';
  pin
    'A':
      PIN_GROUP='1';
      PIN_NUMBER='(1)';
      PIN_TYPE='UNSPEC';
      PINUSE='UNSPEC';
    'B':
      PIN_GROUP='1';
      PIN_NUMBER='(2)';
      PIN_TYPE='UNSPEC';
      PINUSE='UNSPEC';
  end_pin;
  body
      PART_NAME='Q_RES';
      PHYS_DES_PREFIX='R';
      STANDARD='End of Design';
      LIFECYCLE='Comp-Approve';
      PART_NUMBER='CS21002FB06';
      JEDEC_TYPE='R0402';
      ALT_SYMBOLS='(R0402-0201)';
      VALUE='1K';
      TOL='1%';
      WATTAGE='1/16W';
      CLASS='DISCRETE';
      DESCRIPTION='RES CHIP 1K 1/16W +-1%(0402)EF';
      COMPONENT_TYPE='CHIPR0402';
      LEAD_LENGTH='';
      DFM_EXCLUSION='';
      DAY='20180208';
      PARENT_PART_TYPE='Q_RES';
      PARENT_PPT='Q_RES';
      PARENT_PPT_PART='Q_RES_0402LF-1K,1%,1/16W,CHIP,CS21002FB06';
  end_body;
end_primitive;
primitive 'Q_RES_0402LF-1K,1%,1/16W,EMPTY,CS21002FB06';
  pin
    'A':
      PIN_GROUP='1';
      PIN_NUMBER='(1)';
      PIN_TYPE='UNSPEC';
      PINUSE='UNSPEC';
    'B':
      PIN_GROUP='1';
      PIN_NUMBER='(2)';
      PIN_TYPE='UNSPEC';
      PINUSE='UNSPEC';
  end_pin;
  body
      PART_NAME='Q_RES';
      PHYS_DES_PREFIX='R';
      STANDARD='End of Design';
      LIFECYCLE='Comp-Approve';
      PART_NUMBER='CS21002FB06';
      JEDEC_TYPE='R0402';
      ALT_SYMBOLS='(R0402-0201)';
      VALUE='1K';
      TOL='1%';
      WATTAGE='1/16W';
      CLASS='IO';
      DESCRIPTION='RES CHIP 1K 1/16W +-1%(0402)EF';
      COMPONENT_TYPE='CHIPR0402';
      LEAD_LENGTH='';
      DFM_EXCLUSION='';
      DAY='20180208';
      PARENT_PART_TYPE='Q_RES';
      PARENT_PPT='Q_RES';
      PARENT_PPT_PART='Q_RES_0402LF-1K,1%,1/16W,EMPTY,CS21002FB06';
  end_body;
end_primitive;
primitive 'Q_RES_0402LF-1M,1%,1/16W,CHIP,CS51002FB05';
  pin
    'A':
      PIN_GROUP='1';
      PIN_NUMBER='(1)';
      PIN_TYPE='UNSPEC';
      PINUSE='UNSPEC';
    'B':
      PIN_GROUP='1';
      PIN_NUMBER='(2)';
      PIN_TYPE='UNSPEC';
      PINUSE='UNSPEC';
  end_pin;
  body
      PART_NAME='Q_RES';
      PHYS_DES_PREFIX='R';
      STANDARD='End of Design';
      LIFECYCLE='Comp-Approve';
      PART_NUMBER='CS51002FB05';
      JEDEC_TYPE='R0402';
      ALT_SYMBOLS='(R0402-0201)';
      VALUE='1M';
      TOL='1%';
      WATTAGE='1/16W';
      CLASS='DISCRETE';
      DESCRIPTION='RES CHIP 1M 1/16W +-1%(0402)EF';
      COMPONENT_TYPE='CHIPR0402';
      LEAD_LENGTH='';
      DFM_EXCLUSION='';
      DAY='20180221';
      PARENT_PART_TYPE='Q_RES';
      PARENT_PPT='Q_RES';
      PARENT_PPT_PART='Q_RES_0402LF-1M,1%,1/16W,CHIP,CS51002FB05';
  end_body;
end_primitive;
primitive 'Q_RES_0402LF-1M,1%,1/16W,EMPTY,CS51002FB05';
  pin
    'A':
      PIN_GROUP='1';
      PIN_NUMBER='(1)';
      PIN_TYPE='UNSPEC';
      PINUSE='UNSPEC';
    'B':
      PIN_GROUP='1';
      PIN_NUMBER='(2)';
      PIN_TYPE='UNSPEC';
      PINUSE='UNSPEC';
  end_pin;
  body
      PART_NAME='Q_RES';
      PHYS_DES_PREFIX='R';
      STANDARD='End of Design';
      LIFECYCLE='Comp-Approve';
      PART_NUMBER='CS51002FB05';
      JEDEC_TYPE='R0402';
      ALT_SYMBOLS='(R0402-0201)';
      VALUE='1M';
      TOL='1%';
      WATTAGE='1/16W';
      CLASS='IO';
      DESCRIPTION='RES CHIP 1M 1/16W +-1%(0402)EF';
      COMPONENT_TYPE='CHIPR0402';
      LEAD_LENGTH='';
      DFM_EXCLUSION='';
      DAY='20180221';
      PARENT_PART_TYPE='Q_RES';
      PARENT_PPT='Q_RES';
      PARENT_PPT_PART='Q_RES_0402LF-1M,1%,1/16W,EMPTY,CS51002FB05';
  end_body;
end_primitive;
primitive 'Q_RES_0402LF-2.2,1%,1/16W,CHIP,CS-2202FB01';
  pin
    'A':
      PIN_GROUP='1';
      PIN_NUMBER='(1)';
      PIN_TYPE='UNSPEC';
      PINUSE='UNSPEC';
    'B':
      PIN_GROUP='1';
      PIN_NUMBER='(2)';
      PIN_TYPE='UNSPEC';
      PINUSE='UNSPEC';
  end_pin;
  body
      PART_NAME='Q_RES';
      PHYS_DES_PREFIX='R';
      STANDARD='End of Design';
      LIFECYCLE='Comp-Approve';
      PART_NUMBER='CS-2202FB01';
      JEDEC_TYPE='R0402';
      ALT_SYMBOLS='(R0402-0201)';
      VALUE='2.2';
      TOL='1%';
      WATTAGE='1/16W';
      CLASS='DISCRETE';
      DESCRIPTION='RES CHIP 2.2 1/16W +-1%(0402)EF';
      COMPONENT_TYPE='CHIP0402';
      LEAD_LENGTH='';
      DFM_EXCLUSION='';
      DAY='20180212';
      PARENT_PART_TYPE='Q_RES';
      PARENT_PPT='Q_RES';
      PARENT_PPT_PART='Q_RES_0402LF-2.2,1%,1/16W,CHIP,CS-2202FB01';
  end_body;
end_primitive;
primitive 'Q_RES_0402LF-2.2,5%,1/16W,CHIP,TMP_QCS-2202JB25';
  pin
    'A':
      PIN_GROUP='1';
      PIN_NUMBER='(1)';
      PIN_TYPE='UNSPEC';
      PINUSE='UNSPEC';
    'B':
      PIN_GROUP='1';
      PIN_NUMBER='(2)';
      PIN_TYPE='UNSPEC';
      PINUSE='UNSPEC';
  end_pin;
  body
      PART_NAME='Q_RES';
      PHYS_DES_PREFIX='R';
      STANDARD='End of Design';
      LIFECYCLE='Comp-Approve';
      PART_NUMBER='CS-2202JB25';
      JEDEC_TYPE='R0402';
      ALT_SYMBOLS='(R0402-0201)';
      VALUE='2.2';
      TOL='5%';
      WATTAGE='1/16W';
      CLASS='DISCRETE';
      DESCRIPTION='RES CHIP 2.2 1/16W +-5%  (0402)';
      COMPONENT_TYPE='CHIP0402';
      LEAD_LENGTH='';
      DFM_EXCLUSION='';
      DAY='';
      PARENT_PART_TYPE='Q_RES';
      PARENT_PPT='Q_RES';
      PARENT_PPT_PART='Q_RES_0402LF-2.2,5%,1/16W,CHIP,TMP_QCS-2202JB25';
  end_body;
end_primitive;
primitive 'Q_RES_0402LF-2.2K,5%,1/16W,CHIP,CS22202JB07';
  pin
    'A':
      PIN_GROUP='1';
      PIN_NUMBER='(1)';
      PIN_TYPE='UNSPEC';
      PINUSE='UNSPEC';
    'B':
      PIN_GROUP='1';
      PIN_NUMBER='(2)';
      PIN_TYPE='UNSPEC';
      PINUSE='UNSPEC';
  end_pin;
  body
      PART_NAME='Q_RES';
      PHYS_DES_PREFIX='R';
      STANDARD='End of Design';
      LIFECYCLE='Comp-Approve';
      PART_NUMBER='CS22202JB07';
      JEDEC_TYPE='R0402';
      ALT_SYMBOLS='(R0402-0201)';
      VALUE='2.2K';
      TOL='5%';
      WATTAGE='1/16W';
      CLASS='DISCRETE';
      DESCRIPTION='RES CHIP 2.2K 1/16W +-5%(0402)EF';
      COMPONENT_TYPE='CHIP0402';
      LEAD_LENGTH='';
      DFM_EXCLUSION='';
      DAY='20180212';
      PARENT_PART_TYPE='Q_RES';
      PARENT_PPT='Q_RES';
      PARENT_PPT_PART='Q_RES_0402LF-2.2K,5%,1/16W,CHIP,CS22202JB07';
  end_body;
end_primitive;
primitive 'Q_RES_0402LF-2.2K,5%,1/16W,EMPTY,CS22202JB07';
  pin
    'A':
      PIN_GROUP='1';
      PIN_NUMBER='(1)';
      PIN_TYPE='UNSPEC';
      PINUSE='UNSPEC';
    'B':
      PIN_GROUP='1';
      PIN_NUMBER='(2)';
      PIN_TYPE='UNSPEC';
      PINUSE='UNSPEC';
  end_pin;
  body
      PART_NAME='Q_RES';
      PHYS_DES_PREFIX='R';
      STANDARD='End of Design';
      LIFECYCLE='Comp-Approve';
      PART_NUMBER='CS22202JB07';
      JEDEC_TYPE='R0402';
      ALT_SYMBOLS='(R0402-0201)';
      VALUE='2.2K';
      TOL='5%';
      WATTAGE='1/16W';
      CLASS='IO';
      DESCRIPTION='RES CHIP 2.2K 1/16W +-5%(0402)EF';
      COMPONENT_TYPE='CHIP0402';
      LEAD_LENGTH='';
      DFM_EXCLUSION='';
      DAY='20180212';
      PARENT_PART_TYPE='Q_RES';
      PARENT_PPT='Q_RES';
      PARENT_PPT_PART='Q_RES_0402LF-2.2K,5%,1/16W,EMPTY,CS22202JB07';
  end_body;
end_primitive;
primitive 'Q_RES_0402LF-2.49K,1%,1/16W,CHIP,CS22492FB05';
  pin
    'A':
      PIN_GROUP='1';
      PIN_NUMBER='(1)';
      PIN_TYPE='UNSPEC';
      PINUSE='UNSPEC';
    'B':
      PIN_GROUP='1';
      PIN_NUMBER='(2)';
      PIN_TYPE='UNSPEC';
      PINUSE='UNSPEC';
  end_pin;
  body
      PART_NAME='Q_RES';
      PHYS_DES_PREFIX='R';
      STANDARD='End of Design';
      LIFECYCLE='Comp-Approve';
      PART_NUMBER='CS22492FB05';
      JEDEC_TYPE='R0402';
      ALT_SYMBOLS='(R0402-0201)';
      VALUE='2.49K';
      TOL='1%';
      WATTAGE='1/16W';
      CLASS='DISCRETE';
      DESCRIPTION='RES CHIP 2.49K 1/16W +-1%(0402)EF';
      COMPONENT_TYPE='CHIPR0402';
      LEAD_LENGTH='';
      DFM_EXCLUSION='';
      DAY='20180221';
      PARENT_PART_TYPE='Q_RES';
      PARENT_PPT='Q_RES';
      PARENT_PPT_PART='Q_RES_0402LF-2.49K,1%,1/16W,CHIP,CS22492FB05';
  end_body;
end_primitive;
primitive 'Q_RES_0402LF-2.67K,1%,1/16W,CHIP,CS22672FB03';
  pin
    'A':
      PIN_GROUP='1';
      PIN_NUMBER='(1)';
      PIN_TYPE='UNSPEC';
      PINUSE='UNSPEC';
    'B':
      PIN_GROUP='1';
      PIN_NUMBER='(2)';
      PIN_TYPE='UNSPEC';
      PINUSE='UNSPEC';
  end_pin;
  body
      PART_NAME='Q_RES';
      PHYS_DES_PREFIX='R';
      STANDARD='End of Design';
      LIFECYCLE='Comp-Approve';
      PART_NUMBER='CS22672FB03';
      JEDEC_TYPE='R0402';
      ALT_SYMBOLS='(R0402-0201)';
      VALUE='2.67K';
      TOL='1%';
      WATTAGE='1/16W';
      CLASS='DISCRETE';
      DESCRIPTION='RES CHIP 2.67K 1/16W +-1%(0402)EF';
      COMPONENT_TYPE='CHIPR0402';
      LEAD_LENGTH='';
      DFM_EXCLUSION='';
      DAY='20190905';
      PARENT_PART_TYPE='Q_RES';
      PARENT_PPT='Q_RES';
      PARENT_PPT_PART='Q_RES_0402LF-2.67K,1%,1/16W,CHIP,CS22672FB03';
  end_body;
end_primitive;
primitive 'Q_RES_0402LF-2.8K,1%,1/16W,CHIP,CS22802FB04';
  pin
    'A':
      PIN_GROUP='1';
      PIN_NUMBER='(1)';
      PIN_TYPE='UNSPEC';
      PINUSE='UNSPEC';
    'B':
      PIN_GROUP='1';
      PIN_NUMBER='(2)';
      PIN_TYPE='UNSPEC';
      PINUSE='UNSPEC';
  end_pin;
  body
      PART_NAME='Q_RES';
      PHYS_DES_PREFIX='R';
      STANDARD='End of Design';
      LIFECYCLE='Comp-Approve';
      PART_NUMBER='CS22802FB04';
      JEDEC_TYPE='R0402';
      ALT_SYMBOLS='(R0402-0201)';
      VALUE='2.8K';
      TOL='1%';
      WATTAGE='1/16W';
      CLASS='DISCRETE';
      DESCRIPTION='RES CHIP 2.8K 1/16W +-1%(0402)EF';
      COMPONENT_TYPE='CHIPR0402';
      LEAD_LENGTH='';
      DFM_EXCLUSION='';
      DAY='20211222';
      PARENT_PART_TYPE='Q_RES';
      PARENT_PPT='Q_RES';
      PARENT_PPT_PART='Q_RES_0402LF-2.8K,1%,1/16W,CHIP,CS22802FB04';
  end_body;
end_primitive;
primitive 'Q_RES_0402LF-200,1%,1/16W,CHIP,CS12002FB06';
  pin
    'A':
      PIN_GROUP='1';
      PIN_NUMBER='(1)';
      PIN_TYPE='UNSPEC';
      PINUSE='UNSPEC';
    'B':
      PIN_GROUP='1';
      PIN_NUMBER='(2)';
      PIN_TYPE='UNSPEC';
      PINUSE='UNSPEC';
  end_pin;
  body
      PART_NAME='Q_RES';
      PHYS_DES_PREFIX='R';
      STANDARD='End of Design';
      LIFECYCLE='Comp-Approve';
      PART_NUMBER='CS12002FB06';
      JEDEC_TYPE='R0402';
      ALT_SYMBOLS='(R0402-0201)';
      VALUE='200';
      TOL='1%';
      WATTAGE='1/16W';
      CLASS='DISCRETE';
      DESCRIPTION='RES CHIP 200 1/16W +-1%(0402)EF';
      COMPONENT_TYPE='CHIPR0402';
      LEAD_LENGTH='';
      DFM_EXCLUSION='';
      DAY='20180208';
      PARENT_PART_TYPE='Q_RES';
      PARENT_PPT='Q_RES';
      PARENT_PPT_PART='Q_RES_0402LF-200,1%,1/16W,CHIP,CS12002FB06';
  end_body;
end_primitive;
primitive 'Q_RES_0402LF-200K,1%,1/16W,CHIP,CS42002FB05';
  pin
    'A':
      PIN_GROUP='1';
      PIN_NUMBER='(1)';
      PIN_TYPE='UNSPEC';
      PINUSE='UNSPEC';
    'B':
      PIN_GROUP='1';
      PIN_NUMBER='(2)';
      PIN_TYPE='UNSPEC';
      PINUSE='UNSPEC';
  end_pin;
  body
      PART_NAME='Q_RES';
      PHYS_DES_PREFIX='R';
      STANDARD='End of Design';
      LIFECYCLE='Comp-Approve';
      PART_NUMBER='CS42002FB05';
      JEDEC_TYPE='R0402';
      ALT_SYMBOLS='(R0402-0201)';
      VALUE='200K';
      TOL='1%';
      WATTAGE='1/16W';
      CLASS='DISCRETE';
      DESCRIPTION='RES CHIP 200K 1/16W +-1%(0402)EF';
      COMPONENT_TYPE='CHIPR0402';
      LEAD_LENGTH='';
      DFM_EXCLUSION='';
      DAY='20180208';
      PARENT_PART_TYPE='Q_RES';
      PARENT_PPT='Q_RES';
      PARENT_PPT_PART='Q_RES_0402LF-200K,1%,1/16W,CHIP,CS42002FB05';
  end_body;
end_primitive;
primitive 'Q_RES_0402LF-200K,1%,1/16W,EMPTY,CS42002FB05';
  pin
    'A':
      PIN_GROUP='1';
      PIN_NUMBER='(1)';
      PIN_TYPE='UNSPEC';
      PINUSE='UNSPEC';
    'B':
      PIN_GROUP='1';
      PIN_NUMBER='(2)';
      PIN_TYPE='UNSPEC';
      PINUSE='UNSPEC';
  end_pin;
  body
      PART_NAME='Q_RES';
      PHYS_DES_PREFIX='R';
      STANDARD='End of Design';
      LIFECYCLE='Comp-Approve';
      PART_NUMBER='CS42002FB05';
      JEDEC_TYPE='R0402';
      ALT_SYMBOLS='(R0402-0201)';
      VALUE='200K';
      TOL='1%';
      WATTAGE='1/16W';
      CLASS='IO';
      DESCRIPTION='RES CHIP 200K 1/16W +-1%(0402)EF';
      COMPONENT_TYPE='CHIPR0402';
      LEAD_LENGTH='';
      DFM_EXCLUSION='';
      DAY='20180208';
      PARENT_PART_TYPE='Q_RES';
      PARENT_PPT='Q_RES';
      PARENT_PPT_PART='Q_RES_0402LF-200K,1%,1/16W,EMPTY,CS42002FB05';
  end_body;
end_primitive;
primitive 'Q_RES_0402LF-20K,1%,1/16W,CHIP,CS32002FB06';
  pin
    'A':
      PIN_GROUP='1';
      PIN_NUMBER='(1)';
      PIN_TYPE='UNSPEC';
      PINUSE='UNSPEC';
    'B':
      PIN_GROUP='1';
      PIN_NUMBER='(2)';
      PIN_TYPE='UNSPEC';
      PINUSE='UNSPEC';
  end_pin;
  body
      PART_NAME='Q_RES';
      PHYS_DES_PREFIX='R';
      STANDARD='End of Design';
      LIFECYCLE='Comp-Approve';
      PART_NUMBER='CS32002FB06';
      JEDEC_TYPE='R0402';
      ALT_SYMBOLS='(R0402-0201)';
      VALUE='20K';
      TOL='1%';
      WATTAGE='1/16W';
      CLASS='DISCRETE';
      DESCRIPTION='RES CHIP 20K 1/16W +-1%(0402)EF';
      COMPONENT_TYPE='CHIPR0402';
      LEAD_LENGTH='';
      DFM_EXCLUSION='';
      DAY='20180208';
      PARENT_PART_TYPE='Q_RES';
      PARENT_PPT='Q_RES';
      PARENT_PPT_PART='Q_RES_0402LF-20K,1%,1/16W,CHIP,CS32002FB06';
  end_body;
end_primitive;
primitive 'Q_RES_0402LF-20M,1%,1/16W,CHIP,CS62002FB01';
  pin
    'A':
      PIN_GROUP='1';
      PIN_NUMBER='(1)';
      PIN_TYPE='UNSPEC';
      PINUSE='UNSPEC';
    'B':
      PIN_GROUP='1';
      PIN_NUMBER='(2)';
      PIN_TYPE='UNSPEC';
      PINUSE='UNSPEC';
  end_pin;
  body
      PART_NAME='Q_RES';
      PHYS_DES_PREFIX='R';
      STANDARD='';
      LIFECYCLE='';
      PART_NUMBER='CS62002FB01';
      JEDEC_TYPE='R0402';
      ALT_SYMBOLS='(R0402-0201)';
      VALUE='20M';
      TOL='1%';
      WATTAGE='1/16W';
      CLASS='DISCRETE';
      DESCRIPTION='RES CHIP 20M 1/16W +-1%(0402)EF';
      COMPONENT_TYPE='CHIPR0402';
      LEAD_LENGTH='';
      DFM_EXCLUSION='';
      DAY='20220613';
      PARENT_PART_TYPE='Q_RES';
      PARENT_PPT='Q_RES';
      PARENT_PPT_PART='Q_RES_0402LF-20M,1%,1/16W,CHIP,CS62002FB01';
  end_body;
end_primitive;
primitive 'Q_RES_0402LF-21.5K,1%,1/16W,CHIP,CS32152FB04';
  pin
    'A':
      PIN_GROUP='1';
      PIN_NUMBER='(1)';
      PIN_TYPE='UNSPEC';
      PINUSE='UNSPEC';
    'B':
      PIN_GROUP='1';
      PIN_NUMBER='(2)';
      PIN_TYPE='UNSPEC';
      PINUSE='UNSPEC';
  end_pin;
  body
      PART_NAME='Q_RES';
      PHYS_DES_PREFIX='R';
      STANDARD='';
      LIFECYCLE='';
      PART_NUMBER='CS32152FB04';
      JEDEC_TYPE='R0402';
      ALT_SYMBOLS='(R0402-0201)';
      VALUE='21.5K';
      TOL='1%';
      WATTAGE='1/16W';
      CLASS='DISCRETE';
      DESCRIPTION='RES CHIP 21.5K 1/16W +-1%(0402)EF';
      COMPONENT_TYPE='CHIPR0402';
      LEAD_LENGTH='';
      DFM_EXCLUSION='';
      DAY='20200302';
      PARENT_PART_TYPE='Q_RES';
      PARENT_PPT='Q_RES';
      PARENT_PPT_PART='Q_RES_0402LF-21.5K,1%,1/16W,CHIP,CS32152FB04';
  end_body;
end_primitive;
primitive 'Q_RES_0402LF-22,1%,1/16W,CHIP,CS02202FB02';
  pin
    'A':
      PIN_GROUP='1';
      PIN_NUMBER='(1)';
      PIN_TYPE='UNSPEC';
      PINUSE='UNSPEC';
    'B':
      PIN_GROUP='1';
      PIN_NUMBER='(2)';
      PIN_TYPE='UNSPEC';
      PINUSE='UNSPEC';
  end_pin;
  body
      PART_NAME='Q_RES';
      PHYS_DES_PREFIX='R';
      STANDARD='End of Design';
      LIFECYCLE='Comp-Approve';
      PART_NUMBER='CS02202FB02';
      JEDEC_TYPE='R0402';
      ALT_SYMBOLS='(R0402-0201)';
      VALUE='22';
      TOL='1%';
      WATTAGE='1/16W';
      CLASS='DISCRETE';
      DESCRIPTION='RES CHIP 22 1/16W +-1%(0402)EF';
      COMPONENT_TYPE='CHIP0402';
      LEAD_LENGTH='';
      DFM_EXCLUSION='';
      DAY='20180212';
      PARENT_PART_TYPE='Q_RES';
      PARENT_PPT='Q_RES';
      PARENT_PPT_PART='Q_RES_0402LF-22,1%,1/16W,CHIP,CS02202FB02';
  end_body;
end_primitive;
primitive 'Q_RES_0402LF-22,1%,1/16W,EMPTY,CS02202FB02';
  pin
    'A':
      PIN_GROUP='1';
      PIN_NUMBER='(1)';
      PIN_TYPE='UNSPEC';
      PINUSE='UNSPEC';
    'B':
      PIN_GROUP='1';
      PIN_NUMBER='(2)';
      PIN_TYPE='UNSPEC';
      PINUSE='UNSPEC';
  end_pin;
  body
      PART_NAME='Q_RES';
      PHYS_DES_PREFIX='R';
      STANDARD='End of Design';
      LIFECYCLE='Comp-Approve';
      PART_NUMBER='CS02202FB02';
      JEDEC_TYPE='R0402';
      ALT_SYMBOLS='(R0402-0201)';
      VALUE='22';
      TOL='1%';
      WATTAGE='1/16W';
      CLASS='IO';
      DESCRIPTION='RES CHIP 22 1/16W +-1%(0402)EF';
      COMPONENT_TYPE='CHIP0402';
      LEAD_LENGTH='';
      DFM_EXCLUSION='';
      DAY='20180212';
      PARENT_PART_TYPE='Q_RES';
      PARENT_PPT='Q_RES';
      PARENT_PPT_PART='Q_RES_0402LF-22,1%,1/16W,EMPTY,CS02202FB02';
  end_body;
end_primitive;
primitive 'Q_RES_0402LF-22.1K,1%,1/16W,CHIP,CS32212FB02';
  pin
    'A':
      PIN_GROUP='1';
      PIN_NUMBER='(1)';
      PIN_TYPE='UNSPEC';
      PINUSE='UNSPEC';
    'B':
      PIN_GROUP='1';
      PIN_NUMBER='(2)';
      PIN_TYPE='UNSPEC';
      PINUSE='UNSPEC';
  end_pin;
  body
      PART_NAME='Q_RES';
      PHYS_DES_PREFIX='R';
      STANDARD='End of Design';
      LIFECYCLE='Comp-Approve';
      PART_NUMBER='CS32212FB02';
      JEDEC_TYPE='R0402';
      ALT_SYMBOLS='(R0402-0201)';
      VALUE='22.1K';
      TOL='1%';
      WATTAGE='1/16W';
      CLASS='DISCRETE';
      DESCRIPTION='RES CHIP 22.1K 1/16W +-1%(0402)EF';
      COMPONENT_TYPE='CHIPR0402';
      LEAD_LENGTH='';
      DFM_EXCLUSION='';
      DAY='20180208';
      PARENT_PART_TYPE='Q_RES';
      PARENT_PPT='Q_RES';
      PARENT_PPT_PART='Q_RES_0402LF-22.1K,1%,1/16W,CHIP,CS32212FB02';
  end_body;
end_primitive;
primitive 'Q_RES_0402LF-23.2K,1%,1/16W,CHIP,CS32322FB03';
  pin
    'A':
      PIN_GROUP='1';
      PIN_NUMBER='(1)';
      PIN_TYPE='UNSPEC';
      PINUSE='UNSPEC';
    'B':
      PIN_GROUP='1';
      PIN_NUMBER='(2)';
      PIN_TYPE='UNSPEC';
      PINUSE='UNSPEC';
  end_pin;
  body
      PART_NAME='Q_RES';
      PHYS_DES_PREFIX='R';
      STANDARD='End of Design';
      LIFECYCLE='Comp-Approve';
      PART_NUMBER='CS32322FB03';
      JEDEC_TYPE='R0402';
      ALT_SYMBOLS='(R0402-0201)';
      VALUE='23.2K';
      TOL='1%';
      WATTAGE='1/16W';
      CLASS='DISCRETE';
      DESCRIPTION='RES CHIP 23.2K 1/16W +-1%(0402)EF';
      COMPONENT_TYPE='CHIPR0402';
      LEAD_LENGTH='';
      DFM_EXCLUSION='';
      DAY='20210720';
      PARENT_PART_TYPE='Q_RES';
      PARENT_PPT='Q_RES';
      PARENT_PPT_PART='Q_RES_0402LF-23.2K,1%,1/16W,CHIP,CS32322FB03';
  end_body;
end_primitive;
primitive 'Q_RES_0402LF-24.3K,1%,1/16W,CHIP,CS32432FB03';
  pin
    'A':
      PIN_GROUP='1';
      PIN_NUMBER='(1)';
      PIN_TYPE='UNSPEC';
      PINUSE='UNSPEC';
    'B':
      PIN_GROUP='1';
      PIN_NUMBER='(2)';
      PIN_TYPE='UNSPEC';
      PINUSE='UNSPEC';
  end_pin;
  body
      PART_NAME='Q_RES';
      PHYS_DES_PREFIX='R';
      STANDARD='';
      LIFECYCLE='';
      PART_NUMBER='CS32432FB03';
      JEDEC_TYPE='R0402';
      ALT_SYMBOLS='(R0402-0201)';
      VALUE='24.3K';
      TOL='1%';
      WATTAGE='1/16W';
      CLASS='DISCRETE';
      DESCRIPTION='RES CHIP 24.3K 1/16W +-1%(0402)EF';
      COMPONENT_TYPE='CHIPR0402';
      LEAD_LENGTH='';
      DFM_EXCLUSION='';
      DAY='20190717';
      PARENT_PART_TYPE='Q_RES';
      PARENT_PPT='Q_RES';
      PARENT_PPT_PART='Q_RES_0402LF-24.3K,1%,1/16W,CHIP,CS32432FB03';
  end_body;
end_primitive;
primitive 'Q_RES_0402LF-249,1%,1/16W,CHIP,CS12492FB02';
  pin
    'A':
      PIN_GROUP='1';
      PIN_NUMBER='(1)';
      PIN_TYPE='UNSPEC';
      PINUSE='UNSPEC';
    'B':
      PIN_GROUP='1';
      PIN_NUMBER='(2)';
      PIN_TYPE='UNSPEC';
      PINUSE='UNSPEC';
  end_pin;
  body
      PART_NAME='Q_RES';
      PHYS_DES_PREFIX='R';
      STANDARD='End of Design';
      LIFECYCLE='Comp-Approve';
      PART_NUMBER='CS12492FB02';
      JEDEC_TYPE='R0402';
      ALT_SYMBOLS='(R0402-0201)';
      VALUE='249';
      TOL='1%';
      WATTAGE='1/16W';
      CLASS='DISCRETE';
      DESCRIPTION='RES CHIP 249 1/16W +-1%(0402)EF';
      COMPONENT_TYPE='CHIPR0402';
      LEAD_LENGTH='';
      DFM_EXCLUSION='';
      DAY='20190904';
      PARENT_PART_TYPE='Q_RES';
      PARENT_PPT='Q_RES';
      PARENT_PPT_PART='Q_RES_0402LF-249,1%,1/16W,CHIP,CS12492FB02';
  end_body;
end_primitive;
primitive 'Q_RES_0402LF-25.5K,1%,1/16W,CHIP,CS32552FB06';
  pin
    'A':
      PIN_GROUP='1';
      PIN_NUMBER='(1)';
      PIN_TYPE='UNSPEC';
      PINUSE='UNSPEC';
    'B':
      PIN_GROUP='1';
      PIN_NUMBER='(2)';
      PIN_TYPE='UNSPEC';
      PINUSE='UNSPEC';
  end_pin;
  body
      PART_NAME='Q_RES';
      PHYS_DES_PREFIX='R';
      STANDARD='End of Design';
      LIFECYCLE='Comp-Approve';
      PART_NUMBER='CS32552FB06';
      JEDEC_TYPE='R0402';
      ALT_SYMBOLS='(R0402-0201)';
      VALUE='25.5K';
      TOL='1%';
      WATTAGE='1/16W';
      CLASS='DISCRETE';
      DESCRIPTION='RES CHIP 25.5K 1/16W +-1%(0402)EF';
      COMPONENT_TYPE='CHIPR0402';
      LEAD_LENGTH='';
      DFM_EXCLUSION='';
      DAY='20180221';
      PARENT_PART_TYPE='Q_RES';
      PARENT_PPT='Q_RES';
      PARENT_PPT_PART='Q_RES_0402LF-25.5K,1%,1/16W,CHIP,CS32552FB06';
  end_body;
end_primitive;
primitive 'Q_RES_0402LF-26.7K,1%,1/16W,EMPTY,CS32672FB03';
  pin
    'A':
      PIN_GROUP='1';
      PIN_NUMBER='(1)';
      PIN_TYPE='UNSPEC';
      PINUSE='UNSPEC';
    'B':
      PIN_GROUP='1';
      PIN_NUMBER='(2)';
      PIN_TYPE='UNSPEC';
      PINUSE='UNSPEC';
  end_pin;
  body
      PART_NAME='Q_RES';
      PHYS_DES_PREFIX='R';
      STANDARD='End of Design';
      LIFECYCLE='Comp-Approve';
      PART_NUMBER='CS32672FB03';
      JEDEC_TYPE='R0402';
      ALT_SYMBOLS='(R0402-0201)';
      VALUE='26.7K';
      TOL='1%';
      WATTAGE='1/16W';
      CLASS='IO';
      DESCRIPTION='RES CHIP 26.7K 1/16W +-1%(0402)EF';
      COMPONENT_TYPE='CHIPR0402';
      LEAD_LENGTH='';
      DFM_EXCLUSION='';
      DAY='20190906';
      PARENT_PART_TYPE='Q_RES';
      PARENT_PPT='Q_RES';
      PARENT_PPT_PART='Q_RES_0402LF-26.7K,1%,1/16W,EMPTY,CS32672FB03';
  end_body;
end_primitive;
primitive 'Q_RES_0402LF-267K,1%,1/16W,EMPTY,CS42672FB03';
  pin
    'A':
      PIN_GROUP='1';
      PIN_NUMBER='(1)';
      PIN_TYPE='UNSPEC';
      PINUSE='UNSPEC';
    'B':
      PIN_GROUP='1';
      PIN_NUMBER='(2)';
      PIN_TYPE='UNSPEC';
      PINUSE='UNSPEC';
  end_pin;
  body
      PART_NAME='Q_RES';
      PHYS_DES_PREFIX='R';
      STANDARD='End of Design';
      LIFECYCLE='Comp-Approve';
      PART_NUMBER='CS42672FB03';
      JEDEC_TYPE='R0402';
      ALT_SYMBOLS='(R0402-0201)';
      VALUE='267K';
      TOL='1%';
      WATTAGE='1/16W';
      CLASS='IO';
      DESCRIPTION='RES CHIP 267K 1/16W +-1%(0402)EF';
      COMPONENT_TYPE='CHIPR0402';
      LEAD_LENGTH='';
      DFM_EXCLUSION='';
      DAY='20180208';
      PARENT_PART_TYPE='Q_RES';
      PARENT_PPT='Q_RES';
      PARENT_PPT_PART='Q_RES_0402LF-267K,1%,1/16W,EMPTY,CS42672FB03';
  end_body;
end_primitive;
primitive 'Q_RES_0402LF-27,5%,1/16W,CHIP,CS02702JB02';
  pin
    'A':
      PIN_GROUP='1';
      PIN_NUMBER='(1)';
      PIN_TYPE='UNSPEC';
      PINUSE='UNSPEC';
    'B':
      PIN_GROUP='1';
      PIN_NUMBER='(2)';
      PIN_TYPE='UNSPEC';
      PINUSE='UNSPEC';
  end_pin;
  body
      PART_NAME='Q_RES';
      PHYS_DES_PREFIX='R';
      STANDARD='End of Design';
      LIFECYCLE='Comp-Approve';
      PART_NUMBER='CS02702JB02';
      JEDEC_TYPE='R0402';
      ALT_SYMBOLS='(R0402-0201)';
      VALUE='27';
      TOL='5%';
      WATTAGE='1/16W';
      CLASS='DISCRETE';
      DESCRIPTION='RES CHIP 27 1/16W +-5%(0402)EF';
      COMPONENT_TYPE='CHIPR0402';
      LEAD_LENGTH='';
      DFM_EXCLUSION='';
      DAY='20190729';
      PARENT_PART_TYPE='Q_RES';
      PARENT_PPT='Q_RES';
      PARENT_PPT_PART='Q_RES_0402LF-27,5%,1/16W,CHIP,CS02702JB02';
  end_body;
end_primitive;
primitive 'Q_RES_0402LF-27.4,1%,1/16W,CHIP,CS02742FB03';
  pin
    'A':
      PIN_GROUP='1';
      PIN_NUMBER='(1)';
      PIN_TYPE='UNSPEC';
      PINUSE='UNSPEC';
    'B':
      PIN_GROUP='1';
      PIN_NUMBER='(2)';
      PIN_TYPE='UNSPEC';
      PINUSE='UNSPEC';
  end_pin;
  body
      PART_NAME='Q_RES';
      PHYS_DES_PREFIX='R';
      STANDARD='End of Design';
      LIFECYCLE='Comp-Release Qty';
      PART_NUMBER='CS02742FB03';
      JEDEC_TYPE='R0402';
      ALT_SYMBOLS='(R0402-0201)';
      VALUE='27.4';
      TOL='1%';
      WATTAGE='1/16W';
      CLASS='DISCRETE';
      DESCRIPTION='RES CHIP 27.4 1/16W +-1%(0402)EF';
      COMPONENT_TYPE='CHIPR0402';
      LEAD_LENGTH='';
      DFM_EXCLUSION='';
      DAY='20180221';
      PARENT_PART_TYPE='Q_RES';
      PARENT_PPT='Q_RES';
      PARENT_PPT_PART='Q_RES_0402LF-27.4,1%,1/16W,CHIP,CS02742FB03';
  end_body;
end_primitive;
primitive 'Q_RES_0402LF-2K,0.1%,1/16W,CHIP,CS22002BB07';
  pin
    'A':
      PIN_GROUP='1';
      PIN_NUMBER='(1)';
      PIN_TYPE='UNSPEC';
      PINUSE='UNSPEC';
    'B':
      PIN_GROUP='1';
      PIN_NUMBER='(2)';
      PIN_TYPE='UNSPEC';
      PINUSE='UNSPEC';
  end_pin;
  body
      PART_NAME='Q_RES';
      PHYS_DES_PREFIX='R';
      STANDARD='';
      LIFECYCLE='';
      PART_NUMBER='CS22002BB07';
      JEDEC_TYPE='R0402';
      ALT_SYMBOLS='(R0402-0201)';
      VALUE='2K';
      TOL='0.1%';
      WATTAGE='1/16W';
      CLASS='DISCRETE';
      DESCRIPTION='RES CHIP 2K 1/16W +-0.1%(0402)EF';
      COMPONENT_TYPE='CHIPR0402';
      LEAD_LENGTH='';
      DFM_EXCLUSION='';
      DAY='20211207';
      PARENT_PART_TYPE='Q_RES';
      PARENT_PPT='Q_RES';
      PARENT_PPT_PART='Q_RES_0402LF-2K,0.1%,1/16W,CHIP,CS22002BB07';
  end_body;
end_primitive;
primitive 'Q_RES_0402LF-2K,1%,1/16W,CHIP,CS22002FB07';
  pin
    'A':
      PIN_GROUP='1';
      PIN_NUMBER='(1)';
      PIN_TYPE='UNSPEC';
      PINUSE='UNSPEC';
    'B':
      PIN_GROUP='1';
      PIN_NUMBER='(2)';
      PIN_TYPE='UNSPEC';
      PINUSE='UNSPEC';
  end_pin;
  body
      PART_NAME='Q_RES';
      PHYS_DES_PREFIX='R';
      STANDARD='End of Design';
      LIFECYCLE='Comp-Approve';
      PART_NUMBER='CS22002FB07';
      JEDEC_TYPE='R0402';
      ALT_SYMBOLS='(R0402-0201)';
      VALUE='2K';
      TOL='1%';
      WATTAGE='1/16W';
      CLASS='DISCRETE';
      DESCRIPTION='RES CHIP 2K 1/16W +-1%(0402)EF';
      COMPONENT_TYPE='CHIPR0402';
      LEAD_LENGTH='';
      DFM_EXCLUSION='';
      DAY='20180221';
      PARENT_PART_TYPE='Q_RES';
      PARENT_PPT='Q_RES';
      PARENT_PPT_PART='Q_RES_0402LF-2K,1%,1/16W,CHIP,CS22002FB07';
  end_body;
end_primitive;
primitive 'Q_RES_0402LF-2K,1%,1/16W,EMPTY,CS22002FB07';
  pin
    'A':
      PIN_GROUP='1';
      PIN_NUMBER='(1)';
      PIN_TYPE='UNSPEC';
      PINUSE='UNSPEC';
    'B':
      PIN_GROUP='1';
      PIN_NUMBER='(2)';
      PIN_TYPE='UNSPEC';
      PINUSE='UNSPEC';
  end_pin;
  body
      PART_NAME='Q_RES';
      PHYS_DES_PREFIX='R';
      STANDARD='End of Design';
      LIFECYCLE='Comp-Approve';
      PART_NUMBER='CS22002FB07';
      JEDEC_TYPE='R0402';
      ALT_SYMBOLS='(R0402-0201)';
      VALUE='2K';
      TOL='1%';
      WATTAGE='1/16W';
      CLASS='IO';
      DESCRIPTION='RES CHIP 2K 1/16W +-1%(0402)EF';
      COMPONENT_TYPE='CHIPR0402';
      LEAD_LENGTH='';
      DFM_EXCLUSION='';
      DAY='20180221';
      PARENT_PART_TYPE='Q_RES';
      PARENT_PPT='Q_RES';
      PARENT_PPT_PART='Q_RES_0402LF-2K,1%,1/16W,EMPTY,CS22002FB07';
  end_body;
end_primitive;
primitive 'Q_RES_0402LF-2K,5%,1/16W,EMPTY,TMP_QCS22002JB29';
  pin
    'A':
      PIN_GROUP='1';
      PIN_NUMBER='(1)';
      PIN_TYPE='UNSPEC';
      PINUSE='UNSPEC';
    'B':
      PIN_GROUP='1';
      PIN_NUMBER='(2)';
      PIN_TYPE='UNSPEC';
      PINUSE='UNSPEC';
  end_pin;
  body
      PART_NAME='Q_RES';
      PHYS_DES_PREFIX='R';
      STANDARD='End of Design';
      LIFECYCLE='Comp-Approve';
      PART_NUMBER='CS22002JB29';
      JEDEC_TYPE='R0402';
      ALT_SYMBOLS='(R0402-0201)';
      VALUE='2K';
      TOL='5%';
      WATTAGE='1/16W';
      CLASS='IO';
      DESCRIPTION='RES CHIP 2K(1/16W +-5% 0402)';
      COMPONENT_TYPE='CHIP0402';
      LEAD_LENGTH='';
      DFM_EXCLUSION='';
      DAY='20100603';
      PARENT_PART_TYPE='Q_RES';
      PARENT_PPT='Q_RES';
      PARENT_PPT_PART='Q_RES_0402LF-2K,5%,1/16W,EMPTY,TMP_QCS22002JB29';
  end_body;
end_primitive;
primitive 'Q_RES_0402LF-3.09K,1%,1/16W,CHIP,CS23092FB04';
  pin
    'A':
      PIN_GROUP='1';
      PIN_NUMBER='(1)';
      PIN_TYPE='UNSPEC';
      PINUSE='UNSPEC';
    'B':
      PIN_GROUP='1';
      PIN_NUMBER='(2)';
      PIN_TYPE='UNSPEC';
      PINUSE='UNSPEC';
  end_pin;
  body
      PART_NAME='Q_RES';
      PHYS_DES_PREFIX='R';
      STANDARD='';
      LIFECYCLE='';
      PART_NUMBER='CS23092FB04';
      JEDEC_TYPE='R0402';
      ALT_SYMBOLS='(R0402-0201)';
      VALUE='3.09K';
      TOL='1%';
      WATTAGE='1/16W';
      CLASS='DISCRETE';
      DESCRIPTION='RES CHIP 3.09K 1/16W +-1%(0402)EF';
      COMPONENT_TYPE='CHIPR0402';
      LEAD_LENGTH='';
      DFM_EXCLUSION='';
      DAY='20220209';
      PARENT_PART_TYPE='Q_RES';
      PARENT_PPT='Q_RES';
      PARENT_PPT_PART='Q_RES_0402LF-3.09K,1%,1/16W,CHIP,CS23092FB04';
  end_body;
end_primitive;
primitive 'Q_RES_0402LF-3.9K,5%,1/16W,EMPTY,CS23902JB04';
  pin
    'A':
      PIN_GROUP='1';
      PIN_NUMBER='(1)';
      PIN_TYPE='UNSPEC';
      PINUSE='UNSPEC';
    'B':
      PIN_GROUP='1';
      PIN_NUMBER='(2)';
      PIN_TYPE='UNSPEC';
      PINUSE='UNSPEC';
  end_pin;
  body
      PART_NAME='Q_RES';
      PHYS_DES_PREFIX='R';
      STANDARD='End of Design';
      LIFECYCLE='Comp-Approve';
      PART_NUMBER='CS23902JB04';
      JEDEC_TYPE='R0402';
      ALT_SYMBOLS='(R0402-0201)';
      VALUE='3.9K';
      TOL='5%';
      WATTAGE='1/16W';
      CLASS='IO';
      DESCRIPTION='RES CHIP 3.9K 1/16W +-5%(0402)EF';
      COMPONENT_TYPE='CHIPR0402';
      LEAD_LENGTH='';
      DFM_EXCLUSION='';
      DAY='20210715';
      PARENT_PART_TYPE='Q_RES';
      PARENT_PPT='Q_RES';
      PARENT_PPT_PART='Q_RES_0402LF-3.9K,5%,1/16W,EMPTY,CS23902JB04';
  end_body;
end_primitive;
primitive 'Q_RES_0402LF-30.1K,1%,1/16W,CHIP,CS33012FB03';
  pin
    'A':
      PIN_GROUP='1';
      PIN_NUMBER='(1)';
      PIN_TYPE='UNSPEC';
      PINUSE='UNSPEC';
    'B':
      PIN_GROUP='1';
      PIN_NUMBER='(2)';
      PIN_TYPE='UNSPEC';
      PINUSE='UNSPEC';
  end_pin;
  body
      PART_NAME='Q_RES';
      PHYS_DES_PREFIX='R';
      STANDARD='End of Design';
      LIFECYCLE='Comp-Approve';
      PART_NUMBER='CS33012FB03';
      JEDEC_TYPE='R0402';
      ALT_SYMBOLS='(R0402-0201)';
      VALUE='30.1K';
      TOL='1%';
      WATTAGE='1/16W';
      CLASS='DISCRETE';
      DESCRIPTION='RES CHIP 30.1K 1/16W +-1%(0402)EF';
      COMPONENT_TYPE='CHIPR0402';
      LEAD_LENGTH='';
      DFM_EXCLUSION='';
      DAY='20210715';
      PARENT_PART_TYPE='Q_RES';
      PARENT_PPT='Q_RES';
      PARENT_PPT_PART='Q_RES_0402LF-30.1K,1%,1/16W,CHIP,CS33012FB03';
  end_body;
end_primitive;
primitive 'Q_RES_0402LF-30K,1%,1/16W,CHIP,CS33002FB02';
  pin
    'A':
      PIN_GROUP='1';
      PIN_NUMBER='(1)';
      PIN_TYPE='UNSPEC';
      PINUSE='UNSPEC';
    'B':
      PIN_GROUP='1';
      PIN_NUMBER='(2)';
      PIN_TYPE='UNSPEC';
      PINUSE='UNSPEC';
  end_pin;
  body
      PART_NAME='Q_RES';
      PHYS_DES_PREFIX='R';
      STANDARD='End of Design';
      LIFECYCLE='Comp-Approve';
      PART_NUMBER='CS33002FB02';
      JEDEC_TYPE='R0402';
      ALT_SYMBOLS='(R0402-0201)';
      VALUE='30K';
      TOL='1%';
      WATTAGE='1/16W';
      CLASS='DISCRETE';
      DESCRIPTION='RES CHIP 30K 1/16W +-1%(0402)EF';
      COMPONENT_TYPE='CHIPR0402';
      LEAD_LENGTH='';
      DFM_EXCLUSION='';
      DAY='20220616';
      PARENT_PART_TYPE='Q_RES';
      PARENT_PPT='Q_RES';
      PARENT_PPT_PART='Q_RES_0402LF-30K,1%,1/16W,CHIP,CS33002FB02';
  end_body;
end_primitive;
primitive 'Q_RES_0402LF-30K,1%,1/16W,EMPTY,CS33002FB02';
  pin
    'A':
      PIN_GROUP='1';
      PIN_NUMBER='(1)';
      PIN_TYPE='UNSPEC';
      PINUSE='UNSPEC';
    'B':
      PIN_GROUP='1';
      PIN_NUMBER='(2)';
      PIN_TYPE='UNSPEC';
      PINUSE='UNSPEC';
  end_pin;
  body
      PART_NAME='Q_RES';
      PHYS_DES_PREFIX='R';
      STANDARD='End of Design';
      LIFECYCLE='Comp-Approve';
      PART_NUMBER='CS33002FB02';
      JEDEC_TYPE='R0402';
      ALT_SYMBOLS='(R0402-0201)';
      VALUE='30K';
      TOL='1%';
      WATTAGE='1/16W';
      CLASS='IO';
      DESCRIPTION='RES CHIP 30K 1/16W +-1%(0402)EF';
      COMPONENT_TYPE='CHIPR0402';
      LEAD_LENGTH='';
      DFM_EXCLUSION='';
      DAY='20220616';
      PARENT_PART_TYPE='Q_RES';
      PARENT_PPT='Q_RES';
      PARENT_PPT_PART='Q_RES_0402LF-30K,1%,1/16W,EMPTY,CS33002FB02';
  end_body;
end_primitive;
primitive 'Q_RES_0402LF-31.6K,1%,1/16W,CHIP,CS33162FB02';
  pin
    'A':
      PIN_GROUP='1';
      PIN_NUMBER='(1)';
      PIN_TYPE='UNSPEC';
      PINUSE='UNSPEC';
    'B':
      PIN_GROUP='1';
      PIN_NUMBER='(2)';
      PIN_TYPE='UNSPEC';
      PINUSE='UNSPEC';
  end_pin;
  body
      PART_NAME='Q_RES';
      PHYS_DES_PREFIX='R';
      STANDARD='End of Design';
      LIFECYCLE='Comp-Approve';
      PART_NUMBER='CS33162FB02';
      JEDEC_TYPE='R0402';
      ALT_SYMBOLS='(R0402-0201)';
      VALUE='31.6K';
      TOL='1%';
      WATTAGE='1/16W';
      CLASS='DISCRETE';
      DESCRIPTION='RES CHIP 31.6K 1/16W +-1%(0402)EF';
      COMPONENT_TYPE='CHIPR0402';
      LEAD_LENGTH='';
      DFM_EXCLUSION='';
      DAY='20190718';
      PARENT_PART_TYPE='Q_RES';
      PARENT_PPT='Q_RES';
      PARENT_PPT_PART='Q_RES_0402LF-31.6K,1%,1/16W,CHIP,CS33162FB02';
  end_body;
end_primitive;
primitive 'Q_RES_0402LF-33,5%,1/16W,CHIP,CS03302JB10';
  pin
    'A':
      PIN_GROUP='1';
      PIN_NUMBER='(1)';
      PIN_TYPE='UNSPEC';
      PINUSE='UNSPEC';
    'B':
      PIN_GROUP='1';
      PIN_NUMBER='(2)';
      PIN_TYPE='UNSPEC';
      PINUSE='UNSPEC';
  end_pin;
  body
      PART_NAME='Q_RES';
      PHYS_DES_PREFIX='R';
      STANDARD='End of Design';
      LIFECYCLE='Comp-Approve';
      PART_NUMBER='CS03302JB10';
      JEDEC_TYPE='R0402';
      ALT_SYMBOLS='(R0402-0201)';
      VALUE='33';
      TOL='5%';
      WATTAGE='1/16W';
      CLASS='DISCRETE';
      DESCRIPTION='RES CHIP 33 1/16W +-5%(0402)EF';
      COMPONENT_TYPE='CHIPR0402';
      LEAD_LENGTH='';
      DFM_EXCLUSION='';
      DAY='20190904';
      PARENT_PART_TYPE='Q_RES';
      PARENT_PPT='Q_RES';
      PARENT_PPT_PART='Q_RES_0402LF-33,5%,1/16W,CHIP,CS03302JB10';
  end_body;
end_primitive;
primitive 'Q_RES_0402LF-33,5%,1/16W,EMPTY,CS03302JB10';
  pin
    'A':
      PIN_GROUP='1';
      PIN_NUMBER='(1)';
      PIN_TYPE='UNSPEC';
      PINUSE='UNSPEC';
    'B':
      PIN_GROUP='1';
      PIN_NUMBER='(2)';
      PIN_TYPE='UNSPEC';
      PINUSE='UNSPEC';
  end_pin;
  body
      PART_NAME='Q_RES';
      PHYS_DES_PREFIX='R';
      STANDARD='End of Design';
      LIFECYCLE='Comp-Approve';
      PART_NUMBER='CS03302JB10';
      JEDEC_TYPE='R0402';
      ALT_SYMBOLS='(R0402-0201)';
      VALUE='33';
      TOL='5%';
      WATTAGE='1/16W';
      CLASS='IO';
      DESCRIPTION='RES CHIP 33 1/16W +-5%(0402)EF';
      COMPONENT_TYPE='CHIPR0402';
      LEAD_LENGTH='';
      DFM_EXCLUSION='';
      DAY='20190904';
      PARENT_PART_TYPE='Q_RES';
      PARENT_PPT='Q_RES';
      PARENT_PPT_PART='Q_RES_0402LF-33,5%,1/16W,EMPTY,CS03302JB10';
  end_body;
end_primitive;
primitive 'Q_RES_0402LF-33.2,1%,1/16W,CHIP,CS03322FB03';
  pin
    'A':
      PIN_GROUP='1';
      PIN_NUMBER='(1)';
      PIN_TYPE='UNSPEC';
      PINUSE='UNSPEC';
    'B':
      PIN_GROUP='1';
      PIN_NUMBER='(2)';
      PIN_TYPE='UNSPEC';
      PINUSE='UNSPEC';
  end_pin;
  body
      PART_NAME='Q_RES';
      PHYS_DES_PREFIX='R';
      STANDARD='End of Design';
      LIFECYCLE='Comp-Approve';
      PART_NUMBER='CS03322FB03';
      JEDEC_TYPE='R0402';
      ALT_SYMBOLS='(R0402-0201)';
      VALUE='33.2';
      TOL='1%';
      WATTAGE='1/16W';
      CLASS='DISCRETE';
      DESCRIPTION='RES CHIP 33.2 1/16W +-1%(0402)EF';
      COMPONENT_TYPE='CHIPR0402';
      LEAD_LENGTH='';
      DFM_EXCLUSION='';
      DAY='20180208';
      PARENT_PART_TYPE='Q_RES';
      PARENT_PPT='Q_RES';
      PARENT_PPT_PART='Q_RES_0402LF-33.2,1%,1/16W,CHIP,CS03322FB03';
  end_body;
end_primitive;
primitive 'Q_RES_0402LF-33.2,1%,1/16W,EMPTY,CS03322FB03';
  pin
    'A':
      PIN_GROUP='1';
      PIN_NUMBER='(1)';
      PIN_TYPE='UNSPEC';
      PINUSE='UNSPEC';
    'B':
      PIN_GROUP='1';
      PIN_NUMBER='(2)';
      PIN_TYPE='UNSPEC';
      PINUSE='UNSPEC';
  end_pin;
  body
      PART_NAME='Q_RES';
      PHYS_DES_PREFIX='R';
      STANDARD='End of Design';
      LIFECYCLE='Comp-Approve';
      PART_NUMBER='CS03322FB03';
      JEDEC_TYPE='R0402';
      ALT_SYMBOLS='(R0402-0201)';
      VALUE='33.2';
      TOL='1%';
      WATTAGE='1/16W';
      CLASS='IO';
      DESCRIPTION='RES CHIP 33.2 1/16W +-1%(0402)EF';
      COMPONENT_TYPE='CHIPR0402';
      LEAD_LENGTH='';
      DFM_EXCLUSION='';
      DAY='20180208';
      PARENT_PART_TYPE='Q_RES';
      PARENT_PPT='Q_RES';
      PARENT_PPT_PART='Q_RES_0402LF-33.2,1%,1/16W,EMPTY,CS03322FB03';
  end_body;
end_primitive;
primitive 'Q_RES_0402LF-33K,1%,1/16W,CHIP,CS33302FB00';
  pin
    'A':
      PIN_GROUP='1';
      PIN_NUMBER='(1)';
      PIN_TYPE='UNSPEC';
      PINUSE='UNSPEC';
    'B':
      PIN_GROUP='1';
      PIN_NUMBER='(2)';
      PIN_TYPE='UNSPEC';
      PINUSE='UNSPEC';
  end_pin;
  body
      PART_NAME='Q_RES';
      PHYS_DES_PREFIX='R';
      STANDARD='';
      LIFECYCLE='';
      PART_NUMBER='CS33302FB00';
      JEDEC_TYPE='R0402';
      ALT_SYMBOLS='(R0402-0201)';
      VALUE='33K';
      TOL='1%';
      WATTAGE='1/16W';
      CLASS='DISCRETE';
      DESCRIPTION='RES CHIP 33K 1/16W +-1%(0402)EF';
      COMPONENT_TYPE='CHIPR0402';
      LEAD_LENGTH='';
      DFM_EXCLUSION='';
      DAY='20180221';
      PARENT_PART_TYPE='Q_RES';
      PARENT_PPT='Q_RES';
      PARENT_PPT_PART='Q_RES_0402LF-33K,1%,1/16W,CHIP,CS33302FB00';
  end_body;
end_primitive;
primitive 'Q_RES_0402LF-35.7K,1%,1/16W,CHIP,CS33572FB01';
  pin
    'A':
      PIN_GROUP='1';
      PIN_NUMBER='(1)';
      PIN_TYPE='UNSPEC';
      PINUSE='UNSPEC';
    'B':
      PIN_GROUP='1';
      PIN_NUMBER='(2)';
      PIN_TYPE='UNSPEC';
      PINUSE='UNSPEC';
  end_pin;
  body
      PART_NAME='Q_RES';
      PHYS_DES_PREFIX='R';
      STANDARD='End of Design';
      LIFECYCLE='Comp-Approve';
      PART_NUMBER='CS33572FB01';
      JEDEC_TYPE='R0402';
      ALT_SYMBOLS='(R0402-0201)';
      VALUE='35.7K';
      TOL='1%';
      WATTAGE='1/16W';
      CLASS='DISCRETE';
      DESCRIPTION='RES CHIP 35.7K 1/16W +-1%(0402) EF';
      COMPONENT_TYPE='CHIPR0402';
      LEAD_LENGTH='';
      DFM_EXCLUSION='';
      DAY='20180221';
      PARENT_PART_TYPE='Q_RES';
      PARENT_PPT='Q_RES';
      PARENT_PPT_PART='Q_RES_0402LF-35.7K,1%,1/16W,CHIP,CS33572FB01';
  end_body;
end_primitive;
primitive 'Q_RES_0402LF-4.53K,1%,1/16W,CHIP,CS24532FB03';
  pin
    'A':
      PIN_GROUP='1';
      PIN_NUMBER='(1)';
      PIN_TYPE='UNSPEC';
      PINUSE='UNSPEC';
    'B':
      PIN_GROUP='1';
      PIN_NUMBER='(2)';
      PIN_TYPE='UNSPEC';
      PINUSE='UNSPEC';
  end_pin;
  body
      PART_NAME='Q_RES';
      PHYS_DES_PREFIX='R';
      STANDARD='End of Design';
      LIFECYCLE='Comp-Approve';
      PART_NUMBER='CS24532FB03';
      JEDEC_TYPE='R0402';
      ALT_SYMBOLS='(R0402-0201)';
      VALUE='4.53K';
      TOL='1%';
      WATTAGE='1/16W';
      CLASS='DISCRETE';
      DESCRIPTION='RES CHIP 4.53K 1/16W +-1%(0402)EF';
      COMPONENT_TYPE='CHIP0402';
      LEAD_LENGTH='';
      DFM_EXCLUSION='';
      DAY='20180212';
      PARENT_PART_TYPE='Q_RES';
      PARENT_PPT='Q_RES';
      PARENT_PPT_PART='Q_RES_0402LF-4.53K,1%,1/16W,CHIP,CS24532FB03';
  end_body;
end_primitive;
primitive 'Q_RES_0402LF-4.75K,1%,1/16W,CHIP,CS24752FB03';
  pin
    'A':
      PIN_GROUP='1';
      PIN_NUMBER='(1)';
      PIN_TYPE='UNSPEC';
      PINUSE='UNSPEC';
    'B':
      PIN_GROUP='1';
      PIN_NUMBER='(2)';
      PIN_TYPE='UNSPEC';
      PINUSE='UNSPEC';
  end_pin;
  body
      PART_NAME='Q_RES';
      PHYS_DES_PREFIX='R';
      STANDARD='End of Design';
      LIFECYCLE='Comp-Approve';
      PART_NUMBER='CS24752FB03';
      JEDEC_TYPE='R0402';
      ALT_SYMBOLS='(R0402-0201)';
      VALUE='4.75K';
      TOL='1%';
      WATTAGE='1/16W';
      CLASS='DISCRETE';
      DESCRIPTION='RES CHIP 4.75K 1/16W +-1%(0402)EF';
      COMPONENT_TYPE='CHIPR0402';
      LEAD_LENGTH='';
      DFM_EXCLUSION='';
      DAY='20190124';
      PARENT_PART_TYPE='Q_RES';
      PARENT_PPT='Q_RES';
      PARENT_PPT_PART='Q_RES_0402LF-4.75K,1%,1/16W,CHIP,CS24752FB03';
  end_body;
end_primitive;
primitive 'Q_RES_0402LF-4.75K,1%,1/16W,EMPTY,CS24752FB03';
  pin
    'A':
      PIN_GROUP='1';
      PIN_NUMBER='(1)';
      PIN_TYPE='UNSPEC';
      PINUSE='UNSPEC';
    'B':
      PIN_GROUP='1';
      PIN_NUMBER='(2)';
      PIN_TYPE='UNSPEC';
      PINUSE='UNSPEC';
  end_pin;
  body
      PART_NAME='Q_RES';
      PHYS_DES_PREFIX='R';
      STANDARD='End of Design';
      LIFECYCLE='Comp-Approve';
      PART_NUMBER='CS24752FB03';
      JEDEC_TYPE='R0402';
      ALT_SYMBOLS='(R0402-0201)';
      VALUE='4.75K';
      TOL='1%';
      WATTAGE='1/16W';
      CLASS='IO';
      DESCRIPTION='RES CHIP 4.75K 1/16W +-1%(0402)EF';
      COMPONENT_TYPE='CHIPR0402';
      LEAD_LENGTH='';
      DFM_EXCLUSION='';
      DAY='20190124';
      PARENT_PART_TYPE='Q_RES';
      PARENT_PPT='Q_RES';
      PARENT_PPT_PART='Q_RES_0402LF-4.75K,1%,1/16W,EMPTY,CS24752FB03';
  end_body;
end_primitive;
primitive 'Q_RES_0402LF-4.7K,1%,1/16W,CHIP,CS24702FB06';
  pin
    'A':
      PIN_GROUP='1';
      PIN_NUMBER='(1)';
      PIN_TYPE='UNSPEC';
      PINUSE='UNSPEC';
    'B':
      PIN_GROUP='1';
      PIN_NUMBER='(2)';
      PIN_TYPE='UNSPEC';
      PINUSE='UNSPEC';
  end_pin;
  body
      PART_NAME='Q_RES';
      PHYS_DES_PREFIX='R';
      STANDARD='End of Design';
      LIFECYCLE='Comp-Approve';
      PART_NUMBER='CS24702FB06';
      JEDEC_TYPE='R0402';
      ALT_SYMBOLS='(R0402-0201)';
      VALUE='4.7K';
      TOL='1%';
      WATTAGE='1/16W';
      CLASS='DISCRETE';
      DESCRIPTION='RES CHIP 4.7K 1/16W +-1%(0402)EF';
      COMPONENT_TYPE='CHIPR0402';
      LEAD_LENGTH='';
      DFM_EXCLUSION='';
      DAY='20180208';
      PARENT_PART_TYPE='Q_RES';
      PARENT_PPT='Q_RES';
      PARENT_PPT_PART='Q_RES_0402LF-4.7K,1%,1/16W,CHIP,CS24702FB06';
  end_body;
end_primitive;
primitive 'Q_RES_0402LF-4.7K,1%,1/16W,EMPTY,CS24702FB06';
  pin
    'A':
      PIN_GROUP='1';
      PIN_NUMBER='(1)';
      PIN_TYPE='UNSPEC';
      PINUSE='UNSPEC';
    'B':
      PIN_GROUP='1';
      PIN_NUMBER='(2)';
      PIN_TYPE='UNSPEC';
      PINUSE='UNSPEC';
  end_pin;
  body
      PART_NAME='Q_RES';
      PHYS_DES_PREFIX='R';
      STANDARD='End of Design';
      LIFECYCLE='Comp-Approve';
      PART_NUMBER='CS24702FB06';
      JEDEC_TYPE='R0402';
      ALT_SYMBOLS='(R0402-0201)';
      VALUE='4.7K';
      TOL='1%';
      WATTAGE='1/16W';
      CLASS='IO';
      DESCRIPTION='RES CHIP 4.7K 1/16W +-1%(0402)EF';
      COMPONENT_TYPE='CHIPR0402';
      LEAD_LENGTH='';
      DFM_EXCLUSION='';
      DAY='20180208';
      PARENT_PART_TYPE='Q_RES';
      PARENT_PPT='Q_RES';
      PARENT_PPT_PART='Q_RES_0402LF-4.7K,1%,1/16W,EMPTY,CS24702FB06';
  end_body;
end_primitive;
primitive 'Q_RES_0402LF-4.7K,5%,1/16W,CHIP,CS24702JB10';
  pin
    'A':
      PIN_GROUP='1';
      PIN_NUMBER='(1)';
      PIN_TYPE='UNSPEC';
      PINUSE='UNSPEC';
    'B':
      PIN_GROUP='1';
      PIN_NUMBER='(2)';
      PIN_TYPE='UNSPEC';
      PINUSE='UNSPEC';
  end_pin;
  body
      PART_NAME='Q_RES';
      PHYS_DES_PREFIX='R';
      STANDARD='End of Design';
      LIFECYCLE='Comp-Approve';
      PART_NUMBER='CS24702JB10';
      JEDEC_TYPE='R0402';
      ALT_SYMBOLS='(R0402-0201)';
      VALUE='4.7K';
      TOL='5%';
      WATTAGE='1/16W';
      CLASS='DISCRETE';
      DESCRIPTION='RES CHIP 4.7K 1/16W +-5%(0402)EF';
      COMPONENT_TYPE='CHIPR0402';
      LEAD_LENGTH='';
      DFM_EXCLUSION='';
      DAY='20190729';
      PARENT_PART_TYPE='Q_RES';
      PARENT_PPT='Q_RES';
      PARENT_PPT_PART='Q_RES_0402LF-4.7K,5%,1/16W,CHIP,CS24702JB10';
  end_body;
end_primitive;
primitive 'Q_RES_0402LF-4.7K,5%,1/16W,EMPTY,CS24702JB10';
  pin
    'A':
      PIN_GROUP='1';
      PIN_NUMBER='(1)';
      PIN_TYPE='UNSPEC';
      PINUSE='UNSPEC';
    'B':
      PIN_GROUP='1';
      PIN_NUMBER='(2)';
      PIN_TYPE='UNSPEC';
      PINUSE='UNSPEC';
  end_pin;
  body
      PART_NAME='Q_RES';
      PHYS_DES_PREFIX='R';
      STANDARD='End of Design';
      LIFECYCLE='Comp-Approve';
      PART_NUMBER='CS24702JB10';
      JEDEC_TYPE='R0402';
      ALT_SYMBOLS='(R0402-0201)';
      VALUE='4.7K';
      TOL='5%';
      WATTAGE='1/16W';
      CLASS='IO';
      DESCRIPTION='RES CHIP 4.7K 1/16W +-5%(0402)EF';
      COMPONENT_TYPE='CHIPR0402';
      LEAD_LENGTH='';
      DFM_EXCLUSION='';
      DAY='20190729';
      PARENT_PART_TYPE='Q_RES';
      PARENT_PPT='Q_RES';
      PARENT_PPT_PART='Q_RES_0402LF-4.7K,5%,1/16W,EMPTY,CS24702JB10';
  end_body;
end_primitive;
primitive 'Q_RES_0402LF-4.87K,1%,1/16W,EMPTY,CS24872FB01';
  pin
    'A':
      PIN_GROUP='1';
      PIN_NUMBER='(1)';
      PIN_TYPE='UNSPEC';
      PINUSE='UNSPEC';
    'B':
      PIN_GROUP='1';
      PIN_NUMBER='(2)';
      PIN_TYPE='UNSPEC';
      PINUSE='UNSPEC';
  end_pin;
  body
      PART_NAME='Q_RES';
      PHYS_DES_PREFIX='R';
      STANDARD='End of Design';
      LIFECYCLE='Comp-Approve';
      PART_NUMBER='CS24872FB01';
      JEDEC_TYPE='R0402';
      ALT_SYMBOLS='(R0402-0201)';
      VALUE='4.87K';
      TOL='1%';
      WATTAGE='1/16W';
      CLASS='IO';
      DESCRIPTION='RES CHIP 4.87K 1/16W +-1%(0402)EF';
      COMPONENT_TYPE='CHIPR0402';
      LEAD_LENGTH='';
      DFM_EXCLUSION='';
      DAY='20180221';
      PARENT_PART_TYPE='Q_RES';
      PARENT_PPT='Q_RES';
      PARENT_PPT_PART='Q_RES_0402LF-4.87K,1%,1/16W,EMPTY,CS24872FB01';
  end_body;
end_primitive;
primitive 'Q_RES_0402LF-4.87K,1%,1/16W,EMPTY,CS24872FB07';
  pin
    'A':
      PIN_GROUP='1';
      PIN_NUMBER='(1)';
      PIN_TYPE='UNSPEC';
      PINUSE='UNSPEC';
    'B':
      PIN_GROUP='1';
      PIN_NUMBER='(2)';
      PIN_TYPE='UNSPEC';
      PINUSE='UNSPEC';
  end_pin;
  body
      PART_NAME='Q_RES';
      PHYS_DES_PREFIX='R';
      STANDARD='End of Design';
      LIFECYCLE='Comp-Approve';
      PART_NUMBER='CS24872FB07';
      JEDEC_TYPE='R0402';
      ALT_SYMBOLS='(R0402-0201)';
      VALUE='4.87K';
      TOL='1%';
      WATTAGE='1/16W';
      CLASS='IO';
      DESCRIPTION='RES CHIP 4.87K 1/16W+-1%(0402)';
      COMPONENT_TYPE='CHIP0402';
      LEAD_LENGTH='';
      DFM_EXCLUSION='';
      DAY='20120730';
      PARENT_PART_TYPE='Q_RES';
      PARENT_PPT='Q_RES';
      PARENT_PPT_PART='Q_RES_0402LF-4.87K,1%,1/16W,EMPTY,CS24872FB07';
  end_body;
end_primitive;
primitive 'Q_RES_0402LF-4.99K,0.1%,1/16W,CHIP,CS24992BB04';
  pin
    'A':
      PIN_GROUP='1';
      PIN_NUMBER='(1)';
      PIN_TYPE='UNSPEC';
      PINUSE='UNSPEC';
    'B':
      PIN_GROUP='1';
      PIN_NUMBER='(2)';
      PIN_TYPE='UNSPEC';
      PINUSE='UNSPEC';
  end_pin;
  body
      PART_NAME='Q_RES';
      PHYS_DES_PREFIX='R';
      STANDARD='';
      LIFECYCLE='';
      PART_NUMBER='CS24992BB04';
      JEDEC_TYPE='R0402';
      ALT_SYMBOLS='(R0402-0201)';
      VALUE='4.99K';
      TOL='0.1%';
      WATTAGE='1/16W';
      CLASS='DISCRETE';
      DESCRIPTION='RES CHIP 4.99K 1/16W +-0.1%(0402)EF';
      COMPONENT_TYPE='CHIPR0402';
      LEAD_LENGTH='';
      DFM_EXCLUSION='';
      DAY='20211216';
      PARENT_PART_TYPE='Q_RES';
      PARENT_PPT='Q_RES';
      PARENT_PPT_PART='Q_RES_0402LF-4.99K,0.1%,1/16W,CHIP,CS24992BB04';
  end_body;
end_primitive;
primitive 'Q_RES_0402LF-4.99K,1%,1/16W,EMPTY,CS24992FB07';
  pin
    'A':
      PIN_GROUP='1';
      PIN_NUMBER='(1)';
      PIN_TYPE='UNSPEC';
      PINUSE='UNSPEC';
    'B':
      PIN_GROUP='1';
      PIN_NUMBER='(2)';
      PIN_TYPE='UNSPEC';
      PINUSE='UNSPEC';
  end_pin;
  body
      PART_NAME='Q_RES';
      PHYS_DES_PREFIX='R';
      STANDARD='End of Design';
      LIFECYCLE='Comp-Approve';
      PART_NUMBER='CS24992FB07';
      JEDEC_TYPE='R0402';
      ALT_SYMBOLS='(R0402-0201)';
      VALUE='4.99K';
      TOL='1%';
      WATTAGE='1/16W';
      CLASS='IO';
      DESCRIPTION='RES CHIP 4.99K 1/16W +-1%(0402)EF';
      COMPONENT_TYPE='CHIPR0402';
      LEAD_LENGTH='';
      DFM_EXCLUSION='';
      DAY='20190717';
      PARENT_PART_TYPE='Q_RES';
      PARENT_PPT='Q_RES';
      PARENT_PPT_PART='Q_RES_0402LF-4.99K,1%,1/16W,EMPTY,CS24992FB07';
  end_body;
end_primitive;
primitive 'Q_RES_0402LF-40.2K,1%,1/16W,CHIP,CS34022FB04';
  pin
    'A':
      PIN_GROUP='1';
      PIN_NUMBER='(1)';
      PIN_TYPE='UNSPEC';
      PINUSE='UNSPEC';
    'B':
      PIN_GROUP='1';
      PIN_NUMBER='(2)';
      PIN_TYPE='UNSPEC';
      PINUSE='UNSPEC';
  end_pin;
  body
      PART_NAME='Q_RES';
      PHYS_DES_PREFIX='R';
      STANDARD='End of Design';
      LIFECYCLE='Comp-Approve';
      PART_NUMBER='CS34022FB04';
      JEDEC_TYPE='R0402';
      ALT_SYMBOLS='(R0402-0201)';
      VALUE='40.2K';
      TOL='1%';
      WATTAGE='1/16W';
      CLASS='DISCRETE';
      DESCRIPTION='RES CHIP 40.2K 1/16W +-1%(0402)EF';
      COMPONENT_TYPE='CHIPR0402';
      LEAD_LENGTH='';
      DFM_EXCLUSION='';
      DAY='20191101';
      PARENT_PART_TYPE='Q_RES';
      PARENT_PPT='Q_RES';
      PARENT_PPT_PART='Q_RES_0402LF-40.2K,1%,1/16W,CHIP,CS34022FB04';
  end_body;
end_primitive;
primitive 'Q_RES_0402LF-46.4K,1%,1/16W,CHIP,CS34642FB02';
  pin
    'A':
      PIN_GROUP='1';
      PIN_NUMBER='(1)';
      PIN_TYPE='UNSPEC';
      PINUSE='UNSPEC';
    'B':
      PIN_GROUP='1';
      PIN_NUMBER='(2)';
      PIN_TYPE='UNSPEC';
      PINUSE='UNSPEC';
  end_pin;
  body
      PART_NAME='Q_RES';
      PHYS_DES_PREFIX='R';
      STANDARD='';
      LIFECYCLE='';
      PART_NUMBER='CS34642FB02';
      JEDEC_TYPE='R0402';
      ALT_SYMBOLS='(R0402-0201)';
      VALUE='46.4K';
      TOL='1%';
      WATTAGE='1/16W';
      CLASS='DISCRETE';
      DESCRIPTION='RES CHIP 46.4K 1/16W +-1%(0402)EF';
      COMPONENT_TYPE='CHIPR0402';
      LEAD_LENGTH='';
      DFM_EXCLUSION='';
      DAY='20200227';
      PARENT_PART_TYPE='Q_RES';
      PARENT_PPT='Q_RES';
      PARENT_PPT_PART='Q_RES_0402LF-46.4K,1%,1/16W,CHIP,CS34642FB02';
  end_body;
end_primitive;
primitive 'Q_RES_0402LF-470,1%,1/16W,CHIP,CS14702FB04';
  pin
    'A':
      PIN_GROUP='1';
      PIN_NUMBER='(1)';
      PIN_TYPE='UNSPEC';
      PINUSE='UNSPEC';
    'B':
      PIN_GROUP='1';
      PIN_NUMBER='(2)';
      PIN_TYPE='UNSPEC';
      PINUSE='UNSPEC';
  end_pin;
  body
      PART_NAME='Q_RES';
      PHYS_DES_PREFIX='R';
      STANDARD='End of Design';
      LIFECYCLE='Comp-Approve';
      PART_NUMBER='CS14702FB04';
      JEDEC_TYPE='R0402';
      ALT_SYMBOLS='(R0402-0201)';
      VALUE='470';
      TOL='1%';
      WATTAGE='1/16W';
      CLASS='DISCRETE';
      DESCRIPTION='RES CHIP 470 1/16W +-1%(0402)EF';
      COMPONENT_TYPE='CHIPR0402';
      LEAD_LENGTH='';
      DFM_EXCLUSION='';
      DAY='20210715';
      PARENT_PART_TYPE='Q_RES';
      PARENT_PPT='Q_RES';
      PARENT_PPT_PART='Q_RES_0402LF-470,1%,1/16W,CHIP,CS14702FB04';
  end_body;
end_primitive;
primitive 'Q_RES_0402LF-47K,0.1%,1/16W,CHIP,CS34702BB05';
  pin
    'A':
      PIN_GROUP='1';
      PIN_NUMBER='(1)';
      PIN_TYPE='UNSPEC';
      PINUSE='UNSPEC';
    'B':
      PIN_GROUP='1';
      PIN_NUMBER='(2)';
      PIN_TYPE='UNSPEC';
      PINUSE='UNSPEC';
  end_pin;
  body
      PART_NAME='Q_RES';
      PHYS_DES_PREFIX='R';
      STANDARD='';
      LIFECYCLE='';
      PART_NUMBER='CS34702BB05';
      JEDEC_TYPE='R0402';
      ALT_SYMBOLS='(R0402-0201)';
      VALUE='47K';
      TOL='0.1%';
      WATTAGE='1/16W';
      CLASS='DISCRETE';
      DESCRIPTION='RES CHIP 47K 1/16W +-0.1%(0402)EF';
      COMPONENT_TYPE='CHIPR0402';
      LEAD_LENGTH='';
      DFM_EXCLUSION='';
      DAY='20211028';
      PARENT_PART_TYPE='Q_RES';
      PARENT_PPT='Q_RES';
      PARENT_PPT_PART='Q_RES_0402LF-47K,0.1%,1/16W,CHIP,CS34702BB05';
  end_body;
end_primitive;
primitive 'Q_RES_0402LF-47K,0.1%,1/16W,EMPTY,CS34702BB05';
  pin
    'A':
      PIN_GROUP='1';
      PIN_NUMBER='(1)';
      PIN_TYPE='UNSPEC';
      PINUSE='UNSPEC';
    'B':
      PIN_GROUP='1';
      PIN_NUMBER='(2)';
      PIN_TYPE='UNSPEC';
      PINUSE='UNSPEC';
  end_pin;
  body
      PART_NAME='Q_RES';
      PHYS_DES_PREFIX='R';
      STANDARD='';
      LIFECYCLE='';
      PART_NUMBER='CS34702BB05';
      JEDEC_TYPE='R0402';
      ALT_SYMBOLS='(R0402-0201)';
      VALUE='47K';
      TOL='0.1%';
      WATTAGE='1/16W';
      CLASS='IO';
      DESCRIPTION='RES CHIP 47K 1/16W +-0.1%(0402)EF';
      COMPONENT_TYPE='CHIPR0402';
      LEAD_LENGTH='';
      DFM_EXCLUSION='';
      DAY='20211028';
      PARENT_PART_TYPE='Q_RES';
      PARENT_PPT='Q_RES';
      PARENT_PPT_PART='Q_RES_0402LF-47K,0.1%,1/16W,EMPTY,CS34702BB05';
  end_body;
end_primitive;
primitive 'Q_RES_0402LF-49.9,1%,1/16W,CHIP,CS04992FB07';
  pin
    'A':
      PIN_GROUP='1';
      PIN_NUMBER='(1)';
      PIN_TYPE='UNSPEC';
      PINUSE='UNSPEC';
    'B':
      PIN_GROUP='1';
      PIN_NUMBER='(2)';
      PIN_TYPE='UNSPEC';
      PINUSE='UNSPEC';
  end_pin;
  body
      PART_NAME='Q_RES';
      PHYS_DES_PREFIX='R';
      STANDARD='End of Design';
      LIFECYCLE='Comp-Approve';
      PART_NUMBER='CS04992FB07';
      JEDEC_TYPE='R0402';
      ALT_SYMBOLS='(R0402-0201)';
      VALUE='49.9';
      TOL='1%';
      WATTAGE='1/16W';
      CLASS='DISCRETE';
      DESCRIPTION='RES CHIP 49.9 1/16W +-1%(0402)EF';
      COMPONENT_TYPE='CHIPR0402';
      LEAD_LENGTH='';
      DFM_EXCLUSION='';
      DAY='20180208';
      PARENT_PART_TYPE='Q_RES';
      PARENT_PPT='Q_RES';
      PARENT_PPT_PART='Q_RES_0402LF-49.9,1%,1/16W,CHIP,CS04992FB07';
  end_body;
end_primitive;
primitive 'Q_RES_0402LF-49.9,1%,1/16W,EMPTY,CS04992FB07';
  pin
    'A':
      PIN_GROUP='1';
      PIN_NUMBER='(1)';
      PIN_TYPE='UNSPEC';
      PINUSE='UNSPEC';
    'B':
      PIN_GROUP='1';
      PIN_NUMBER='(2)';
      PIN_TYPE='UNSPEC';
      PINUSE='UNSPEC';
  end_pin;
  body
      PART_NAME='Q_RES';
      PHYS_DES_PREFIX='R';
      STANDARD='End of Design';
      LIFECYCLE='Comp-Approve';
      PART_NUMBER='CS04992FB07';
      JEDEC_TYPE='R0402';
      ALT_SYMBOLS='(R0402-0201)';
      VALUE='49.9';
      TOL='1%';
      WATTAGE='1/16W';
      CLASS='IO';
      DESCRIPTION='RES CHIP 49.9 1/16W +-1%(0402)EF';
      COMPONENT_TYPE='CHIPR0402';
      LEAD_LENGTH='';
      DFM_EXCLUSION='';
      DAY='20180208';
      PARENT_PART_TYPE='Q_RES';
      PARENT_PPT='Q_RES';
      PARENT_PPT_PART='Q_RES_0402LF-49.9,1%,1/16W,EMPTY,CS04992FB07';
  end_body;
end_primitive;
primitive 'Q_RES_0402LF-5.11K,1%,1/16W,CHIP,CS25112FB04';
  pin
    'A':
      PIN_GROUP='1';
      PIN_NUMBER='(1)';
      PIN_TYPE='UNSPEC';
      PINUSE='UNSPEC';
    'B':
      PIN_GROUP='1';
      PIN_NUMBER='(2)';
      PIN_TYPE='UNSPEC';
      PINUSE='UNSPEC';
  end_pin;
  body
      PART_NAME='Q_RES';
      PHYS_DES_PREFIX='R';
      STANDARD='End of Design';
      LIFECYCLE='Comp-Approve';
      PART_NUMBER='CS25112FB04';
      JEDEC_TYPE='R0402';
      ALT_SYMBOLS='(R0402-0201)';
      VALUE='5.11K';
      TOL='1%';
      WATTAGE='1/16W';
      CLASS='DISCRETE';
      DESCRIPTION='RES CHIP 5.11K 1/16W +-1%(0402)EF';
      COMPONENT_TYPE='CHIPR0402';
      LEAD_LENGTH='';
      DFM_EXCLUSION='';
      DAY='20190726';
      PARENT_PART_TYPE='Q_RES';
      PARENT_PPT='Q_RES';
      PARENT_PPT_PART='Q_RES_0402LF-5.11K,1%,1/16W,CHIP,CS25112FB04';
  end_body;
end_primitive;
primitive 'Q_RES_0402LF-5.23K,1%,1/16W,CHIP,CS25232FB08';
  pin
    'A':
      PIN_GROUP='1';
      PIN_NUMBER='(1)';
      PIN_TYPE='UNSPEC';
      PINUSE='UNSPEC';
    'B':
      PIN_GROUP='1';
      PIN_NUMBER='(2)';
      PIN_TYPE='UNSPEC';
      PINUSE='UNSPEC';
  end_pin;
  body
      PART_NAME='Q_RES';
      PHYS_DES_PREFIX='R';
      STANDARD='';
      LIFECYCLE='';
      PART_NUMBER='CS25232FB08';
      JEDEC_TYPE='R0402';
      ALT_SYMBOLS='(R0402-0201)';
      VALUE='5.23K';
      TOL='1%';
      WATTAGE='1/16W';
      CLASS='DISCRETE';
      DESCRIPTION='RES CHIP 5.23K 1/16W +-1%(0402)EF';
      COMPONENT_TYPE='CHIPR0402';
      LEAD_LENGTH='';
      DFM_EXCLUSION='';
      DAY='20210719';
      PARENT_PART_TYPE='Q_RES';
      PARENT_PPT='Q_RES';
      PARENT_PPT_PART='Q_RES_0402LF-5.23K,1%,1/16W,CHIP,CS25232FB08';
  end_body;
end_primitive;
primitive 'Q_RES_0402LF-5.36K,1%,1/16W,CHIP,CS25362FB02';
  pin
    'A':
      PIN_GROUP='1';
      PIN_NUMBER='(1)';
      PIN_TYPE='UNSPEC';
      PINUSE='UNSPEC';
    'B':
      PIN_GROUP='1';
      PIN_NUMBER='(2)';
      PIN_TYPE='UNSPEC';
      PINUSE='UNSPEC';
  end_pin;
  body
      PART_NAME='Q_RES';
      PHYS_DES_PREFIX='R';
      STANDARD='End of Design';
      LIFECYCLE='Comp-Approve';
      PART_NUMBER='CS25362FB02';
      JEDEC_TYPE='R0402';
      ALT_SYMBOLS='(R0402-0201)';
      VALUE='5.36K';
      TOL='1%';
      WATTAGE='1/16W';
      CLASS='DISCRETE';
      DESCRIPTION='RES CHIP 5.36K 1/16W +-1%(0402)EF';
      COMPONENT_TYPE='CHIPR0402';
      LEAD_LENGTH='';
      DFM_EXCLUSION='';
      DAY='20190906';
      PARENT_PART_TYPE='Q_RES';
      PARENT_PPT='Q_RES';
      PARENT_PPT_PART='Q_RES_0402LF-5.36K,1%,1/16W,CHIP,CS25362FB02';
  end_body;
end_primitive;
primitive 'Q_RES_0402LF-5.36K,1%,1/16W,EMPTY,CS25362FB02';
  pin
    'A':
      PIN_GROUP='1';
      PIN_NUMBER='(1)';
      PIN_TYPE='UNSPEC';
      PINUSE='UNSPEC';
    'B':
      PIN_GROUP='1';
      PIN_NUMBER='(2)';
      PIN_TYPE='UNSPEC';
      PINUSE='UNSPEC';
  end_pin;
  body
      PART_NAME='Q_RES';
      PHYS_DES_PREFIX='R';
      STANDARD='End of Design';
      LIFECYCLE='Comp-Approve';
      PART_NUMBER='CS25362FB02';
      JEDEC_TYPE='R0402';
      ALT_SYMBOLS='(R0402-0201)';
      VALUE='5.36K';
      TOL='1%';
      WATTAGE='1/16W';
      CLASS='IO';
      DESCRIPTION='RES CHIP 5.36K 1/16W +-1%(0402)EF';
      COMPONENT_TYPE='CHIPR0402';
      LEAD_LENGTH='';
      DFM_EXCLUSION='';
      DAY='20190906';
      PARENT_PART_TYPE='Q_RES';
      PARENT_PPT='Q_RES';
      PARENT_PPT_PART='Q_RES_0402LF-5.36K,1%,1/16W,EMPTY,CS25362FB02';
  end_body;
end_primitive;
primitive 'Q_RES_0402LF-5.6,1%,1/16W,CHIP,CS-5602FB01';
  pin
    'A':
      PIN_GROUP='1';
      PIN_NUMBER='(1)';
      PIN_TYPE='UNSPEC';
      PINUSE='UNSPEC';
    'B':
      PIN_GROUP='1';
      PIN_NUMBER='(2)';
      PIN_TYPE='UNSPEC';
      PINUSE='UNSPEC';
  end_pin;
  body
      PART_NAME='Q_RES';
      PHYS_DES_PREFIX='R';
      STANDARD='';
      LIFECYCLE='';
      PART_NUMBER='CS-5602FB01';
      JEDEC_TYPE='R0402';
      ALT_SYMBOLS='(R0402-0201)';
      VALUE='5.6';
      TOL='1%';
      WATTAGE='1/16W';
      CLASS='DISCRETE';
      DESCRIPTION='RES CHIP 5.6 1/16W 1%(0402)EF';
      COMPONENT_TYPE='CHIPR0402';
      LEAD_LENGTH='';
      DFM_EXCLUSION='';
      DAY='20221018';
      PARENT_PART_TYPE='Q_RES';
      PARENT_PPT='Q_RES';
      PARENT_PPT_PART='Q_RES_0402LF-5.6,1%,1/16W,CHIP,CS-5602FB01';
  end_body;
end_primitive;
primitive 'Q_RES_0402LF-51,5%,1/16W,EMPTY,CS05102JB04';
  pin
    'A':
      PIN_GROUP='1';
      PIN_NUMBER='(1)';
      PIN_TYPE='UNSPEC';
      PINUSE='UNSPEC';
    'B':
      PIN_GROUP='1';
      PIN_NUMBER='(2)';
      PIN_TYPE='UNSPEC';
      PINUSE='UNSPEC';
  end_pin;
  body
      PART_NAME='Q_RES';
      PHYS_DES_PREFIX='R';
      STANDARD='End of Design';
      LIFECYCLE='Comp-Approve';
      PART_NUMBER='CS05102JB04';
      JEDEC_TYPE='R0402';
      ALT_SYMBOLS='(R0402-0201)';
      VALUE='51';
      TOL='5%';
      WATTAGE='1/16W';
      CLASS='IO';
      DESCRIPTION='RES CHIP 51 1/16W +-5%(0402)EF';
      COMPONENT_TYPE='CHIP0402';
      LEAD_LENGTH='';
      DFM_EXCLUSION='';
      DAY='20180212';
      PARENT_PART_TYPE='Q_RES';
      PARENT_PPT='Q_RES';
      PARENT_PPT_PART='Q_RES_0402LF-51,5%,1/16W,EMPTY,CS05102JB04';
  end_body;
end_primitive;
primitive 'Q_RES_0402LF-510K,5%,1/16W,EMPTY,CS45102JB03';
  pin
    'A':
      PIN_GROUP='1';
      PIN_NUMBER='(1)';
      PIN_TYPE='UNSPEC';
      PINUSE='UNSPEC';
    'B':
      PIN_GROUP='1';
      PIN_NUMBER='(2)';
      PIN_TYPE='UNSPEC';
      PINUSE='UNSPEC';
  end_pin;
  body
      PART_NAME='Q_RES';
      PHYS_DES_PREFIX='R';
      STANDARD='End of Design';
      LIFECYCLE='Comp-Approve';
      PART_NUMBER='CS45102JB03';
      JEDEC_TYPE='R0402';
      ALT_SYMBOLS='(R0402-0201)';
      VALUE='510K';
      TOL='5%';
      WATTAGE='1/16W';
      CLASS='IO';
      DESCRIPTION='RES CHIP 510K 1/16W +-5%(0402)EF';
      COMPONENT_TYPE='CHIPR0402';
      LEAD_LENGTH='';
      DFM_EXCLUSION='';
      DAY='20180221';
      PARENT_PART_TYPE='Q_RES';
      PARENT_PPT='Q_RES';
      PARENT_PPT_PART='Q_RES_0402LF-510K,5%,1/16W,EMPTY,CS45102JB03';
  end_body;
end_primitive;
primitive 'Q_RES_0402LF-54.9K,1%,1/16W,CHIP,CS35492FB03';
  pin
    'A':
      PIN_GROUP='1';
      PIN_NUMBER='(1)';
      PIN_TYPE='UNSPEC';
      PINUSE='UNSPEC';
    'B':
      PIN_GROUP='1';
      PIN_NUMBER='(2)';
      PIN_TYPE='UNSPEC';
      PINUSE='UNSPEC';
  end_pin;
  body
      PART_NAME='Q_RES';
      PHYS_DES_PREFIX='R';
      STANDARD='End of Design';
      LIFECYCLE='Comp-Approve';
      PART_NUMBER='CS35492FB03';
      JEDEC_TYPE='R0402';
      ALT_SYMBOLS='(R0402-0201)';
      VALUE='54.9K';
      TOL='1%';
      WATTAGE='1/16W';
      CLASS='DISCRETE';
      DESCRIPTION='RES CHIP 54.9K 1/16W  +-1%(0402)EF';
      COMPONENT_TYPE='CHIPR0402';
      LEAD_LENGTH='';
      DFM_EXCLUSION='';
      DAY='20180221';
      PARENT_PART_TYPE='Q_RES';
      PARENT_PPT='Q_RES';
      PARENT_PPT_PART='Q_RES_0402LF-54.9K,1%,1/16W,CHIP,CS35492FB03';
  end_body;
end_primitive;
primitive 'Q_RES_0402LF-54.9K,1%,1/16W,EMPTY,CS35492FB03';
  pin
    'A':
      PIN_GROUP='1';
      PIN_NUMBER='(1)';
      PIN_TYPE='UNSPEC';
      PINUSE='UNSPEC';
    'B':
      PIN_GROUP='1';
      PIN_NUMBER='(2)';
      PIN_TYPE='UNSPEC';
      PINUSE='UNSPEC';
  end_pin;
  body
      PART_NAME='Q_RES';
      PHYS_DES_PREFIX='R';
      STANDARD='End of Design';
      LIFECYCLE='Comp-Approve';
      PART_NUMBER='CS35492FB03';
      JEDEC_TYPE='R0402';
      ALT_SYMBOLS='(R0402-0201)';
      VALUE='54.9K';
      TOL='1%';
      WATTAGE='1/16W';
      CLASS='IO';
      DESCRIPTION='RES CHIP 54.9K 1/16W  +-1%(0402)EF';
      COMPONENT_TYPE='CHIPR0402';
      LEAD_LENGTH='';
      DFM_EXCLUSION='';
      DAY='20180221';
      PARENT_PART_TYPE='Q_RES';
      PARENT_PPT='Q_RES';
      PARENT_PPT_PART='Q_RES_0402LF-54.9K,1%,1/16W,EMPTY,CS35492FB03';
  end_body;
end_primitive;
primitive 'Q_RES_0402LF-560,1%,1/16W,CHIP,CS15602FB03';
  pin
    'A':
      PIN_GROUP='1';
      PIN_NUMBER='(1)';
      PIN_TYPE='UNSPEC';
      PINUSE='UNSPEC';
    'B':
      PIN_GROUP='1';
      PIN_NUMBER='(2)';
      PIN_TYPE='UNSPEC';
      PINUSE='UNSPEC';
  end_pin;
  body
      PART_NAME='Q_RES';
      PHYS_DES_PREFIX='R';
      STANDARD='';
      LIFECYCLE='';
      PART_NUMBER='CS15602FB03';
      JEDEC_TYPE='R0402';
      ALT_SYMBOLS='(R0402-0201)';
      VALUE='560';
      TOL='1%';
      WATTAGE='1/16W';
      CLASS='DISCRETE';
      DESCRIPTION='RES CHIP 560 1/16W +-1%(0402)EF';
      COMPONENT_TYPE='CHIPR0402';
      LEAD_LENGTH='';
      DFM_EXCLUSION='';
      DAY='20190904';
      PARENT_PART_TYPE='Q_RES';
      PARENT_PPT='Q_RES';
      PARENT_PPT_PART='Q_RES_0402LF-560,1%,1/16W,CHIP,CS15602FB03';
  end_body;
end_primitive;
primitive 'Q_RES_0402LF-56K,1%,1/16W,CHIP,CS35602FB00';
  pin
    'A':
      PIN_GROUP='1';
      PIN_NUMBER='(1)';
      PIN_TYPE='UNSPEC';
      PINUSE='UNSPEC';
    'B':
      PIN_GROUP='1';
      PIN_NUMBER='(2)';
      PIN_TYPE='UNSPEC';
      PINUSE='UNSPEC';
  end_pin;
  body
      PART_NAME='Q_RES';
      PHYS_DES_PREFIX='R';
      STANDARD='';
      LIFECYCLE='';
      PART_NUMBER='CS35602FB00';
      JEDEC_TYPE='R0402';
      ALT_SYMBOLS='(R0402-0201)';
      VALUE='56K';
      TOL='1%';
      WATTAGE='1/16W';
      CLASS='DISCRETE';
      DESCRIPTION='RES CHIP 56K 1/16W +-1%(0402)EF';
      COMPONENT_TYPE='CHIPR0402';
      LEAD_LENGTH='';
      DFM_EXCLUSION='';
      DAY='20190711';
      PARENT_PART_TYPE='Q_RES';
      PARENT_PPT='Q_RES';
      PARENT_PPT_PART='Q_RES_0402LF-56K,1%,1/16W,CHIP,CS35602FB00';
  end_body;
end_primitive;
primitive 'Q_RES_0402LF-6.04K,1%,1/16W,CHIP,CS26042FB04';
  pin
    'A':
      PIN_GROUP='1';
      PIN_NUMBER='(1)';
      PIN_TYPE='UNSPEC';
      PINUSE='UNSPEC';
    'B':
      PIN_GROUP='1';
      PIN_NUMBER='(2)';
      PIN_TYPE='UNSPEC';
      PINUSE='UNSPEC';
  end_pin;
  body
      PART_NAME='Q_RES';
      PHYS_DES_PREFIX='R';
      STANDARD='End of Design';
      LIFECYCLE='Comp-Approve';
      PART_NUMBER='CS26042FB04';
      JEDEC_TYPE='R0402';
      ALT_SYMBOLS='(R0402-0201)';
      VALUE='6.04K';
      TOL='1%';
      WATTAGE='1/16W';
      CLASS='DISCRETE';
      DESCRIPTION='RES CHIP 6.04K 1/16W +-1%(0402)EF';
      COMPONENT_TYPE='CHIPR0402';
      LEAD_LENGTH='';
      DFM_EXCLUSION='';
      DAY='20190717';
      PARENT_PART_TYPE='Q_RES';
      PARENT_PPT='Q_RES';
      PARENT_PPT_PART='Q_RES_0402LF-6.04K,1%,1/16W,CHIP,CS26042FB04';
  end_body;
end_primitive;
primitive 'Q_RES_0402LF-6.19K,1%,1/16W,CHIP,CS26192FB03';
  pin
    'A':
      PIN_GROUP='1';
      PIN_NUMBER='(1)';
      PIN_TYPE='UNSPEC';
      PINUSE='UNSPEC';
    'B':
      PIN_GROUP='1';
      PIN_NUMBER='(2)';
      PIN_TYPE='UNSPEC';
      PINUSE='UNSPEC';
  end_pin;
  body
      PART_NAME='Q_RES';
      PHYS_DES_PREFIX='R';
      STANDARD='End of Design';
      LIFECYCLE='Comp-Approve';
      PART_NUMBER='CS26192FB03';
      JEDEC_TYPE='R0402';
      ALT_SYMBOLS='(R0402-0201)';
      VALUE='6.19K';
      TOL='1%';
      WATTAGE='1/16W';
      CLASS='DISCRETE';
      DESCRIPTION='RES CHIP 6.19K 1/16W +-1%(0402)EF';
      COMPONENT_TYPE='CHIPR0402';
      LEAD_LENGTH='';
      DFM_EXCLUSION='';
      DAY='20180221';
      PARENT_PART_TYPE='Q_RES';
      PARENT_PPT='Q_RES';
      PARENT_PPT_PART='Q_RES_0402LF-6.19K,1%,1/16W,CHIP,CS26192FB03';
  end_body;
end_primitive;
primitive 'Q_RES_0402LF-6.8K,1%,1/16W,CHIP,CS26802FB02';
  pin
    'A':
      PIN_GROUP='1';
      PIN_NUMBER='(1)';
      PIN_TYPE='UNSPEC';
      PINUSE='UNSPEC';
    'B':
      PIN_GROUP='1';
      PIN_NUMBER='(2)';
      PIN_TYPE='UNSPEC';
      PINUSE='UNSPEC';
  end_pin;
  body
      PART_NAME='Q_RES';
      PHYS_DES_PREFIX='R';
      STANDARD='';
      LIFECYCLE='';
      PART_NUMBER='CS26802FB02';
      JEDEC_TYPE='R0402';
      ALT_SYMBOLS='(R0402-0201)';
      VALUE='6.8K';
      TOL='1%';
      WATTAGE='1/16W';
      CLASS='DISCRETE';
      DESCRIPTION='RES CHIP 6.8K 1/16W +-1%(0402)EF';
      COMPONENT_TYPE='CHIP0402';
      LEAD_LENGTH='';
      DFM_EXCLUSION='';
      DAY='20180212';
      PARENT_PART_TYPE='Q_RES';
      PARENT_PPT='Q_RES';
      PARENT_PPT_PART='Q_RES_0402LF-6.8K,1%,1/16W,CHIP,CS26802FB02';
  end_body;
end_primitive;
primitive 'Q_RES_0402LF-6.98K,1%,1/16W,CHIP,CS26982FB08';
  pin
    'A':
      PIN_GROUP='1';
      PIN_NUMBER='(1)';
      PIN_TYPE='UNSPEC';
      PINUSE='UNSPEC';
    'B':
      PIN_GROUP='1';
      PIN_NUMBER='(2)';
      PIN_TYPE='UNSPEC';
      PINUSE='UNSPEC';
  end_pin;
  body
      PART_NAME='Q_RES';
      PHYS_DES_PREFIX='R';
      STANDARD='';
      LIFECYCLE='';
      PART_NUMBER='CS26982FB08';
      JEDEC_TYPE='R0402';
      ALT_SYMBOLS='(R0402-0201)';
      VALUE='6.98K';
      TOL='1%';
      WATTAGE='1/16W';
      CLASS='DISCRETE';
      DESCRIPTION='RES CHIP 6.98K 1/16W +-1%(0402)EF';
      COMPONENT_TYPE='CHIPR0402';
      LEAD_LENGTH='';
      DFM_EXCLUSION='';
      DAY='20190906';
      PARENT_PART_TYPE='Q_RES';
      PARENT_PPT='Q_RES';
      PARENT_PPT_PART='Q_RES_0402LF-6.98K,1%,1/16W,CHIP,CS26982FB08';
  end_body;
end_primitive;
primitive 'Q_RES_0402LF-60.4K,1%,1/16W,CHIP,CS36042FB04';
  pin
    'A':
      PIN_GROUP='1';
      PIN_NUMBER='(1)';
      PIN_TYPE='UNSPEC';
      PINUSE='UNSPEC';
    'B':
      PIN_GROUP='1';
      PIN_NUMBER='(2)';
      PIN_TYPE='UNSPEC';
      PINUSE='UNSPEC';
  end_pin;
  body
      PART_NAME='Q_RES';
      PHYS_DES_PREFIX='R';
      STANDARD='End of Design';
      LIFECYCLE='Comp-Approve';
      PART_NUMBER='CS36042FB04';
      JEDEC_TYPE='R0402';
      ALT_SYMBOLS='(R0402-0201)';
      VALUE='60.4K';
      TOL='1%';
      WATTAGE='1/16W';
      CLASS='DISCRETE';
      DESCRIPTION='RES CHIP 60.4K 1/16W +-1%(0402)EF';
      COMPONENT_TYPE='CHIP0402';
      LEAD_LENGTH='';
      DFM_EXCLUSION='';
      DAY='20180212';
      PARENT_PART_TYPE='Q_RES';
      PARENT_PPT='Q_RES';
      PARENT_PPT_PART='Q_RES_0402LF-60.4K,1%,1/16W,CHIP,CS36042FB04';
  end_body;
end_primitive;
primitive 'Q_RES_0402LF-63.4K,1%,1/16W,CHIP,CS36342FB04';
  pin
    'A':
      PIN_GROUP='1';
      PIN_NUMBER='(1)';
      PIN_TYPE='UNSPEC';
      PINUSE='UNSPEC';
    'B':
      PIN_GROUP='1';
      PIN_NUMBER='(2)';
      PIN_TYPE='UNSPEC';
      PINUSE='UNSPEC';
  end_pin;
  body
      PART_NAME='Q_RES';
      PHYS_DES_PREFIX='R';
      STANDARD='End of Design';
      LIFECYCLE='Comp-Approve';
      PART_NUMBER='CS36342FB04';
      JEDEC_TYPE='R0402';
      ALT_SYMBOLS='(R0402-0201)';
      VALUE='63.4K';
      TOL='1%';
      WATTAGE='1/16W';
      CLASS='DISCRETE';
      DESCRIPTION='RES CHIP 63.4K 1/16W +-1%(0402)EF';
      COMPONENT_TYPE='CHIP0402';
      LEAD_LENGTH='';
      DFM_EXCLUSION='';
      DAY='20180212';
      PARENT_PART_TYPE='Q_RES';
      PARENT_PPT='Q_RES';
      PARENT_PPT_PART='Q_RES_0402LF-63.4K,1%,1/16W,CHIP,CS36342FB04';
  end_body;
end_primitive;
primitive 'Q_RES_0402LF-680,1%,1/16W,CHIP,CS16802FB03';
  pin
    'A':
      PIN_GROUP='1';
      PIN_NUMBER='(1)';
      PIN_TYPE='UNSPEC';
      PINUSE='UNSPEC';
    'B':
      PIN_GROUP='1';
      PIN_NUMBER='(2)';
      PIN_TYPE='UNSPEC';
      PINUSE='UNSPEC';
  end_pin;
  body
      PART_NAME='Q_RES';
      PHYS_DES_PREFIX='R';
      STANDARD='';
      LIFECYCLE='';
      PART_NUMBER='CS16802FB03';
      JEDEC_TYPE='R0402';
      ALT_SYMBOLS='(R0402-0201)';
      VALUE='680';
      TOL='1%';
      WATTAGE='1/16W';
      CLASS='DISCRETE';
      DESCRIPTION='RES CHIP 680 1/16W +-1%(0402)EF';
      COMPONENT_TYPE='CHIPR0402';
      LEAD_LENGTH='';
      DFM_EXCLUSION='';
      DAY='20190829';
      PARENT_PART_TYPE='Q_RES';
      PARENT_PPT='Q_RES';
      PARENT_PPT_PART='Q_RES_0402LF-680,1%,1/16W,CHIP,CS16802FB03';
  end_body;
end_primitive;
primitive 'Q_RES_0402LF-681,1%,1/16W,CHIP,CS16812FB02';
  pin
    'A':
      PIN_GROUP='1';
      PIN_NUMBER='(1)';
      PIN_TYPE='UNSPEC';
      PINUSE='UNSPEC';
    'B':
      PIN_GROUP='1';
      PIN_NUMBER='(2)';
      PIN_TYPE='UNSPEC';
      PINUSE='UNSPEC';
  end_pin;
  body
      PART_NAME='Q_RES';
      PHYS_DES_PREFIX='R';
      STANDARD='End of Design';
      LIFECYCLE='Comp-Approve';
      PART_NUMBER='CS16812FB02';
      JEDEC_TYPE='R0402';
      ALT_SYMBOLS='(R0402-0201)';
      VALUE='681';
      TOL='1%';
      WATTAGE='1/16W';
      CLASS='DISCRETE';
      DESCRIPTION='RES CHIP 681 1/16W +-1%(0402)EF';
      COMPONENT_TYPE='CHIPR0402';
      LEAD_LENGTH='';
      DFM_EXCLUSION='';
      DAY='20190325';
      PARENT_PART_TYPE='Q_RES';
      PARENT_PPT='Q_RES';
      PARENT_PPT_PART='Q_RES_0402LF-681,1%,1/16W,CHIP,CS16812FB02';
  end_body;
end_primitive;
primitive 'Q_RES_0402LF-68K,1%,1/16W,EMPTY,CS36802FB04';
  pin
    'A':
      PIN_GROUP='1';
      PIN_NUMBER='(1)';
      PIN_TYPE='UNSPEC';
      PINUSE='UNSPEC';
    'B':
      PIN_GROUP='1';
      PIN_NUMBER='(2)';
      PIN_TYPE='UNSPEC';
      PINUSE='UNSPEC';
  end_pin;
  body
      PART_NAME='Q_RES';
      PHYS_DES_PREFIX='R';
      STANDARD='End of Design';
      LIFECYCLE='Comp-Approve';
      PART_NUMBER='CS36802FB04';
      JEDEC_TYPE='R0402';
      ALT_SYMBOLS='(R0402-0201)';
      VALUE='68K';
      TOL='1%';
      WATTAGE='1/16W';
      CLASS='IO';
      DESCRIPTION='RES CHIP 68K 1/16W +-1%(0402)EF';
      COMPONENT_TYPE='CHIPR0402';
      LEAD_LENGTH='';
      DFM_EXCLUSION='';
      DAY='20190906';
      PARENT_PART_TYPE='Q_RES';
      PARENT_PPT='Q_RES';
      PARENT_PPT_PART='Q_RES_0402LF-68K,1%,1/16W,EMPTY,CS36802FB04';
  end_body;
end_primitive;
primitive 'Q_RES_0402LF-7.15K,1%,1/16W,CHIP,CS27152FB03';
  pin
    'A':
      PIN_GROUP='1';
      PIN_NUMBER='(1)';
      PIN_TYPE='UNSPEC';
      PINUSE='UNSPEC';
    'B':
      PIN_GROUP='1';
      PIN_NUMBER='(2)';
      PIN_TYPE='UNSPEC';
      PINUSE='UNSPEC';
  end_pin;
  body
      PART_NAME='Q_RES';
      PHYS_DES_PREFIX='R';
      STANDARD='End of Design';
      LIFECYCLE='Comp-Approve';
      PART_NUMBER='CS27152FB03';
      JEDEC_TYPE='R0402';
      ALT_SYMBOLS='(R0402-0201)';
      VALUE='7.15K';
      TOL='1%';
      WATTAGE='1/16W';
      CLASS='DISCRETE';
      DESCRIPTION='RES CHIP 7.15K 1/16W +-1%(0402)EF';
      COMPONENT_TYPE='CHIPR0402';
      LEAD_LENGTH='';
      DFM_EXCLUSION='';
      DAY='20200609';
      PARENT_PART_TYPE='Q_RES';
      PARENT_PPT='Q_RES';
      PARENT_PPT_PART='Q_RES_0402LF-7.15K,1%,1/16W,CHIP,CS27152FB03';
  end_body;
end_primitive;
primitive 'Q_RES_0402LF-7.87K,1%,1/16W,CHIP,CS27872FB02';
  pin
    'A':
      PIN_GROUP='1';
      PIN_NUMBER='(1)';
      PIN_TYPE='UNSPEC';
      PINUSE='UNSPEC';
    'B':
      PIN_GROUP='1';
      PIN_NUMBER='(2)';
      PIN_TYPE='UNSPEC';
      PINUSE='UNSPEC';
  end_pin;
  body
      PART_NAME='Q_RES';
      PHYS_DES_PREFIX='R';
      STANDARD='End of Design';
      LIFECYCLE='Comp-Approve';
      PART_NUMBER='CS27872FB02';
      JEDEC_TYPE='R0402';
      ALT_SYMBOLS='(R0402-0201)';
      VALUE='7.87K';
      TOL='1%';
      WATTAGE='1/16W';
      CLASS='DISCRETE';
      DESCRIPTION='RES CHIP 7.87K 1/16W +-1%(0402)EF';
      COMPONENT_TYPE='CHIPR0402';
      LEAD_LENGTH='';
      DFM_EXCLUSION='';
      DAY='20190820';
      PARENT_PART_TYPE='Q_RES';
      PARENT_PPT='Q_RES';
      PARENT_PPT_PART='Q_RES_0402LF-7.87K,1%,1/16W,CHIP,CS27872FB02';
  end_body;
end_primitive;
primitive 'Q_RES_0402LF-71.5K,1%,1/16W,CHIP,CS37152FB05';
  pin
    'A':
      PIN_GROUP='1';
      PIN_NUMBER='(1)';
      PIN_TYPE='UNSPEC';
      PINUSE='UNSPEC';
    'B':
      PIN_GROUP='1';
      PIN_NUMBER='(2)';
      PIN_TYPE='UNSPEC';
      PINUSE='UNSPEC';
  end_pin;
  body
      PART_NAME='Q_RES';
      PHYS_DES_PREFIX='R';
      STANDARD='';
      LIFECYCLE='';
      PART_NUMBER='CS37152FB05';
      JEDEC_TYPE='R0402';
      ALT_SYMBOLS='(R0402-0201)';
      VALUE='71.5K';
      TOL='1%';
      WATTAGE='1/16W';
      CLASS='DISCRETE';
      DESCRIPTION='RES CHIP 71.5K 1/16W +-1%(0402)EF';
      COMPONENT_TYPE='CHIPR0402';
      LEAD_LENGTH='';
      DFM_EXCLUSION='';
      DAY='20190717';
      PARENT_PART_TYPE='Q_RES';
      PARENT_PPT='Q_RES';
      PARENT_PPT_PART='Q_RES_0402LF-71.5K,1%,1/16W,CHIP,CS37152FB05';
  end_body;
end_primitive;
primitive 'Q_RES_0402LF-71.5K,1%,1/16W,EMPTY,CS37152FB05';
  pin
    'A':
      PIN_GROUP='1';
      PIN_NUMBER='(1)';
      PIN_TYPE='UNSPEC';
      PINUSE='UNSPEC';
    'B':
      PIN_GROUP='1';
      PIN_NUMBER='(2)';
      PIN_TYPE='UNSPEC';
      PINUSE='UNSPEC';
  end_pin;
  body
      PART_NAME='Q_RES';
      PHYS_DES_PREFIX='R';
      STANDARD='';
      LIFECYCLE='';
      PART_NUMBER='CS37152FB05';
      JEDEC_TYPE='R0402';
      ALT_SYMBOLS='(R0402-0201)';
      VALUE='71.5K';
      TOL='1%';
      WATTAGE='1/16W';
      CLASS='IO';
      DESCRIPTION='RES CHIP 71.5K 1/16W +-1%(0402)EF';
      COMPONENT_TYPE='CHIPR0402';
      LEAD_LENGTH='';
      DFM_EXCLUSION='';
      DAY='20190717';
      PARENT_PART_TYPE='Q_RES';
      PARENT_PPT='Q_RES';
      PARENT_PPT_PART='Q_RES_0402LF-71.5K,1%,1/16W,EMPTY,CS37152FB05';
  end_body;
end_primitive;
primitive 'Q_RES_0402LF-75K,0.1%,1/16W,CHIP,CS37502BB01';
  pin
    'A':
      PIN_GROUP='1';
      PIN_NUMBER='(1)';
      PIN_TYPE='UNSPEC';
      PINUSE='UNSPEC';
    'B':
      PIN_GROUP='1';
      PIN_NUMBER='(2)';
      PIN_TYPE='UNSPEC';
      PINUSE='UNSPEC';
  end_pin;
  body
      PART_NAME='Q_RES';
      PHYS_DES_PREFIX='R';
      STANDARD='';
      LIFECYCLE='';
      PART_NUMBER='CS37502BB01';
      JEDEC_TYPE='R0402';
      ALT_SYMBOLS='(R0402-0201)';
      VALUE='75K';
      TOL='0.1%';
      WATTAGE='1/16W';
      CLASS='DISCRETE';
      DESCRIPTION='RES CHIP 75K 1/16W +-0.1%(0402)EF';
      COMPONENT_TYPE='CHIPR0402';
      LEAD_LENGTH='';
      DFM_EXCLUSION='';
      DAY='20211207';
      PARENT_PART_TYPE='Q_RES';
      PARENT_PPT='Q_RES';
      PARENT_PPT_PART='Q_RES_0402LF-75K,0.1%,1/16W,CHIP,CS37502BB01';
  end_body;
end_primitive;
primitive 'Q_RES_0402LF-8.45K,1%,1/16W,EMPTY,CS28452FB06';
  pin
    'A':
      PIN_GROUP='1';
      PIN_NUMBER='(1)';
      PIN_TYPE='UNSPEC';
      PINUSE='UNSPEC';
    'B':
      PIN_GROUP='1';
      PIN_NUMBER='(2)';
      PIN_TYPE='UNSPEC';
      PINUSE='UNSPEC';
  end_pin;
  body
      PART_NAME='Q_RES';
      PHYS_DES_PREFIX='R';
      STANDARD='';
      LIFECYCLE='';
      PART_NUMBER='CS28452FB06';
      JEDEC_TYPE='R0402';
      ALT_SYMBOLS='(R0402-0201)';
      VALUE='8.45K';
      TOL='1%';
      WATTAGE='1/16W';
      CLASS='IO';
      DESCRIPTION='RES CHIP 8.45K 1/16W +-1%( 0402)EF';
      COMPONENT_TYPE='CHIP0402';
      LEAD_LENGTH='';
      DFM_EXCLUSION='';
      DAY='20180212';
      PARENT_PART_TYPE='Q_RES';
      PARENT_PPT='Q_RES';
      PARENT_PPT_PART='Q_RES_0402LF-8.45K,1%,1/16W,EMPTY,CS28452FB06';
  end_body;
end_primitive;
primitive 'Q_RES_0402LF-8.66K,1%,1/16W,CHIP,CS28662FB02';
  pin
    'A':
      PIN_GROUP='1';
      PIN_NUMBER='(1)';
      PIN_TYPE='UNSPEC';
      PINUSE='UNSPEC';
    'B':
      PIN_GROUP='1';
      PIN_NUMBER='(2)';
      PIN_TYPE='UNSPEC';
      PINUSE='UNSPEC';
  end_pin;
  body
      PART_NAME='Q_RES';
      PHYS_DES_PREFIX='R';
      STANDARD='End of Design';
      LIFECYCLE='Comp-Approve';
      PART_NUMBER='CS28662FB02';
      JEDEC_TYPE='R0402';
      ALT_SYMBOLS='(R0402-0201)';
      VALUE='8.66K';
      TOL='1%';
      WATTAGE='1/16W';
      CLASS='DISCRETE';
      DESCRIPTION='RES CHIP 8.66K 1/16W +-1%(0402)EF';
      COMPONENT_TYPE='CHIPR0402';
      LEAD_LENGTH='';
      DFM_EXCLUSION='';
      DAY='20220216';
      PARENT_PART_TYPE='Q_RES';
      PARENT_PPT='Q_RES';
      PARENT_PPT_PART='Q_RES_0402LF-8.66K,1%,1/16W,CHIP,CS28662FB02';
  end_body;
end_primitive;
primitive 'Q_RES_0402LF-8.87K,1%,1/16W,EMPTY,CS28872FB01';
  pin
    'A':
      PIN_GROUP='1';
      PIN_NUMBER='(1)';
      PIN_TYPE='UNSPEC';
      PINUSE='UNSPEC';
    'B':
      PIN_GROUP='1';
      PIN_NUMBER='(2)';
      PIN_TYPE='UNSPEC';
      PINUSE='UNSPEC';
  end_pin;
  body
      PART_NAME='Q_RES';
      PHYS_DES_PREFIX='R';
      STANDARD='End of Design';
      LIFECYCLE='Comp-Approve';
      PART_NUMBER='CS28872FB01';
      JEDEC_TYPE='R0402';
      ALT_SYMBOLS='(R0402-0201)';
      VALUE='8.87K';
      TOL='1%';
      WATTAGE='1/16W';
      CLASS='IO';
      DESCRIPTION='RES CHIP 8.87K 1/16W +-1%(0402)EF';
      COMPONENT_TYPE='CHIPR0402';
      LEAD_LENGTH='';
      DFM_EXCLUSION='';
      DAY='20190718';
      PARENT_PART_TYPE='Q_RES';
      PARENT_PPT='Q_RES';
      PARENT_PPT_PART='Q_RES_0402LF-8.87K,1%,1/16W,EMPTY,CS28872FB01';
  end_body;
end_primitive;
primitive 'Q_RES_0402LF-82K,1%,1/16W,CHIP,CS38202FB01';
  pin
    'A':
      PIN_GROUP='1';
      PIN_NUMBER='(1)';
      PIN_TYPE='UNSPEC';
      PINUSE='UNSPEC';
    'B':
      PIN_GROUP='1';
      PIN_NUMBER='(2)';
      PIN_TYPE='UNSPEC';
      PINUSE='UNSPEC';
  end_pin;
  body
      PART_NAME='Q_RES';
      PHYS_DES_PREFIX='R';
      STANDARD='End of Design';
      LIFECYCLE='Comp-Approve';
      PART_NUMBER='CS38202FB01';
      JEDEC_TYPE='R0402';
      ALT_SYMBOLS='(R0402-0201)';
      VALUE='82K';
      TOL='1%';
      WATTAGE='1/16W';
      CLASS='DISCRETE';
      DESCRIPTION='RES CHIP 82K  1/16W +-1% (0402)EF';
      COMPONENT_TYPE='CHIPR0402';
      LEAD_LENGTH='';
      DFM_EXCLUSION='';
      DAY='20190718';
      PARENT_PART_TYPE='Q_RES';
      PARENT_PPT='Q_RES';
      PARENT_PPT_PART='Q_RES_0402LF-82K,1%,1/16W,CHIP,CS38202FB01';
  end_body;
end_primitive;
primitive 'Q_RES_0402LF-84.5K,1%,1/16W,CHIP,CS38452FB05';
  pin
    'A':
      PIN_GROUP='1';
      PIN_NUMBER='(1)';
      PIN_TYPE='UNSPEC';
      PINUSE='UNSPEC';
    'B':
      PIN_GROUP='1';
      PIN_NUMBER='(2)';
      PIN_TYPE='UNSPEC';
      PINUSE='UNSPEC';
  end_pin;
  body
      PART_NAME='Q_RES';
      PHYS_DES_PREFIX='R';
      STANDARD='End of Design';
      LIFECYCLE='Comp-Approve';
      PART_NUMBER='CS38452FB05';
      JEDEC_TYPE='R0402';
      ALT_SYMBOLS='(R0402-0201)';
      VALUE='84.5K';
      TOL='1%';
      WATTAGE='1/16W';
      CLASS='DISCRETE';
      DESCRIPTION='RES CHIP 84.5K 1/16W +-1%(0402)EF';
      COMPONENT_TYPE='CHIPR0402';
      LEAD_LENGTH='';
      DFM_EXCLUSION='';
      DAY='20210715';
      PARENT_PART_TYPE='Q_RES';
      PARENT_PPT='Q_RES';
      PARENT_PPT_PART='Q_RES_0402LF-84.5K,1%,1/16W,CHIP,CS38452FB05';
  end_body;
end_primitive;
primitive 'Q_RES_0402LF-845,1%,1/16W,CHIP,CS18452FB01';
  pin
    'A':
      PIN_GROUP='1';
      PIN_NUMBER='(1)';
      PIN_TYPE='UNSPEC';
      PINUSE='UNSPEC';
    'B':
      PIN_GROUP='1';
      PIN_NUMBER='(2)';
      PIN_TYPE='UNSPEC';
      PINUSE='UNSPEC';
  end_pin;
  body
      PART_NAME='Q_RES';
      PHYS_DES_PREFIX='R';
      STANDARD='End of Design';
      LIFECYCLE='Comp-Approve';
      PART_NUMBER='CS18452FB01';
      JEDEC_TYPE='R0402';
      ALT_SYMBOLS='(R0402-0201)';
      VALUE='845';
      TOL='1%';
      WATTAGE='1/16W';
      CLASS='DISCRETE';
      DESCRIPTION='RES CHIP 845 1/16W +-1%(0402)EF';
      COMPONENT_TYPE='CHIPR0402';
      LEAD_LENGTH='';
      DFM_EXCLUSION='';
      DAY='20180221';
      PARENT_PART_TYPE='Q_RES';
      PARENT_PPT='Q_RES';
      PARENT_PPT_PART='Q_RES_0402LF-845,1%,1/16W,CHIP,CS18452FB01';
  end_body;
end_primitive;
primitive 'Q_RES_0402LF-86.6K,1%,1/16W,CHIP,CS38662FB05';
  pin
    'A':
      PIN_GROUP='1';
      PIN_NUMBER='(1)';
      PIN_TYPE='UNSPEC';
      PINUSE='UNSPEC';
    'B':
      PIN_GROUP='1';
      PIN_NUMBER='(2)';
      PIN_TYPE='UNSPEC';
      PINUSE='UNSPEC';
  end_pin;
  body
      PART_NAME='Q_RES';
      PHYS_DES_PREFIX='R';
      STANDARD='End of Design';
      LIFECYCLE='Comp-Approve';
      PART_NUMBER='CS38662FB05';
      JEDEC_TYPE='R0402';
      ALT_SYMBOLS='(R0402-0201)';
      VALUE='86.6K';
      TOL='1%';
      WATTAGE='1/16W';
      CLASS='DISCRETE';
      DESCRIPTION='RES CHIP 86.6K 1/16W +-1%(0402)EF';
      COMPONENT_TYPE='CHIPR0402';
      LEAD_LENGTH='';
      DFM_EXCLUSION='';
      DAY='20180221';
      PARENT_PART_TYPE='Q_RES';
      PARENT_PPT='Q_RES';
      PARENT_PPT_PART='Q_RES_0402LF-86.6K,1%,1/16W,CHIP,CS38662FB05';
  end_body;
end_primitive;
primitive 'Q_RES_0402LF-86.6K,1%,1/16W,EMPTY,CS38662FB05';
  pin
    'A':
      PIN_GROUP='1';
      PIN_NUMBER='(1)';
      PIN_TYPE='UNSPEC';
      PINUSE='UNSPEC';
    'B':
      PIN_GROUP='1';
      PIN_NUMBER='(2)';
      PIN_TYPE='UNSPEC';
      PINUSE='UNSPEC';
  end_pin;
  body
      PART_NAME='Q_RES';
      PHYS_DES_PREFIX='R';
      STANDARD='End of Design';
      LIFECYCLE='Comp-Approve';
      PART_NUMBER='CS38662FB05';
      JEDEC_TYPE='R0402';
      ALT_SYMBOLS='(R0402-0201)';
      VALUE='86.6K';
      TOL='1%';
      WATTAGE='1/16W';
      CLASS='IO';
      DESCRIPTION='RES CHIP 86.6K 1/16W +-1%(0402)EF';
      COMPONENT_TYPE='CHIPR0402';
      LEAD_LENGTH='';
      DFM_EXCLUSION='';
      DAY='20180221';
      PARENT_PART_TYPE='Q_RES';
      PARENT_PPT='Q_RES';
      PARENT_PPT_PART='Q_RES_0402LF-86.6K,1%,1/16W,EMPTY,CS38662FB05';
  end_body;
end_primitive;
primitive 'Q_RES_0402LF-9.09K,1%,1/16W,CHIP,CS29092FB05';
  pin
    'A':
      PIN_GROUP='1';
      PIN_NUMBER='(1)';
      PIN_TYPE='UNSPEC';
      PINUSE='UNSPEC';
    'B':
      PIN_GROUP='1';
      PIN_NUMBER='(2)';
      PIN_TYPE='UNSPEC';
      PINUSE='UNSPEC';
  end_pin;
  body
      PART_NAME='Q_RES';
      PHYS_DES_PREFIX='R';
      STANDARD='End of Design';
      LIFECYCLE='Comp-Approve';
      PART_NUMBER='CS29092FB05';
      JEDEC_TYPE='R0402';
      ALT_SYMBOLS='(R0402-0201)';
      VALUE='9.09K';
      TOL='1%';
      WATTAGE='1/16W';
      CLASS='DISCRETE';
      DESCRIPTION='RES CHIP 9.09K 1/16W +-1%(0402)EF';
      COMPONENT_TYPE='CHIPR0402';
      LEAD_LENGTH='';
      DFM_EXCLUSION='';
      DAY='20210715';
      PARENT_PART_TYPE='Q_RES';
      PARENT_PPT='Q_RES';
      PARENT_PPT_PART='Q_RES_0402LF-9.09K,1%,1/16W,CHIP,CS29092FB05';
  end_body;
end_primitive;
primitive 'Q_RES_0402LF-9.31K,1%,1/16W,CHIP,CS29312FB02';
  pin
    'A':
      PIN_GROUP='1';
      PIN_NUMBER='(1)';
      PIN_TYPE='UNSPEC';
      PINUSE='UNSPEC';
    'B':
      PIN_GROUP='1';
      PIN_NUMBER='(2)';
      PIN_TYPE='UNSPEC';
      PINUSE='UNSPEC';
  end_pin;
  body
      PART_NAME='Q_RES';
      PHYS_DES_PREFIX='R';
      STANDARD='End of Design';
      LIFECYCLE='Comp-Approve';
      PART_NUMBER='CS29312FB02';
      JEDEC_TYPE='R0402';
      ALT_SYMBOLS='(R0402-0201)';
      VALUE='9.31K';
      TOL='1%';
      WATTAGE='1/16W';
      CLASS='DISCRETE';
      DESCRIPTION='RES CHIP 9.31K 1/16W +-1%(0402)EF';
      COMPONENT_TYPE='CHIPR0402';
      LEAD_LENGTH='';
      DFM_EXCLUSION='';
      DAY='20180221';
      PARENT_PART_TYPE='Q_RES';
      PARENT_PPT='Q_RES';
      PARENT_PPT_PART='Q_RES_0402LF-9.31K,1%,1/16W,CHIP,CS29312FB02';
  end_body;
end_primitive;
primitive 'Q_RES_0402LF-9.53K,1%,1/16W,CHIP,CS29532FB06';
  pin
    'A':
      PIN_GROUP='1';
      PIN_NUMBER='(1)';
      PIN_TYPE='UNSPEC';
      PINUSE='UNSPEC';
    'B':
      PIN_GROUP='1';
      PIN_NUMBER='(2)';
      PIN_TYPE='UNSPEC';
      PINUSE='UNSPEC';
  end_pin;
  body
      PART_NAME='Q_RES';
      PHYS_DES_PREFIX='R';
      STANDARD='';
      LIFECYCLE='';
      PART_NUMBER='CS29532FB06';
      JEDEC_TYPE='R0402';
      ALT_SYMBOLS='(R0402-0201)';
      VALUE='9.53K';
      TOL='1%';
      WATTAGE='1/16W';
      CLASS='DISCRETE';
      DESCRIPTION='RES CHIP 9.53K 1/16W +-1%(0402)EF';
      COMPONENT_TYPE='CHIPR0402';
      LEAD_LENGTH='';
      DFM_EXCLUSION='';
      DAY='20211216';
      PARENT_PART_TYPE='Q_RES';
      PARENT_PPT='Q_RES';
      PARENT_PPT_PART='Q_RES_0402LF-9.53K,1%,1/16W,CHIP,CS29532FB06';
  end_body;
end_primitive;
primitive 'Q_RES_0402LF-9.76K,1%,1/16W,CHIP,CS29762FB05';
  pin
    'A':
      PIN_GROUP='1';
      PIN_NUMBER='(1)';
      PIN_TYPE='UNSPEC';
      PINUSE='UNSPEC';
    'B':
      PIN_GROUP='1';
      PIN_NUMBER='(2)';
      PIN_TYPE='UNSPEC';
      PINUSE='UNSPEC';
  end_pin;
  body
      PART_NAME='Q_RES';
      PHYS_DES_PREFIX='R';
      STANDARD='End of Design';
      LIFECYCLE='Comp-Approve';
      PART_NUMBER='CS29762FB05';
      JEDEC_TYPE='R0402';
      ALT_SYMBOLS='(R0402-0201)';
      VALUE='9.76K';
      TOL='1%';
      WATTAGE='1/16W';
      CLASS='DISCRETE';
      DESCRIPTION='RES CHIP 9.76K 1/16W +-1%(0402)EF';
      COMPONENT_TYPE='CHIP0402';
      LEAD_LENGTH='';
      DFM_EXCLUSION='';
      DAY='20180212';
      PARENT_PART_TYPE='Q_RES';
      PARENT_PPT='Q_RES';
      PARENT_PPT_PART='Q_RES_0402LF-9.76K,1%,1/16W,CHIP,CS29762FB05';
  end_body;
end_primitive;
primitive 'Q_RES_0402LF-90.9K,1%,1/16W,CHIP,CS39092FB04';
  pin
    'A':
      PIN_GROUP='1';
      PIN_NUMBER='(1)';
      PIN_TYPE='UNSPEC';
      PINUSE='UNSPEC';
    'B':
      PIN_GROUP='1';
      PIN_NUMBER='(2)';
      PIN_TYPE='UNSPEC';
      PINUSE='UNSPEC';
  end_pin;
  body
      PART_NAME='Q_RES';
      PHYS_DES_PREFIX='R';
      STANDARD='End of Design';
      LIFECYCLE='Comp-Approve';
      PART_NUMBER='CS39092FB04';
      JEDEC_TYPE='R0402';
      ALT_SYMBOLS='(R0402-0201)';
      VALUE='90.9K';
      TOL='1%';
      WATTAGE='1/16W';
      CLASS='DISCRETE';
      DESCRIPTION='RES CHIP 90.9K 1/16W +-1%(0402)EF';
      COMPONENT_TYPE='CHIPR0402';
      LEAD_LENGTH='';
      DFM_EXCLUSION='';
      DAY='20190715';
      PARENT_PART_TYPE='Q_RES';
      PARENT_PPT='Q_RES';
      PARENT_PPT_PART='Q_RES_0402LF-90.9K,1%,1/16W,CHIP,CS39092FB04';
  end_body;
end_primitive;
primitive 'Q_RES_0603LF-0,5%,1/4W,CHIP,CS00006J900';
  pin
    'A':
      PIN_GROUP='1';
      PIN_NUMBER='(1)';
      PIN_TYPE='UNSPEC';
      PINUSE='UNSPEC';
    'B':
      PIN_GROUP='1';
      PIN_NUMBER='(2)';
      PIN_TYPE='UNSPEC';
      PINUSE='UNSPEC';
  end_pin;
  body
      PART_NAME='Q_RES';
      PHYS_DES_PREFIX='R';
      STANDARD='';
      LIFECYCLE='';
      PART_NUMBER='CS00006J900';
      JEDEC_TYPE='R0603';
      ALT_SYMBOLS='(SMR0603AW)';
      VALUE='0';
      TOL='5%';
      WATTAGE='1/4W';
      CLASS='DISCRETE';
      DESCRIPTION='RES CHIP 0 1/4W +-5%(0603)';
      COMPONENT_TYPE='CHIPR0603';
      LEAD_LENGTH='';
      DFM_EXCLUSION='';
      DAY='20211026';
      PARENT_PART_TYPE='Q_RES';
      PARENT_PPT='Q_RES';
      PARENT_PPT_PART='Q_RES_0603LF-0,5%,1/4W,CHIP,CS00006J900';
  end_body;
end_primitive;
primitive 'Q_RES_0603LF-0,5%,1/4W,EMPTY,CS00006J900';
  pin
    'A':
      PIN_GROUP='1';
      PIN_NUMBER='(1)';
      PIN_TYPE='UNSPEC';
      PINUSE='UNSPEC';
    'B':
      PIN_GROUP='1';
      PIN_NUMBER='(2)';
      PIN_TYPE='UNSPEC';
      PINUSE='UNSPEC';
  end_pin;
  body
      PART_NAME='Q_RES';
      PHYS_DES_PREFIX='R';
      STANDARD='';
      LIFECYCLE='';
      PART_NUMBER='CS00006J900';
      JEDEC_TYPE='R0603';
      ALT_SYMBOLS='(SMR0603AW)';
      VALUE='0';
      TOL='5%';
      WATTAGE='1/4W';
      CLASS='IO';
      DESCRIPTION='RES CHIP 0 1/4W +-5%(0603)';
      COMPONENT_TYPE='CHIPR0603';
      LEAD_LENGTH='';
      DFM_EXCLUSION='';
      DAY='20211026';
      PARENT_PART_TYPE='Q_RES';
      PARENT_PPT='Q_RES';
      PARENT_PPT_PART='Q_RES_0603LF-0,5%,1/4W,EMPTY,CS00006J900';
  end_body;
end_primitive;
primitive 'Q_RES_0603LF-1,1%,1/10W,CHIP,CS-1003F900';
  pin
    'A':
      PIN_GROUP='1';
      PIN_NUMBER='(1)';
      PIN_TYPE='UNSPEC';
      PINUSE='UNSPEC';
    'B':
      PIN_GROUP='1';
      PIN_NUMBER='(2)';
      PIN_TYPE='UNSPEC';
      PINUSE='UNSPEC';
  end_pin;
  body
      PART_NAME='Q_RES';
      PHYS_DES_PREFIX='R';
      STANDARD='End of Design';
      LIFECYCLE='Comp-Approve';
      PART_NUMBER='CS-1003F900';
      JEDEC_TYPE='R0603_H24';
      ALT_SYMBOLS='(SMR0603AW)';
      VALUE='1';
      TOL='1%';
      WATTAGE='1/10W';
      CLASS='DISCRETE';
      DESCRIPTION='RES CHIP 1 1/10W +-1%(0603)EF';
      COMPONENT_TYPE='CHIPR0603';
      LEAD_LENGTH='';
      DFM_EXCLUSION='';
      DAY='20190904';
      PARENT_PART_TYPE='Q_RES';
      PARENT_PPT='Q_RES';
      PARENT_PPT_PART='Q_RES_0603LF-1,1%,1/10W,CHIP,CS-1003F900';
  end_body;
end_primitive;
primitive 'Q_RES_0603LF-49.9,1%,1/10W,CHIP,CS04993F909';
  pin
    'A':
      PIN_GROUP='1';
      PIN_NUMBER='(1)';
      PIN_TYPE='UNSPEC';
      PINUSE='UNSPEC';
    'B':
      PIN_GROUP='1';
      PIN_NUMBER='(2)';
      PIN_TYPE='UNSPEC';
      PINUSE='UNSPEC';
  end_pin;
  body
      PART_NAME='Q_RES';
      PHYS_DES_PREFIX='R';
      STANDARD='End of Design';
      LIFECYCLE='Comp-Approve';
      PART_NUMBER='CS04993F909';
      JEDEC_TYPE='R0603';
      ALT_SYMBOLS='(SMR0603AW)';
      VALUE='49.9';
      TOL='1%';
      WATTAGE='1/10W';
      CLASS='DISCRETE';
      DESCRIPTION='RES CHIP 49.9 1/10W +-1%(0603)EF';
      COMPONENT_TYPE='CHIPR0603';
      LEAD_LENGTH='';
      DFM_EXCLUSION='';
      DAY='20211026';
      PARENT_PART_TYPE='Q_RES';
      PARENT_PPT='Q_RES';
      PARENT_PPT_PART='Q_RES_0603LF-49.9,1%,1/10W,CHIP,CS04993F909';
  end_body;
end_primitive;
primitive 'Q_RES_0603LF-499,1%,1/10W,CHIP,CS14993F901';
  pin
    'A':
      PIN_GROUP='1';
      PIN_NUMBER='(1)';
      PIN_TYPE='UNSPEC';
      PINUSE='UNSPEC';
    'B':
      PIN_GROUP='1';
      PIN_NUMBER='(2)';
      PIN_TYPE='UNSPEC';
      PINUSE='UNSPEC';
  end_pin;
  body
      PART_NAME='Q_RES';
      PHYS_DES_PREFIX='R';
      STANDARD='End of Design';
      LIFECYCLE='Comp-Approve';
      PART_NUMBER='CS14993F901';
      JEDEC_TYPE='R0603';
      ALT_SYMBOLS='(SMR0603AW)';
      VALUE='499';
      TOL='1%';
      WATTAGE='1/10W';
      CLASS='DISCRETE';
      DESCRIPTION='RES CHIP 499 1/10W +-1%(0603)EF';
      COMPONENT_TYPE='CHIPR0603';
      LEAD_LENGTH='';
      DFM_EXCLUSION='';
      DAY='20211227';
      PARENT_PART_TYPE='Q_RES';
      PARENT_PPT='Q_RES';
      PARENT_PPT_PART='Q_RES_0603LF-499,1%,1/10W,CHIP,CS14993F901';
  end_body;
end_primitive;
primitive 'Q_RES_1206LF-243,1%,1/4W,CHIP,CS12436F201';
  pin
    'A':
      PIN_GROUP='1';
      PIN_NUMBER='(1)';
      PIN_TYPE='UNSPEC';
      PINUSE='UNSPEC';
    'B':
      PIN_GROUP='1';
      PIN_NUMBER='(2)';
      PIN_TYPE='UNSPEC';
      PINUSE='UNSPEC';
  end_pin;
  body
      PART_NAME='Q_RES';
      PHYS_DES_PREFIX='R';
      STANDARD='';
      LIFECYCLE='';
      PART_NUMBER='CS12436F201';
      JEDEC_TYPE='R1206XN';
      ALT_SYMBOLS='(SMR1206AW)';
      VALUE='243';
      TOL='1%';
      WATTAGE='1/4W';
      CLASS='DISCRETE';
      DESCRIPTION='RES CHIP 243 1/4W +-1%(1206)EF';
      COMPONENT_TYPE='CHIPR1206';
      LEAD_LENGTH='';
      DFM_EXCLUSION='';
      DAY='20220322';
      PARENT_PART_TYPE='Q_RES';
      PARENT_PPT='Q_RES';
      PARENT_PPT_PART='Q_RES_1206LF-243,1%,1/4W,CHIP,CS12436F201';
  end_body;
end_primitive;
primitive 'Q_RES_2512LF-0.002,1%,2W,CHIP,CS+002AFR06';
  pin
    'A':
      PIN_GROUP='1';
      PIN_NUMBER='(1)';
      PIN_TYPE='UNSPEC';
      PINUSE='UNSPEC';
    'B':
      PIN_GROUP='1';
      PIN_NUMBER='(2)';
      PIN_TYPE='UNSPEC';
      PINUSE='UNSPEC';
  end_pin;
  body
      PART_NAME='Q_RES';
      PHYS_DES_PREFIX='R';
      STANDARD='End of Design';
      LIFECYCLE='Comp-Approve';
      PART_NUMBER='CS+002AFR06';
      JEDEC_TYPE='R2512XS';
      ALT_SYMBOLS='(SMR2512AW)';
      VALUE='0.002';
      TOL='1%';
      WATTAGE='2W';
      CLASS='DISCRETE';
      DESCRIPTION='RES CHIP 0.002 2W +-1%(2512)EF';
      COMPONENT_TYPE='CHIPR2512';
      LEAD_LENGTH='';
      DFM_EXCLUSION='';
      DAY='20180213';
      PARENT_PART_TYPE='Q_RES';
      PARENT_PPT='Q_RES';
      PARENT_PPT_PART='Q_RES_2512LF-0.002,1%,2W,CHIP,CS+002AFR06';
  end_body;
end_primitive;
primitive 'Q_RES_2512LF-10,1%,2W,EMPTY,CS0100AFR00';
  pin
    'A':
      PIN_GROUP='1';
      PIN_NUMBER='(1)';
      PIN_TYPE='UNSPEC';
      PINUSE='UNSPEC';
    'B':
      PIN_GROUP='1';
      PIN_NUMBER='(2)';
      PIN_TYPE='UNSPEC';
      PINUSE='UNSPEC';
  end_pin;
  body
      PART_NAME='Q_RES';
      PHYS_DES_PREFIX='R';
      STANDARD='';
      LIFECYCLE='';
      PART_NUMBER='CS0100AFR00';
      JEDEC_TYPE='R2512XR';
      ALT_SYMBOLS='(SMR2512AW)';
      VALUE='10';
      TOL='1%';
      WATTAGE='2W';
      CLASS='IO';
      DESCRIPTION='RES CHIP 10 2W +-1%(2512)';
      COMPONENT_TYPE='CHIP2512';
      LEAD_LENGTH='';
      DFM_EXCLUSION='';
      DAY='20171030';
      PARENT_PART_TYPE='Q_RES';
      PARENT_PPT='Q_RES';
      PARENT_PPT_PART='Q_RES_2512LF-10,1%,2W,EMPTY,CS0100AFR00';
  end_body;
end_primitive;
primitive 'Q_RES_4P_12-0.001,1%,3W,SMLF,CHIP,SP_CS+001DFR10';
  pin
    '1':
      PIN_NUMBER='(1)';
      PIN_TYPE='ANALOG';
      NO_LOAD_CHECK='Both';
      NO_IO_CHECK='Both';
      NO_ASSERT_CHECK='TRUE';
      NO_DIR_CHECK='TRUE';
      ALLOW_CONNECT='TRUE';
      PINUSE='UNSPEC';
    '2':
      PIN_NUMBER='(2)';
      PIN_TYPE='ANALOG';
      NO_LOAD_CHECK='Both';
      NO_IO_CHECK='Both';
      NO_ASSERT_CHECK='TRUE';
      NO_DIR_CHECK='TRUE';
      ALLOW_CONNECT='TRUE';
      PINUSE='UNSPEC';
    '3':
      PIN_NUMBER='(3)';
      PIN_TYPE='ANALOG';
      NO_LOAD_CHECK='Both';
      NO_IO_CHECK='Both';
      NO_ASSERT_CHECK='TRUE';
      NO_DIR_CHECK='TRUE';
      ALLOW_CONNECT='TRUE';
      PINUSE='UNSPEC';
    '4':
      PIN_NUMBER='(4)';
      PIN_TYPE='ANALOG';
      NO_LOAD_CHECK='Both';
      NO_IO_CHECK='Both';
      NO_ASSERT_CHECK='TRUE';
      NO_DIR_CHECK='TRUE';
      ALLOW_CONNECT='TRUE';
      PINUSE='UNSPEC';
  end_pin;
  body
      PART_NAME='Q_RES_4P_12';
      BODY_NAME='Q_RES_4P_12';
      PHYS_DES_PREFIX='R';
      CLASS='DISCRETE';
      STANDARD='';
      LIFECYCLE='';
      PART_NUMBER='CS+001DFR10';
      JEDEC_TYPE='R2512_4P_H41';
      DESCRIPTION='RES CHIP 0.001 3W +-1%(2512)RLC_4P';
      MANUFTR='RLC';
      MANUF_PN='LR2512-23R001F4';
      RD_CMPLS_LVL='EP(V1)';
      CMPLS_LVL='EP(V1)';
      DIP_SMD='';
      FROM_PJ='S8Z-BRIAN';
      DATA='RLC_LR2512-23R001F4.pdf';
      FP_ECN='LR2512-23R001F4.msg';
      EE_CHECK_LIST='';
      PSL='';
      PREFERENCE='';
      CREATOR='';
      STATUS='';
      CREATEDAY='20210428';
      PARENT_PART_TYPE='Q_RES_4P_12';
      PARENT_PPT='Q_RES_4P_12';
      PARENT_PPT_PART='Q_RES_4P_12-0.001,1%,3W,SMLF,CHIP,SP_CS+001DFR10';
  end_body;
end_primitive;
primitive 'Q_SHORT_SM-EMPTY,SHORT16';
  pin
    '1':
      PIN_NUMBER='(1)';
      INPUT_LOAD='(-0.01,0.01)';
      OUTPUT_LOAD='(1.0,-1.0)';
      BIDIRECTIONAL='TRUE';
      PINUSE='BI';
    '2':
      PIN_NUMBER='(2)';
      INPUT_LOAD='(-0.01,0.01)';
      OUTPUT_LOAD='(1.0,-1.0)';
      BIDIRECTIONAL='TRUE';
      PINUSE='BI';
  end_pin;
  body
      CLASS='IO';
      PART_NAME='Q_SHORT';
      PHYS_DES_PREFIX='J';
      STANDARD='';
      LIFECYCLE='';
      PART_NUMBER='SHORT16';
      JEDEC_TYPE='SHORT_10X12_M_FOR_INNER_LAYER';
      DESCRIPTION='SHORT_10X12_M_FOR_INNER_LAYER';
      HEIGHT='';
      COMPONENT_TYPE='';
      LEAD_LENGTH='';
      DFM_EXCLUSION='';
      I_PN='';
      FROM_PJ='';
      LEAD_FREE='';
      PARENT_PART_TYPE='Q_SHORT';
      PARENT_PPT='Q_SHORT';
      PARENT_PPT_PART='Q_SHORT_SM-EMPTY,SHORT16';
  end_body;
end_primitive;
primitive 'Q_SP_RES4P-0.0003,1%,4W,SMLF,CHIP,SP_CS0000FFT09';
  pin
    '2B':
      PIN_NUMBER='(2B)';
      BIDIRECTIONAL='TRUE';
      INPUT_LOAD='(-0.01,0.01)';
      OUTPUT_LOAD='(1.0,-1.0)';
      PINUSE='BI';
    '1B':
      PIN_NUMBER='(1B)';
      BIDIRECTIONAL='TRUE';
      INPUT_LOAD='(-0.01,0.01)';
      OUTPUT_LOAD='(1.0,-1.0)';
      PINUSE='BI';
    '2A':
      PIN_NUMBER='(2A)';
      BIDIRECTIONAL='TRUE';
      INPUT_LOAD='(-0.01,0.01)';
      OUTPUT_LOAD='(1.0,-1.0)';
      PINUSE='BI';
    '1A':
      PIN_NUMBER='(1A)';
      BIDIRECTIONAL='TRUE';
      INPUT_LOAD='(-0.01,0.01)';
      OUTPUT_LOAD='(1.0,-1.0)';
      PINUSE='BI';
  end_pin;
  body
      PART_NAME='Q_SP_RES4P';
      BODY_NAME='Q_SP_RES4P';
      PHYS_DES_PREFIX='R';
      CLASS='DISCRETE';
      STANDARD='';
      LIFECYCLE='';
      PART_NUMBER='CS0000FFT09';
      JEDEC_TYPE='R2725_4P';
      DESCRIPTION='RES CHIP 0.0003 4W +-1%(2725)RLC';
      MANUFTR='RLC';
      MANUF_PN='LR2725-24R0003F1';
      RD_CMPLS_LVL='EP(V1)';
      CMPLS_LVL='EP(V1)';
      DIP_SMD='';
      FROM_PJ='IOX-EGBERT';
      DATA='RLC_LR2725-24R0003F1.pdf';
      FP_ECN='';
      EE_CHECK_LIST='';
      PSL='';
      PREFERENCE='';
      CREATOR='';
      STATUS='';
      CREATEDAY='20200617';
      PARENT_PART_TYPE='Q_SP_RES4P';
      PARENT_PPT='Q_SP_RES4P';
      PARENT_PPT_PART='Q_SP_RES4P-0.0003,1%,4W,SMLF,CHIP,SP_CS0000FFT09';
  end_body;
end_primitive;
primitive 'Q_SP_RES4P-0.003,1%,2W,SMLF,CHIP,SP_CS+003AFR00_1';
  pin
    '2B':
      PIN_NUMBER='(2B)';
      BIDIRECTIONAL='TRUE';
      INPUT_LOAD='(-0.01,0.01)';
      OUTPUT_LOAD='(1.0,-1.0)';
      PINUSE='BI';
    '1B':
      PIN_NUMBER='(1B)';
      BIDIRECTIONAL='TRUE';
      INPUT_LOAD='(-0.01,0.01)';
      OUTPUT_LOAD='(1.0,-1.0)';
      PINUSE='BI';
    '2A':
      PIN_NUMBER='(2A)';
      BIDIRECTIONAL='TRUE';
      INPUT_LOAD='(-0.01,0.01)';
      OUTPUT_LOAD='(1.0,-1.0)';
      PINUSE='BI';
    '1A':
      PIN_NUMBER='(1A)';
      BIDIRECTIONAL='TRUE';
      INPUT_LOAD='(-0.01,0.01)';
      OUTPUT_LOAD='(1.0,-1.0)';
      PINUSE='BI';
  end_pin;
  body
      PART_NAME='Q_SP_RES4P';
      BODY_NAME='Q_SP_RES4P';
      PHYS_DES_PREFIX='R';
      CLASS='DISCRETE';
      STANDARD='';
      LIFECYCLE='';
      PART_NUMBER='CS+003AFR00';
      JEDEC_TYPE='R2512_4PXM';
      DESCRIPTION='RES CHIP 0.003 2W +-1%(2512)';
      MANUFTR='YGO';
      MANUF_PN='PR2512FKF7W0R003L';
      RD_CMPLS_LVL='EP(V1)';
      CMPLS_LVL='EP(V1)';
      DIP_SMD='';
      FROM_PJ='G1A-AI-JU';
      DATA='YGO_Cur SensorRes_20130301.pdf';
      FP_ECN='';
      EE_CHECK_LIST='';
      PSL='';
      PREFERENCE='';
      CREATOR='';
      STATUS='';
      CREATEDAY='20160606';
      PARENT_PART_TYPE='Q_SP_RES4P';
      PARENT_PPT='Q_SP_RES4P';
      PARENT_PPT_PART='Q_SP_RES4P-0.003,1%,2W,SMLF,CHIP,SP_CS+003AFR00_1';
  end_body;
end_primitive;
primitive 'Q_XTAL_4P_13BI_24GND-12MHZ,SMLF,MISC,BG6120000B0';
  pin
    'X1':
      PIN_NUMBER='(1)';
      BIDIRECTIONAL='TRUE';
      INPUT_LOAD='(-0.01,0.01)';
      OUTPUT_LOAD='(1.0,-1.0)';
      PINUSE='BI';
    'G1':
      PIN_NUMBER='(2)';
      PINUSE='POWER';
      NO_LOAD_CHECK='Both';
      NO_IO_CHECK='Both';
      NO_ASSERT_CHECK='TRUE';
      NO_DIR_CHECK='TRUE';
      ALLOW_CONNECT='TRUE';
    'G2':
      PIN_NUMBER='(4)';
      PINUSE='POWER';
      NO_LOAD_CHECK='Both';
      NO_IO_CHECK='Both';
      NO_ASSERT_CHECK='TRUE';
      NO_DIR_CHECK='TRUE';
      ALLOW_CONNECT='TRUE';
    'X2':
      PIN_NUMBER='(3)';
      BIDIRECTIONAL='TRUE';
      INPUT_LOAD='(-0.01,0.01)';
      OUTPUT_LOAD='(1.0,-1.0)';
      PINUSE='BI';
  end_pin;
  body
      PART_NAME='Q_XTAL_4P_13BI_24GND';
      BODY_NAME='Q_XTAL_4P_13BI_24GND';
      PHYS_DES_PREFIX='Y';
      CLASS='IO';
      STANDARD='';
      LIFECYCLE='';
      PART_NUMBER='BG6120000B0';
      JEDEC_TYPE='X_4S_8Z25000020_2-5X2';
      ALT_SYMBOLS='';
      DESCRIPTION='XTAL 12MHZ(+-20PPM,10PF)8Z12000006';
      MANUFTR='TXC';
      MANUF_PN='8Z12000006';
      RD_CMPLS_LVL='EP(V1)';
      CMPLS_LVL='EP(V1)';
      DIP_SMD='';
      FROM_PJ='F0TG-CART';
      DATA='TXC_8Z12000006.pdf';
      FP_ECN='8Z12000006.msg';
      EE_CHECK_LIST='';
      STATUS='';
      PSL='';
      PREFERENCE='';
      CREATOR='';
      CREATEDAY='20220617';
      PARENT_PART_TYPE='Q_XTAL_4P_13BI_24GND';
      PARENT_PPT='Q_XTAL_4P_13BI_24GND';
      PARENT_PPT_PART='Q_XTAL_4P_13BI_24GND-12MHZ,SMLF,MISC,BG6120000B0';
  end_body;
end_primitive;
primitive 'Q_XTAL_4P_13BI_24GND-24MHZ,SMLF,MISC,BG624000101';
  pin
    'X1':
      PIN_NUMBER='(1)';
      BIDIRECTIONAL='TRUE';
      INPUT_LOAD='(-0.01,0.01)';
      OUTPUT_LOAD='(1.0,-1.0)';
      PINUSE='BI';
    'G1':
      PIN_NUMBER='(2)';
      PINUSE='POWER';
      NO_LOAD_CHECK='Both';
      NO_IO_CHECK='Both';
      NO_ASSERT_CHECK='TRUE';
      NO_DIR_CHECK='TRUE';
      ALLOW_CONNECT='TRUE';
    'G2':
      PIN_NUMBER='(4)';
      PINUSE='POWER';
      NO_LOAD_CHECK='Both';
      NO_IO_CHECK='Both';
      NO_ASSERT_CHECK='TRUE';
      NO_DIR_CHECK='TRUE';
      ALLOW_CONNECT='TRUE';
    'X2':
      PIN_NUMBER='(3)';
      BIDIRECTIONAL='TRUE';
      INPUT_LOAD='(-0.01,0.01)';
      OUTPUT_LOAD='(1.0,-1.0)';
      PINUSE='BI';
  end_pin;
  body
      PART_NAME='Q_XTAL_4P_13BI_24GND';
      BODY_NAME='Q_XTAL_4P_13BI_24GND';
      PHYS_DES_PREFIX='Y';
      CLASS='IO';
      STANDARD='';
      LIFECYCLE='';
      PART_NUMBER='BG624000101';
      JEDEC_TYPE='X_7MXA';
      ALT_SYMBOLS='';
      DESCRIPTION='XTAL SMD 24MHZ(+-30PPM,18PF)7M24020002';
      MANUFTR='TXC';
      MANUF_PN='7M24020002';
      RD_CMPLS_LVL='EP(V1)';
      CMPLS_LVL='';
      DIP_SMD='';
      FROM_PJ='S3A-THOMAS';
      DATA='TXC_7M24020002_REVA1.pdf';
      FP_ECN='';
      EE_CHECK_LIST='';
      STATUS='';
      PSL='';
      PREFERENCE='';
      CREATOR='';
      CREATEDAY='20141230';
      PARENT_PART_TYPE='Q_XTAL_4P_13BI_24GND';
      PARENT_PPT='Q_XTAL_4P_13BI_24GND';
      PARENT_PPT_PART='Q_XTAL_4P_13BI_24GND-24MHZ,SMLF,MISC,BG624000101';
  end_body;
end_primitive;
primitive 'Q_XTAL_4P_13BI_24GND-25MHZ,SMLF,MISC,BG6250000L4';
  pin
    'X1':
      PIN_NUMBER='(1)';
      BIDIRECTIONAL='TRUE';
      INPUT_LOAD='(-0.01,0.01)';
      OUTPUT_LOAD='(1.0,-1.0)';
      PINUSE='BI';
    'G1':
      PIN_NUMBER='(2)';
      PINUSE='POWER';
      NO_LOAD_CHECK='Both';
      NO_IO_CHECK='Both';
      NO_ASSERT_CHECK='TRUE';
      NO_DIR_CHECK='TRUE';
      ALLOW_CONNECT='TRUE';
    'G2':
      PIN_NUMBER='(4)';
      PINUSE='POWER';
      NO_LOAD_CHECK='Both';
      NO_IO_CHECK='Both';
      NO_ASSERT_CHECK='TRUE';
      NO_DIR_CHECK='TRUE';
      ALLOW_CONNECT='TRUE';
    'X2':
      PIN_NUMBER='(3)';
      BIDIRECTIONAL='TRUE';
      INPUT_LOAD='(-0.01,0.01)';
      OUTPUT_LOAD='(1.0,-1.0)';
      PINUSE='BI';
  end_pin;
  body
      PART_NAME='Q_XTAL_4P_13BI_24GND';
      BODY_NAME='Q_XTAL_4P_13BI_24GND';
      PHYS_DES_PREFIX='Y';
      CLASS='IO';
      STANDARD='';
      LIFECYCLE='';
      PART_NUMBER='BG6250000L4';
      JEDEC_TYPE='OSC4_E3FB';
      ALT_SYMBOLS='';
      DESCRIPTION='XTAL SMD 25MHZ(+-10PPM,8PF)E3SB25E000004';
      MANUFTR='HHE';
      MANUF_PN='E3SB25E000004E';
      RD_CMPLS_LVL='EP(V1)';
      CMPLS_LVL='EP(V1)';
      DIP_SMD='';
      FROM_PJ='F0TG-CART';
      DATA='HHE_E3SB25E000004E.pdf';
      FP_ECN='';
      EE_CHECK_LIST='';
      STATUS='';
      PSL='';
      PREFERENCE='';
      CREATOR='';
      CREATEDAY='20221226';
      PARENT_PART_TYPE='Q_XTAL_4P_13BI_24GND';
      PARENT_PPT='Q_XTAL_4P_13BI_24GND';
      PARENT_PPT_PART='Q_XTAL_4P_13BI_24GND-25MHZ,SMLF,MISC,BG6250000L4';
  end_body;
end_primitive;
primitive 'Q_XTAL_4P_13BI_24GND-26MHZ,SMLF,MISC,BG626000049';
  pin
    'X1':
      PIN_NUMBER='(1)';
      BIDIRECTIONAL='TRUE';
      INPUT_LOAD='(-0.01,0.01)';
      OUTPUT_LOAD='(1.0,-1.0)';
      PINUSE='BI';
    'G1':
      PIN_NUMBER='(2)';
      PINUSE='POWER';
      NO_LOAD_CHECK='Both';
      NO_IO_CHECK='Both';
      NO_ASSERT_CHECK='TRUE';
      NO_DIR_CHECK='TRUE';
      ALLOW_CONNECT='TRUE';
    'G2':
      PIN_NUMBER='(4)';
      PINUSE='POWER';
      NO_LOAD_CHECK='Both';
      NO_IO_CHECK='Both';
      NO_ASSERT_CHECK='TRUE';
      NO_DIR_CHECK='TRUE';
      ALLOW_CONNECT='TRUE';
    'X2':
      PIN_NUMBER='(3)';
      BIDIRECTIONAL='TRUE';
      INPUT_LOAD='(-0.01,0.01)';
      OUTPUT_LOAD='(1.0,-1.0)';
      PINUSE='BI';
  end_pin;
  body
      PART_NAME='Q_XTAL_4P_13BI_24GND';
      BODY_NAME='Q_XTAL_4P_13BI_24GND';
      PHYS_DES_PREFIX='Y';
      CLASS='IO';
      STANDARD='';
      LIFECYCLE='';
      PART_NUMBER='BG626000049';
      JEDEC_TYPE='X_4S_8Z25000020_2-5X2';
      ALT_SYMBOLS='';
      DESCRIPTION='XTAL 26MHZ(10PPM,11PF)8Z26000054';
      MANUFTR='TXC';
      MANUF_PN='8Z26000054';
      RD_CMPLS_LVL='EP(V1)';
      CMPLS_LVL='EP(V1)';
      DIP_SMD='';
      FROM_PJ='S6Z-TOM';
      DATA='TXC_8Z26000054.pdf';
      FP_ECN='';
      EE_CHECK_LIST='';
      STATUS='';
      PSL='';
      PREFERENCE='';
      CREATOR='';
      CREATEDAY='20210222';
      PARENT_PART_TYPE='Q_XTAL_4P_13BI_24GND';
      PARENT_PPT='Q_XTAL_4P_13BI_24GND';
      PARENT_PPT_PART='Q_XTAL_4P_13BI_24GND-26MHZ,SMLF,MISC,BG626000049';
  end_body;
end_primitive;
primitive 'Q_XTAL_4P_13BI_24GND-48MHZ,SMLF,MISC,BG648000076';
  pin
    'X1':
      PIN_NUMBER='(1)';
      BIDIRECTIONAL='TRUE';
      INPUT_LOAD='(-0.01,0.01)';
      OUTPUT_LOAD='(1.0,-1.0)';
      PINUSE='BI';
    'G1':
      PIN_NUMBER='(2)';
      PINUSE='POWER';
      NO_LOAD_CHECK='Both';
      NO_IO_CHECK='Both';
      NO_ASSERT_CHECK='TRUE';
      NO_DIR_CHECK='TRUE';
      ALLOW_CONNECT='TRUE';
    'G2':
      PIN_NUMBER='(4)';
      PINUSE='POWER';
      NO_LOAD_CHECK='Both';
      NO_IO_CHECK='Both';
      NO_ASSERT_CHECK='TRUE';
      NO_DIR_CHECK='TRUE';
      ALLOW_CONNECT='TRUE';
    'X2':
      PIN_NUMBER='(3)';
      BIDIRECTIONAL='TRUE';
      INPUT_LOAD='(-0.01,0.01)';
      OUTPUT_LOAD='(1.0,-1.0)';
      PINUSE='BI';
  end_pin;
  body
      PART_NAME='Q_XTAL_4P_13BI_24GND';
      BODY_NAME='Q_XTAL_4P_13BI_24GND';
      PHYS_DES_PREFIX='Y';
      CLASS='IO';
      STANDARD='';
      LIFECYCLE='';
      PART_NUMBER='BG648000076';
      JEDEC_TYPE='X_4S_FL4000120_3-2X2-5';
      ALT_SYMBOLS='';
      DESCRIPTION='XTAL SMD 48MHZ(10PPM, 12PF)FL4800106';
      MANUFTR='DDS';
      MANUF_PN='FL4800106';
      RD_CMPLS_LVL='EP(V1)';
      CMPLS_LVL='EP(V1)';
      DIP_SMD='';
      FROM_PJ='T6UB-MC';
      DATA='DDS_FL4800106.pdf';
      FP_ECN='';
      EE_CHECK_LIST='';
      STATUS='';
      PSL='';
      PREFERENCE='';
      CREATOR='';
      CREATEDAY='20200831';
      PARENT_PART_TYPE='Q_XTAL_4P_13BI_24GND';
      PARENT_PPT='Q_XTAL_4P_13BI_24GND';
      PARENT_PPT_PART='Q_XTAL_4P_13BI_24GND-48MHZ,SMLF,MISC,BG648000076';
  end_body;
end_primitive;
primitive 'RAA229620GNPHA0-RAA229620GNP#HA0,SMLF,IC,ARF0TGP40A';
  pin
    'CS11':
      PIN_NUMBER='(27)';
      INPUT_LOAD='(-0.01,0.01)';
      PINUSE='IN';
    'VCC':
      PIN_NUMBER='(47)';
      PINUSE='POWER';
      NO_LOAD_CHECK='Both';
      NO_IO_CHECK='Both';
      NO_ASSERT_CHECK='TRUE';
      NO_DIR_CHECK='TRUE';
      ALLOW_CONNECT='TRUE';
    'SVTI':
      PIN_NUMBER='(24)';
      INPUT_LOAD='(-0.01,0.01)';
      PINUSE='IN';
    'PMSCL':
      PIN_NUMBER='(14)';
      INPUT_LOAD='(-0.01,0.01)';
      PINUSE='IN';
    'SVC':
      PIN_NUMBER='(22)';
      INPUT_LOAD='(-0.01,0.01)';
      PINUSE='IN';
    'CS6':
      PIN_NUMBER='(32)';
      INPUT_LOAD='(-0.01,0.01)';
      PINUSE='IN';
    'SVTO':
      PIN_NUMBER='(23)';
      OUTPUT_LOAD='(1.0,-1.0)';
      PINUSE='OUT';
    'RESET_L':
      PIN_NUMBER='(18)';
      INPUT_LOAD='(-0.01,0.01)';
      PINUSE='IN';
    'CS5':
      PIN_NUMBER='(33)';
      INPUT_LOAD='(-0.01,0.01)';
      PINUSE='IN';
    'CS4':
      PIN_NUMBER='(34)';
      INPUT_LOAD='(-0.01,0.01)';
      PINUSE='IN';
    'PG1':
      PIN_NUMBER='(20)';
      OUTPUT_LOAD='(1.0,-1.0)';
      PINUSE='OUT';
    'SVD':
      PIN_NUMBER='(21)';
      INPUT_LOAD='(-0.01,0.01)';
      PINUSE='IN';
    'NPMALERT':
      PIN_NUMBER='(15)';
      OUTPUT_LOAD='(1.0,-1.0)';
      PINUSE='OUT';
    'EN0':
      PIN_NUMBER='(17)';
      INPUT_LOAD='(-0.01,0.01)';
      PINUSE='IN';
    'RGND0':
      PIN_NUMBER='(26)';
      INPUT_LOAD='(-0.01,0.01)';
      PINUSE='IN';
    'PMSDA':
      PIN_NUMBER='(13)';
      BIDIRECTIONAL='TRUE';
      INPUT_LOAD='(-0.01,0.01)';
      OUTPUT_LOAD='(1.0,-1.0)';
      PINUSE='BI';
    'PWM4':
      PIN_NUMBER='(5)';
      OUTPUT_LOAD='(1.0,-1.0)';
      PINUSE='OUT';
    'PWM5':
      PIN_NUMBER='(6)';
      OUTPUT_LOAD='(1.0,-1.0)';
      PINUSE='OUT';
    'VSEN0':
      PIN_NUMBER='(25)';
      INPUT_LOAD='(-0.01,0.01)';
      PINUSE='IN';
    'PWM1':
      PIN_NUMBER='(2)';
      OUTPUT_LOAD='(1.0,-1.0)';
      PINUSE='OUT';
    'PG0':
      PIN_NUMBER='(16)';
      OUTPUT_LOAD='(1.0,-1.0)';
      PINUSE='OUT';
    'PWM6':
      PIN_NUMBER='(7)';
      OUTPUT_LOAD='(1.0,-1.0)';
      PINUSE='OUT';
    'VCCS':
      PIN_NUMBER='(48)';
      PINUSE='POWER';
      NO_LOAD_CHECK='Both';
      NO_IO_CHECK='Both';
      NO_ASSERT_CHECK='TRUE';
      NO_DIR_CHECK='TRUE';
      ALLOW_CONNECT='TRUE';
    'VMON||IINSEN':
      PIN_NUMBER='(45)';
      BIDIRECTIONAL='TRUE';
      INPUT_LOAD='(-0.01,0.01)';
      OUTPUT_LOAD='(1.0,-1.0)';
      PINUSE='BI';
    'VINSEN':
      PIN_NUMBER='(46)';
      INPUT_LOAD='(-0.01,0.01)';
      PINUSE='IN';
    'TEMP0':
      PIN_NUMBER='(44)';
      INPUT_LOAD='(-0.01,0.01)';
      PINUSE='IN';
    'VDDIO':
      PIN_NUMBER='(19)';
      PINUSE='POWER';
      NO_LOAD_CHECK='Both';
      NO_IO_CHECK='Both';
      NO_ASSERT_CHECK='TRUE';
      NO_DIR_CHECK='TRUE';
      ALLOW_CONNECT='TRUE';
    'VSEN1':
      PIN_NUMBER='(40)';
      INPUT_LOAD='(-0.01,0.01)';
      PINUSE='IN';
    'RGND1':
      PIN_NUMBER='(39)';
      INPUT_LOAD='(-0.01,0.01)';
      PINUSE='IN';
    'CS1':
      PIN_NUMBER='(37)';
      INPUT_LOAD='(-0.01,0.01)';
      PINUSE='IN';
    'PWM11':
      PIN_NUMBER='(12)';
      OUTPUT_LOAD='(1.0,-1.0)';
      PINUSE='OUT';
    'PWM3':
      PIN_NUMBER='(4)';
      OUTPUT_LOAD='(1.0,-1.0)';
      PINUSE='OUT';
    'CS3':
      PIN_NUMBER='(35)';
      INPUT_LOAD='(-0.01,0.01)';
      PINUSE='IN';
    'PWM2':
      PIN_NUMBER='(3)';
      OUTPUT_LOAD='(1.0,-1.0)';
      PINUSE='OUT';
    'CS2':
      PIN_NUMBER='(36)';
      INPUT_LOAD='(-0.01,0.01)';
      PINUSE='IN';
    'OCP_L':
      PIN_NUMBER='(41)';
      OUTPUT_LOAD='(1.0,-1.0)';
      PINUSE='OUT';
    'TH_GND':
      PIN_NUMBER='(TH)';
      PINUSE='POWER';
      NO_LOAD_CHECK='Both';
      NO_IO_CHECK='Both';
      NO_ASSERT_CHECK='TRUE';
      NO_DIR_CHECK='TRUE';
      ALLOW_CONNECT='TRUE';
    'EN1||ADDR_CFG':
      PIN_NUMBER='(42)';
      INPUT_LOAD='(-0.01,0.01)';
      PINUSE='IN';
    'TEMP1':
      PIN_NUMBER='(43)';
      INPUT_LOAD='(-0.01,0.01)';
      PINUSE='IN';
    'PWM0':
      PIN_NUMBER='(1)';
      OUTPUT_LOAD='(1.0,-1.0)';
      PINUSE='OUT';
    'CS0':
      PIN_NUMBER='(38)';
      INPUT_LOAD='(-0.01,0.01)';
      PINUSE='IN';
    'PWM7':
      PIN_NUMBER='(8)';
      OUTPUT_LOAD='(1.0,-1.0)';
      PINUSE='OUT';
    'CS7':
      PIN_NUMBER='(31)';
      INPUT_LOAD='(-0.01,0.01)';
      PINUSE='IN';
    'PWM8':
      PIN_NUMBER='(9)';
      OUTPUT_LOAD='(1.0,-1.0)';
      PINUSE='OUT';
    'CS8':
      PIN_NUMBER='(30)';
      INPUT_LOAD='(-0.01,0.01)';
      PINUSE='IN';
    'PWM9':
      PIN_NUMBER='(10)';
      OUTPUT_LOAD='(1.0,-1.0)';
      PINUSE='OUT';
    'CS9':
      PIN_NUMBER='(29)';
      INPUT_LOAD='(-0.01,0.01)';
      PINUSE='IN';
    'PWM10':
      PIN_NUMBER='(11)';
      OUTPUT_LOAD='(1.0,-1.0)';
      PINUSE='OUT';
    'CS10':
      PIN_NUMBER='(28)';
      INPUT_LOAD='(-0.01,0.01)';
      PINUSE='IN';
  end_pin;
  body
      PART_NAME='RAA229620GNPHA0';
      BODY_NAME='RAA229620GNPHA0';
      PHYS_DES_PREFIX='U';
      CLASS='IC';
      STANDARD='';
      LIFECYCLE='';
      PART_NUMBER='ARF0TGP4002';
      JEDEC_TYPE='QFN48_TH_0-4_6X6XH';
      DESCRIPTION='PROG IC(49P)RAA229620GNP#HA0(QFN) (checksum:C6AD1D27/9A3E4D0C~
)';
      MANUFTR='RTT';
      MANUF_PN='RAA229620GNP#HA0';
      RD_CMPLS_LVL='EP(V1)';
      CMPLS_LVL='EP(V1)';
      FROM_PJ='F0TG-CART';
      DIP_SMD='';
      DATA='RTT_RAA229620GNPHA0_C6AD1D27_9A3E4D0C.pdf';
      EE_CHECK_LIST='';
      FP_ECN='QFN48_TH_0-4_6X6XH.msg';
      PSL='';
      CREATOR='';
      STATUS='';
      MSD='';
      ESD_CDM='';
      ESD_HBM='';
      ESD_MM='';
      PIN_LENGTH_SHORT_PIN='0 MILS';
      PIN_LENGTH_LONG_PIN='0 MILS';
      CREATEDAY='20221205';
      PARENT_PART_TYPE='RAA229620GNPHA0';
      PARENT_PPT='RAA229620GNPHA0';
      PARENT_PPT_PART='RAA229620GNPHA0-RAA229620GNP#HA0,SMLF,IC,ARF0TGP4002';
  end_body;
end_primitive;
primitive 'RAA229621GNPHA0-RAA229621GNP#HA0,SMLF,IC,ARF0TGP40A';
  pin
    'CS7':
      PIN_NUMBER='(23)';
      INPUT_LOAD='(-0.01,0.01)';
      PINUSE='IN';
    'VCC':
      PIN_NUMBER='(39)';
      PINUSE='POWER';
      NO_LOAD_CHECK='Both';
      NO_IO_CHECK='Both';
      NO_ASSERT_CHECK='TRUE';
      NO_DIR_CHECK='TRUE';
      ALLOW_CONNECT='TRUE';
    'SVTI':
      PIN_NUMBER='(20)';
      INPUT_LOAD='(-0.01,0.01)';
      PINUSE='IN';
    'PMSCL':
      PIN_NUMBER='(10)';
      INPUT_LOAD='(-0.01,0.01)';
      PINUSE='IN';
    'SVC':
      PIN_NUMBER='(18)';
      INPUT_LOAD='(-0.01,0.01)';
      PINUSE='IN';
    'CS6':
      PIN_NUMBER='(24)';
      INPUT_LOAD='(-0.01,0.01)';
      PINUSE='IN';
    'SVTO':
      PIN_NUMBER='(19)';
      OUTPUT_LOAD='(1.0,-1.0)';
      PINUSE='OUT';
    'RESET_L':
      PIN_NUMBER='(14)';
      INPUT_LOAD='(-0.01,0.01)';
      PINUSE='IN';
    'CS5':
      PIN_NUMBER='(25)';
      INPUT_LOAD='(-0.01,0.01)';
      PINUSE='IN';
    'CS4':
      PIN_NUMBER='(26)';
      INPUT_LOAD='(-0.01,0.01)';
      PINUSE='IN';
    'PG1':
      PIN_NUMBER='(16)';
      OUTPUT_LOAD='(1.0,-1.0)';
      PINUSE='OUT';
    'SVD':
      PIN_NUMBER='(17)';
      BIDIRECTIONAL='TRUE';
      INPUT_LOAD='(-0.01,0.01)';
      OUTPUT_LOAD='(1.0,-1.0)';
      PINUSE='BI';
    'NPMALERT':
      PIN_NUMBER='(11)';
      OUTPUT_LOAD='(1.0,-1.0)';
      PINUSE='OUT';
    'EN0':
      PIN_NUMBER='(13)';
      INPUT_LOAD='(-0.01,0.01)';
      PINUSE='IN';
    'RGND0':
      PIN_NUMBER='(22)';
      INPUT_LOAD='(-0.01,0.01)';
      PINUSE='IN';
    'PMSDA':
      PIN_NUMBER='(9)';
      BIDIRECTIONAL='TRUE';
      INPUT_LOAD='(-0.01,0.01)';
      OUTPUT_LOAD='(1.0,-1.0)';
      PINUSE='BI';
    'PWM4':
      PIN_NUMBER='(5)';
      OUTPUT_LOAD='(1.0,-1.0)';
      PINUSE='OUT';
    'PWM5':
      PIN_NUMBER='(6)';
      OUTPUT_LOAD='(1.0,-1.0)';
      PINUSE='OUT';
    'VSEN0':
      PIN_NUMBER='(21)';
      INPUT_LOAD='(-0.01,0.01)';
      PINUSE='IN';
    'PWM1':
      PIN_NUMBER='(2)';
      OUTPUT_LOAD='(1.0,-1.0)';
      PINUSE='OUT';
    'PG0':
      PIN_NUMBER='(12)';
      OUTPUT_LOAD='(1.0,-1.0)';
      PINUSE='OUT';
    'PWM6':
      PIN_NUMBER='(7)';
      OUTPUT_LOAD='(1.0,-1.0)';
      PINUSE='OUT';
    'VCCS':
      PIN_NUMBER='(40)';
      PINUSE='POWER';
      NO_LOAD_CHECK='Both';
      NO_IO_CHECK='Both';
      NO_ASSERT_CHECK='TRUE';
      NO_DIR_CHECK='TRUE';
      ALLOW_CONNECT='TRUE';
    'VMON||IINSEN':
      PIN_NUMBER='(37)';
      INPUT_LOAD='(-0.01,0.01)';
      PINUSE='IN';
    'VINSEN':
      PIN_NUMBER='(38)';
      INPUT_LOAD='(-0.01,0.01)';
      PINUSE='IN';
    'TEMP0':
      PIN_NUMBER='(36)';
      INPUT_LOAD='(-0.01,0.01)';
      PINUSE='IN';
    'VDDIO':
      PIN_NUMBER='(15)';
      INPUT_LOAD='(-0.01,0.01)';
      PINUSE='IN';
    'VSEN1':
      PIN_NUMBER='(32)';
      INPUT_LOAD='(-0.01,0.01)';
      PINUSE='IN';
    'RGND1':
      PIN_NUMBER='(31)';
      INPUT_LOAD='(-0.01,0.01)';
      PINUSE='IN';
    'CS1':
      PIN_NUMBER='(29)';
      INPUT_LOAD='(-0.01,0.01)';
      PINUSE='IN';
    'PWM7':
      PIN_NUMBER='(8)';
      OUTPUT_LOAD='(1.0,-1.0)';
      PINUSE='OUT';
    'PWM3':
      PIN_NUMBER='(4)';
      OUTPUT_LOAD='(1.0,-1.0)';
      PINUSE='OUT';
    'CS3':
      PIN_NUMBER='(27)';
      INPUT_LOAD='(-0.01,0.01)';
      PINUSE='IN';
    'PWM2':
      PIN_NUMBER='(3)';
      OUTPUT_LOAD='(1.0,-1.0)';
      PINUSE='OUT';
    'CS2':
      PIN_NUMBER='(28)';
      INPUT_LOAD='(-0.01,0.01)';
      PINUSE='IN';
    'OCP_L':
      PIN_NUMBER='(33)';
      OUTPUT_LOAD='(1.0,-1.0)';
      PINUSE='OUT';
    'TH_GND':
      PIN_NUMBER='(TH)';
      PINUSE='POWER';
      NO_LOAD_CHECK='Both';
      NO_IO_CHECK='Both';
      NO_ASSERT_CHECK='TRUE';
      NO_DIR_CHECK='TRUE';
      ALLOW_CONNECT='TRUE';
    'EN1||ADDR_CFG':
      PIN_NUMBER='(34)';
      INPUT_LOAD='(-0.01,0.01)';
      PINUSE='IN';
    'TEMP1':
      PIN_NUMBER='(35)';
      INPUT_LOAD='(-0.01,0.01)';
      PINUSE='IN';
    'PWM0':
      PIN_NUMBER='(1)';
      OUTPUT_LOAD='(1.0,-1.0)';
      PINUSE='OUT';
    'CS0':
      PIN_NUMBER='(30)';
      INPUT_LOAD='(-0.01,0.01)';
      PINUSE='IN';
  end_pin;
  body
      PART_NAME='RAA229621GNPHA0';
      BODY_NAME='RAA229621GNPHA0';
      PHYS_DES_PREFIX='U';
      CLASS='IC';
      STANDARD='';
      LIFECYCLE='';
      PART_NUMBER='ARF0TGP4003';
      JEDEC_TYPE='QFN40_TH_0-4_5X5XE';
      DESCRIPTION='PROG IC(41P)RAA229621GNP#HA0(QFN) (checksum:B68CAFAB)';
      MANUFTR='RTT';
      MANUF_PN='RAA229621GNP#HA0';
      RD_CMPLS_LVL='EP(V1)';
      CMPLS_LVL='EP(V1)';
      FROM_PJ='F0TG-CART';
      DIP_SMD='';
      DATA='RTT_RAA229621GNPHA0_B68CAFAB.pdf';
      EE_CHECK_LIST='';
      FP_ECN='';
      PSL='';
      CREATOR='';
      STATUS='';
      MSD='';
      ESD_CDM='';
      ESD_HBM='';
      ESD_MM='';
      PIN_LENGTH_SHORT_PIN='0 MILS';
      PIN_LENGTH_LONG_PIN='0 MILS';
      CREATEDAY='20221212';
      PARENT_PART_TYPE='RAA229621GNPHA0';
      PARENT_PPT='RAA229621GNPHA0';
      PARENT_PPT_PART='RAA229621GNPHA0-RAA229621GNP#HA0,SMLF,IC,ARF0TGP4003';
  end_body;
end_primitive;
primitive 'RS31312R-RS31312R,SMLF,IC,AL031312000';
  pin
    'VOUT_20':
      PIN_NUMBER='(20)';
      OUTPUT_LOAD='(1.0,-1.0)';
      PINUSE='OUT';
    'VIN_21_22':
      PIN_NUMBER='(21_22)';
      INPUT_LOAD='(-0.01,0.01)';
      PINUSE='IN';
    'VOUT_19':
      PIN_NUMBER='(19)';
      OUTPUT_LOAD='(1.0,-1.0)';
      PINUSE='OUT';
    'VOUT_18':
      PIN_NUMBER='(18)';
      OUTPUT_LOAD='(1.0,-1.0)';
      PINUSE='OUT';
    'VOUT_17':
      PIN_NUMBER='(17)';
      OUTPUT_LOAD='(1.0,-1.0)';
      PINUSE='OUT';
    'VOUT_16':
      PIN_NUMBER='(16)';
      OUTPUT_LOAD='(1.0,-1.0)';
      PINUSE='OUT';
    'VOUT_15':
      PIN_NUMBER='(15)';
      OUTPUT_LOAD='(1.0,-1.0)';
      PINUSE='OUT';
    'VOUT_14':
      PIN_NUMBER='(14)';
      OUTPUT_LOAD='(1.0,-1.0)';
      PINUSE='OUT';
    'AVIN':
      PIN_NUMBER='(12)';
      INPUT_LOAD='(-0.01,0.01)';
      PINUSE='IN';
    'VOUT_13':
      PIN_NUMBER='(13)';
      OUTPUT_LOAD='(1.0,-1.0)';
      PINUSE='OUT';
    'OV':
      PIN_NUMBER='(11)';
      INPUT_LOAD='(-0.01,0.01)';
      PINUSE='IN';
    'PG':
      PIN_NUMBER='(10)';
      OUTPUT_LOAD='(1.0,-1.0)';
      PINUSE='OUT';
    'FLTB':
      PIN_NUMBER='(9)';
      OUTPUT_LOAD='(1.0,-1.0)';
      PINUSE='OUT';
    'IMON':
      PIN_NUMBER='(8)';
      OUTPUT_LOAD='(1.0,-1.0)';
      PINUSE='OUT';
    'VIN_23':
      PIN_NUMBER='(23)';
      INPUT_LOAD='(-0.01,0.01)';
      PINUSE='IN';
    'VIN_24':
      PIN_NUMBER='(24)';
      INPUT_LOAD='(-0.01,0.01)';
      PINUSE='IN';
    'VIN_25':
      PIN_NUMBER='(25)';
      INPUT_LOAD='(-0.01,0.01)';
      PINUSE='IN';
    'VIN_26':
      PIN_NUMBER='(26)';
      INPUT_LOAD='(-0.01,0.01)';
      PINUSE='IN';
    'EN':
      PIN_NUMBER='(1)';
      INPUT_LOAD='(-0.01,0.01)';
      PINUSE='IN';
    'LOADEN':
      PIN_NUMBER='(2)';
      INPUT_LOAD='(-0.01,0.01)';
      PINUSE='IN';
    'ENTM':
      PIN_NUMBER='(3)';
      INPUT_LOAD='(-0.01,0.01)';
      PINUSE='IN';
    'TIMER':
      PIN_NUMBER='(4)';
      INPUT_LOAD='(-0.01,0.01)';
      PINUSE='IN';
    'ISET':
      PIN_NUMBER='(5)';
      INPUT_LOAD='(-0.01,0.01)';
      PINUSE='IN';
    'SS':
      PIN_NUMBER='(6)';
      INPUT_LOAD='(-0.01,0.01)';
      PINUSE='IN';
    'GND':
      PIN_NUMBER='(7)';
      PINUSE='POWER';
      NO_LOAD_CHECK='Both';
      NO_IO_CHECK='Both';
      NO_ASSERT_CHECK='TRUE';
      NO_DIR_CHECK='TRUE';
      ALLOW_CONNECT='TRUE';
  end_pin;
  body
      PART_NAME='RS31312R';
      BODY_NAME='RS31312R';
      PHYS_DES_PREFIX='U';
      CLASS='IC';
      STANDARD='';
      LIFECYCLE='';
      PART_NUMBER='AL031312000';
      JEDEC_TYPE='QFN22_TH_3X5';
      DESCRIPTION='IC(22P)RS31312R(QFN)';
      MANUFTR='RDS';
      MANUF_PN='RS31312R';
      RD_CMPLS_LVL='EP(V1)';
      CMPLS_LVL='';
      FROM_PJ='F0T-GREG';
      DIP_SMD='';
      DATA='RDS_RS31312R.pdf';
      EE_CHECK_LIST='';
      FP_ECN='RS31312R.msg';
      PSL='';
      CREATOR='';
      STATUS='';
      MSD='';
      ESD_CDM='';
      ESD_HBM='';
      ESD_MM='';
      PIN_LENGTH_SHORT_PIN='0 MILS';
      PIN_LENGTH_LONG_PIN='0 MILS';
      CREATEDAY='20220608';
      PARENT_PART_TYPE='RS31312R';
      PARENT_PPT='RS31312R';
      PARENT_PPT_PART='RS31312R-RS31312R,SMLF,IC,AL031312000';
  end_body;
end_primitive;
primitive 'RT9818C44GV-RT9818C-44GV,SMLF,IC,AL009818001';
  pin
    'VDD':
      PIN_NUMBER='(3)';
      PINUSE='POWER';
      NO_LOAD_CHECK='Both';
      NO_IO_CHECK='Both';
      NO_ASSERT_CHECK='TRUE';
      NO_DIR_CHECK='TRUE';
      ALLOW_CONNECT='TRUE';
    'RESET#':
      PIN_NUMBER='(1)';
      OUTPUT_LOAD='(1.0,-1.0)';
      PINUSE='OUT';
    'GND':
      PIN_NUMBER='(2)';
      PINUSE='POWER';
      NO_LOAD_CHECK='Both';
      NO_IO_CHECK='Both';
      NO_ASSERT_CHECK='TRUE';
      NO_DIR_CHECK='TRUE';
      ALLOW_CONNECT='TRUE';
  end_pin;
  body
      PART_NAME='RT9818C44GV';
      BODY_NAME='RT9818C44GV';
      PHYS_DES_PREFIX='U';
      CLASS='IC';
      STANDARD='';
      LIFECYCLE='';
      PART_NUMBER='AL009818001';
      JEDEC_TYPE='SOT23_123_2-89X1-6';
      DESCRIPTION='IC OTHER(3P)RT9818C-44GV(SOT23-3)';
      MANUFTR='RTK';
      MANUF_PN='RT9818C-44GV';
      RD_CMPLS_LVL='EP(V1)';
      CMPLS_LVL='';
      FROM_PJ='S5B-YU-LIN';
      DIP_SMD='';
      DATA='RTK_RT9818C-44GV.pdf';
      EE_CHECK_LIST='';
      FP_ECN='';
      PSL='';
      CREATOR='';
      STATUS='';
      CREATEDAY='20150914';
      PARENT_PART_TYPE='RT9818C44GV';
      PARENT_PPT='RT9818C44GV';
      PARENT_PPT_PART='RT9818C44GV-RT9818C-44GV,SMLF,IC,AL009818001';
  end_body;
end_primitive;
primitive 'SCHOTTKY_12-B0530WS7F,SMLF,EMPTY,BC000530Z41';
  pin
    'A':
      PIN_NUMBER='(1)';
      INPUT_LOAD='(-0.01,0.01)';
      PINUSE='IN';
    'C':
      PIN_NUMBER='(2)';
      BIDIRECTIONAL='TRUE';
      INPUT_LOAD='(-0.01,0.01)';
      OUTPUT_LOAD='(1.0,-1.0)';
      PINUSE='BI';
  end_pin;
  body
      PART_NAME='SCHOTTKY_12';
      BODY_NAME='SCHOTTKY_12';
      PHYS_DES_PREFIX='D';
      CLASS='IC';
      STANDARD='End of Design';
      LIFECYCLE='Comp-Approve';
      PART_NUMBER='BC000530Z41';
      JEDEC_TYPE='SOD323XB';
      DESCRIPTION='DIODE SMD B0530WS-7-F(30V,0.5A)SOD-323';
      MANUFTR='DDS';
      MANUF_PN='B0530WS-7-F';
      RD_CMPLS_LVL='EP';
      CMPLS_LVL='EP(V1)';
      DIP_SMD='';
      FP_ECN='';
      FROM_PJ='T2R-GAVEN';
      DATA='B0530WS-7-F.pdf';
      EE_CHECK_LIST='';
      STATUS='';
      PSL='';
      PREFERENCE='';
      CREATOR='';
      CREATEDAY='20140704';
      PARENT_PART_TYPE='SCHOTTKY_12';
      PARENT_PPT='SCHOTTKY_12';
      PARENT_PPT_PART='SCHOTTKY_12-B0530WS7F,SMLF,EMPTY,BC000530Z41';
  end_body;
end_primitive;
primitive 'SCHOTTKY_AC-B340A-13-F,SMLF,IC,BC000340Z30';
  pin
    'A':
      PIN_NUMBER='(A)';
      INPUT_LOAD='(-0.01,0.01)';
      PINUSE='IN';
    'C':
      PIN_NUMBER='(C)';
      BIDIRECTIONAL='TRUE';
      INPUT_LOAD='(-0.01,0.01)';
      OUTPUT_LOAD='(1.0,-1.0)';
      PINUSE='BI';
  end_pin;
  body
      PART_NAME='SCHOTTKY_AC';
      BODY_NAME='SCHOTTKY_AC';
      PHYS_DES_PREFIX='D';
      CLASS='IC';
      STANDARD='';
      LIFECYCLE='';
      PART_NUMBER='BC000340Z30';
      JEDEC_TYPE='D2010XF';
      DESCRIPTION='DIODE SMD B340A-13-F(40V,3A)SCHOTTKY';
      MANUFTR='DDS';
      MANUF_PN='B340A-13-F';
      RD_CMPLS_LVL='EP(V1)';
      CMPLS_LVL='EP(V1)';
      DIP_SMD='';
      FP_ECN='';
      FROM_PJ='S5B-ROSSI';
      DATA='DDS_B340A-13-F.pdf';
      EE_CHECK_LIST='';
      PSL='';
      PREFERENCE='';
      CREATOR='';
      CREATEDAY='20151231';
      STATUS='';
      PARENT_PART_TYPE='SCHOTTKY_AC';
      PARENT_PPT='SCHOTTKY_AC';
      PARENT_PPT_PART='SCHOTTKY_AC-B340A-13-F,SMLF,IC,BC000340Z30';
  end_body;
end_primitive;
primitive 'SCHOTTKY_DUAL_12A_3C-BAT54CW,SMLF,EMPTY,BCBAT54CZ13';
  pin
    'A':
      PIN_NUMBER='(2)';
      INPUT_LOAD='(-0.01,0.01)';
      PINUSE='IN';
    'B':
      PIN_NUMBER='(1)';
      INPUT_LOAD='(-0.01,0.01)';
      PINUSE='IN';
    'C':
      PIN_NUMBER='(3)';
      BIDIRECTIONAL='TRUE';
      INPUT_LOAD='(-0.01,0.01)';
      OUTPUT_LOAD='(1.0,-1.0)';
      PINUSE='BI';
  end_pin;
  body
      PART_NAME='SCHOTTKY_DUAL_12A_3C';
      BODY_NAME='SCHOTTKY_DUAL_12A_3C';
      PHYS_DES_PREFIX='U';
      CLASS='IC';
      STANDARD='';
      LIFECYCLE='';
      PART_NUMBER='BCBAT54CZ13';
      JEDEC_TYPE='SOT323';
      DESCRIPTION='DIODE SMD BAT54CW(30V,0.2A,SOT323)';
      MANUFTR='PJT';
      MANUF_PN='BAT54CW';
      RD_CMPLS_LVL='EP(V1)';
      CMPLS_LVL='EP(V1)';
      DIP_SMD='';
      FP_ECN='';
      FROM_PJ='TU1H-JAMIE';
      DATA='PJT_BAT54CW-SERIES.pdf';
      EE_CHECK_LIST='';
      STATUS='';
      PSL='';
      PREFERENCE='';
      CREATOR='';
      CREATEDAY='20131016';
      ESD_CDM='';
      ESD_HBM='';
      ESD_MM='';
      MSD='';
      PIN_LENGTH_LONG_PIN='';
      PIN_LENGTH_SHORT_PIN='';
      PARENT_PART_TYPE='SCHOTTKY_DUAL_12A_3C';
      PARENT_PPT='SCHOTTKY_DUAL_12A_3C';
      PARENT_PPT_PART='SCHOTTKY_DUAL_12A_3C-BAT54CW,SMLF,EMPTY,BCBAT54CZ13';
  end_body;
end_primitive;
primitive 'SCHOTTKY_DUAL_12A_3C-BAT54CW,SMLF,IC,BCBAT54CZ13';
  pin
    'A':
      PIN_NUMBER='(2)';
      INPUT_LOAD='(-0.01,0.01)';
      PINUSE='IN';
    'B':
      PIN_NUMBER='(1)';
      INPUT_LOAD='(-0.01,0.01)';
      PINUSE='IN';
    'C':
      PIN_NUMBER='(3)';
      BIDIRECTIONAL='TRUE';
      INPUT_LOAD='(-0.01,0.01)';
      OUTPUT_LOAD='(1.0,-1.0)';
      PINUSE='BI';
  end_pin;
  body
      PART_NAME='SCHOTTKY_DUAL_12A_3C';
      BODY_NAME='SCHOTTKY_DUAL_12A_3C';
      PHYS_DES_PREFIX='U';
      CLASS='IC';
      STANDARD='';
      LIFECYCLE='';
      PART_NUMBER='BCBAT54CZ13';
      JEDEC_TYPE='SOT323';
      DESCRIPTION='DIODE SMD BAT54CW(30V,0.2A,SOT323)';
      MANUFTR='PJT';
      MANUF_PN='BAT54CW';
      RD_CMPLS_LVL='EP(V1)';
      CMPLS_LVL='EP(V1)';
      DIP_SMD='';
      FP_ECN='';
      FROM_PJ='TU1H-JAMIE';
      DATA='PJT_BAT54CW-SERIES.pdf';
      EE_CHECK_LIST='';
      STATUS='';
      PSL='';
      PREFERENCE='';
      CREATOR='';
      CREATEDAY='20131016';
      ESD_CDM='';
      ESD_HBM='';
      ESD_MM='';
      MSD='';
      PIN_LENGTH_LONG_PIN='';
      PIN_LENGTH_SHORT_PIN='';
      PARENT_PART_TYPE='SCHOTTKY_DUAL_12A_3C';
      PARENT_PPT='SCHOTTKY_DUAL_12A_3C';
      PARENT_PPT_PART='SCHOTTKY_DUAL_12A_3C-BAT54CW,SMLF,IC,BCBAT54CZ13';
  end_body;
end_primitive;
primitive 'SCONN168_ME1016810202011-SCONN168_ME1016810202011,A';
  pin
    'NIC_PWR_GOOD':
      PIN_NUMBER='(OB1)';
      INPUT_LOAD='(-0.01,0.01)';
      PINUSE='IN';
    'MAIN_PWR_EN':
      PIN_NUMBER='(OB2)';
      OUTPUT_LOAD='(1.0,-1.0)';
      PINUSE='OUT';
    'LD#':
      PIN_NUMBER='(OB3)';
      OUTPUT_LOAD='(1.0,-1.0)';
      PINUSE='OUT';
    'DATA_IN':
      PIN_NUMBER='(OB4)';
      INPUT_LOAD='(-0.01,0.01)';
      PINUSE='IN';
    'DATA_OUT':
      PIN_NUMBER='(OB5)';
      OUTPUT_LOAD='(1.0,-1.0)';
      PINUSE='OUT';
    'CLK':
      PIN_NUMBER='(OB6)';
      OUTPUT_LOAD='(1.0,-1.0)';
      PINUSE='OUT';
    'SLOT_ID0':
      PIN_NUMBER='(OB7)';
      OUTPUT_LOAD='(1.0,-1.0)';
      PINUSE='OUT';
    'RBT_RXD1':
      PIN_NUMBER='(OB8)';
      INPUT_LOAD='(-0.01,0.01)';
      PINUSE='IN';
    'RBT_RXD0':
      PIN_NUMBER='(OB9)';
      INPUT_LOAD='(-0.01,0.01)';
      PINUSE='IN';
    'GND_OB10':
      PIN_NUMBER='(OB10)';
      PINUSE='POWER';
      NO_LOAD_CHECK='Both';
      NO_IO_CHECK='Both';
      NO_ASSERT_CHECK='TRUE';
      NO_DIR_CHECK='TRUE';
      ALLOW_CONNECT='TRUE';
    'REFCLKN2':
      PIN_NUMBER='(OB11)';
      OUTPUT_LOAD='(1.0,-1.0)';
      PINUSE='OUT';
    'REFCLKP2':
      PIN_NUMBER='(OB12)';
      OUTPUT_LOAD='(1.0,-1.0)';
      PINUSE='OUT';
    'GND_OB13':
      PIN_NUMBER='(OB13)';
      PINUSE='POWER';
      NO_LOAD_CHECK='Both';
      NO_IO_CHECK='Both';
      NO_ASSERT_CHECK='TRUE';
      NO_DIR_CHECK='TRUE';
      ALLOW_CONNECT='TRUE';
    'RBT_CRS_DV':
      PIN_NUMBER='(OB14)';
      OUTPUT_LOAD='(1.0,-1.0)';
      PINUSE='OUT';
    '+12V_EDGE_B1':
      PIN_NUMBER='(B1)';
      PINUSE='POWER';
      NO_LOAD_CHECK='Both';
      NO_IO_CHECK='Both';
      NO_ASSERT_CHECK='TRUE';
      NO_DIR_CHECK='TRUE';
      ALLOW_CONNECT='TRUE';
    '+12V_EDGE_B2':
      PIN_NUMBER='(B2)';
      PINUSE='POWER';
      NO_LOAD_CHECK='Both';
      NO_IO_CHECK='Both';
      NO_ASSERT_CHECK='TRUE';
      NO_DIR_CHECK='TRUE';
      ALLOW_CONNECT='TRUE';
    '+12V_EDGE_B3':
      PIN_NUMBER='(B3)';
      PINUSE='POWER';
      NO_LOAD_CHECK='Both';
      NO_IO_CHECK='Both';
      NO_ASSERT_CHECK='TRUE';
      NO_DIR_CHECK='TRUE';
      ALLOW_CONNECT='TRUE';
    '+12V_EDGE_B4':
      PIN_NUMBER='(B4)';
      PINUSE='POWER';
      NO_LOAD_CHECK='Both';
      NO_IO_CHECK='Both';
      NO_ASSERT_CHECK='TRUE';
      NO_DIR_CHECK='TRUE';
      ALLOW_CONNECT='TRUE';
    '+12V_EDGE_B5':
      PIN_NUMBER='(B5)';
      PINUSE='POWER';
      NO_LOAD_CHECK='Both';
      NO_IO_CHECK='Both';
      NO_ASSERT_CHECK='TRUE';
      NO_DIR_CHECK='TRUE';
      ALLOW_CONNECT='TRUE';
    '+12V_EDGE_B6':
      PIN_NUMBER='(B6)';
      PINUSE='POWER';
      NO_LOAD_CHECK='Both';
      NO_IO_CHECK='Both';
      NO_ASSERT_CHECK='TRUE';
      NO_DIR_CHECK='TRUE';
      ALLOW_CONNECT='TRUE';
    'BIF0#':
      PIN_NUMBER='(B7)';
      OUTPUT_LOAD='(1.0,-1.0)';
      PINUSE='OUT';
    'BIF1#':
      PIN_NUMBER='(B8)';
      OUTPUT_LOAD='(1.0,-1.0)';
      PINUSE='OUT';
    'BIF2#':
      PIN_NUMBER='(B9)';
      OUTPUT_LOAD='(1.0,-1.0)';
      PINUSE='OUT';
    'PERST0#':
      PIN_NUMBER='(B10)';
      OUTPUT_LOAD='(1.0,-1.0)';
      PINUSE='OUT';
    '+3.3V_EDGE':
      PIN_NUMBER='(B11)';
      PINUSE='POWER';
      NO_LOAD_CHECK='Both';
      NO_IO_CHECK='Both';
      NO_ASSERT_CHECK='TRUE';
      NO_DIR_CHECK='TRUE';
      ALLOW_CONNECT='TRUE';
    'AUX_PWR_EN':
      PIN_NUMBER='(B12)';
      OUTPUT_LOAD='(1.0,-1.0)';
      PINUSE='OUT';
    'GND_B13':
      PIN_NUMBER='(B13)';
      PINUSE='POWER';
      NO_LOAD_CHECK='Both';
      NO_IO_CHECK='Both';
      NO_ASSERT_CHECK='TRUE';
      NO_DIR_CHECK='TRUE';
      ALLOW_CONNECT='TRUE';
    'REFCLKN0':
      PIN_NUMBER='(B14)';
      INPUT_LOAD='(-0.01,0.01)';
      PINUSE='IN';
    'REFCLKP0':
      PIN_NUMBER='(B15)';
      OUTPUT_LOAD='(1.0,-1.0)';
      PINUSE='OUT';
    'GND_B16':
      PIN_NUMBER='(B16)';
      PINUSE='POWER';
      NO_LOAD_CHECK='Both';
      NO_IO_CHECK='Both';
      NO_ASSERT_CHECK='TRUE';
      NO_DIR_CHECK='TRUE';
      ALLOW_CONNECT='TRUE';
    'PETN0':
      PIN_NUMBER='(B17)';
      OUTPUT_LOAD='(1.0,-1.0)';
      PINUSE='OUT';
    'PETP0':
      PIN_NUMBER='(B18)';
      OUTPUT_LOAD='(1.0,-1.0)';
      PINUSE='OUT';
    'GND_B19':
      PIN_NUMBER='(B19)';
      PINUSE='POWER';
      NO_LOAD_CHECK='Both';
      NO_IO_CHECK='Both';
      NO_ASSERT_CHECK='TRUE';
      NO_DIR_CHECK='TRUE';
      ALLOW_CONNECT='TRUE';
    'PETN1':
      PIN_NUMBER='(B20)';
      OUTPUT_LOAD='(1.0,-1.0)';
      PINUSE='OUT';
    'PETP1':
      PIN_NUMBER='(B21)';
      OUTPUT_LOAD='(1.0,-1.0)';
      PINUSE='OUT';
    'GND_B22':
      PIN_NUMBER='(B22)';
      PINUSE='POWER';
      NO_LOAD_CHECK='Both';
      NO_IO_CHECK='Both';
      NO_ASSERT_CHECK='TRUE';
      NO_DIR_CHECK='TRUE';
      ALLOW_CONNECT='TRUE';
    'PETN2':
      PIN_NUMBER='(B23)';
      OUTPUT_LOAD='(1.0,-1.0)';
      PINUSE='OUT';
    'PETP2':
      PIN_NUMBER='(B24)';
      OUTPUT_LOAD='(1.0,-1.0)';
      PINUSE='OUT';
    'GND_B25':
      PIN_NUMBER='(B25)';
      PINUSE='POWER';
      NO_LOAD_CHECK='Both';
      NO_IO_CHECK='Both';
      NO_ASSERT_CHECK='TRUE';
      NO_DIR_CHECK='TRUE';
      ALLOW_CONNECT='TRUE';
    'PETN3':
      PIN_NUMBER='(B26)';
      OUTPUT_LOAD='(1.0,-1.0)';
      PINUSE='OUT';
    'PETP3':
      PIN_NUMBER='(B27)';
      OUTPUT_LOAD='(1.0,-1.0)';
      PINUSE='OUT';
    'GND_B28':
      PIN_NUMBER='(B28)';
      PINUSE='POWER';
      NO_LOAD_CHECK='Both';
      NO_IO_CHECK='Both';
      NO_ASSERT_CHECK='TRUE';
      NO_DIR_CHECK='TRUE';
      ALLOW_CONNECT='TRUE';
    'GND_B29':
      PIN_NUMBER='(B29)';
      PINUSE='POWER';
      NO_LOAD_CHECK='Both';
      NO_IO_CHECK='Both';
      NO_ASSERT_CHECK='TRUE';
      NO_DIR_CHECK='TRUE';
      ALLOW_CONNECT='TRUE';
    'PETN4':
      PIN_NUMBER='(B30)';
      OUTPUT_LOAD='(1.0,-1.0)';
      PINUSE='OUT';
    'PETP4':
      PIN_NUMBER='(B31)';
      OUTPUT_LOAD='(1.0,-1.0)';
      PINUSE='OUT';
    'GND_B32':
      PIN_NUMBER='(B32)';
      PINUSE='POWER';
      NO_LOAD_CHECK='Both';
      NO_IO_CHECK='Both';
      NO_ASSERT_CHECK='TRUE';
      NO_DIR_CHECK='TRUE';
      ALLOW_CONNECT='TRUE';
    'PETN5':
      PIN_NUMBER='(B33)';
      OUTPUT_LOAD='(1.0,-1.0)';
      PINUSE='OUT';
    'PETP5':
      PIN_NUMBER='(B34)';
      OUTPUT_LOAD='(1.0,-1.0)';
      PINUSE='OUT';
    'GND_B35':
      PIN_NUMBER='(B35)';
      PINUSE='POWER';
      NO_LOAD_CHECK='Both';
      NO_IO_CHECK='Both';
      NO_ASSERT_CHECK='TRUE';
      NO_DIR_CHECK='TRUE';
      ALLOW_CONNECT='TRUE';
    'PETN6':
      PIN_NUMBER='(B36)';
      OUTPUT_LOAD='(1.0,-1.0)';
      PINUSE='OUT';
    'PETP6':
      PIN_NUMBER='(B37)';
      OUTPUT_LOAD='(1.0,-1.0)';
      PINUSE='OUT';
    'GND_B38':
      PIN_NUMBER='(B38)';
      PINUSE='POWER';
      NO_LOAD_CHECK='Both';
      NO_IO_CHECK='Both';
      NO_ASSERT_CHECK='TRUE';
      NO_DIR_CHECK='TRUE';
      ALLOW_CONNECT='TRUE';
    'PETN7':
      PIN_NUMBER='(B39)';
      OUTPUT_LOAD='(1.0,-1.0)';
      PINUSE='OUT';
    'PETP7':
      PIN_NUMBER='(B40)';
      OUTPUT_LOAD='(1.0,-1.0)';
      PINUSE='OUT';
    'GND_B41':
      PIN_NUMBER='(B41)';
      PINUSE='POWER';
      NO_LOAD_CHECK='Both';
      NO_IO_CHECK='Both';
      NO_ASSERT_CHECK='TRUE';
      NO_DIR_CHECK='TRUE';
      ALLOW_CONNECT='TRUE';
    'PRSNTB0#':
      PIN_NUMBER='(B42)';
      INPUT_LOAD='(-0.01,0.01)';
      PINUSE='IN';
    'GND_B43':
      PIN_NUMBER='(B43)';
      PINUSE='POWER';
      NO_LOAD_CHECK='Both';
      NO_IO_CHECK='Both';
      NO_ASSERT_CHECK='TRUE';
      NO_DIR_CHECK='TRUE';
      ALLOW_CONNECT='TRUE';
    'PETN8':
      PIN_NUMBER='(B44)';
      OUTPUT_LOAD='(1.0,-1.0)';
      PINUSE='OUT';
    'PETP8':
      PIN_NUMBER='(B45)';
      OUTPUT_LOAD='(1.0,-1.0)';
      PINUSE='OUT';
    'GND_B46':
      PIN_NUMBER='(B46)';
      PINUSE='POWER';
      NO_LOAD_CHECK='Both';
      NO_IO_CHECK='Both';
      NO_ASSERT_CHECK='TRUE';
      NO_DIR_CHECK='TRUE';
      ALLOW_CONNECT='TRUE';
    'PETN9':
      PIN_NUMBER='(B47)';
      OUTPUT_LOAD='(1.0,-1.0)';
      PINUSE='OUT';
    'PETP9':
      PIN_NUMBER='(B48)';
      OUTPUT_LOAD='(1.0,-1.0)';
      PINUSE='OUT';
    'GND_B49':
      PIN_NUMBER='(B49)';
      PINUSE='POWER';
      NO_LOAD_CHECK='Both';
      NO_IO_CHECK='Both';
      NO_ASSERT_CHECK='TRUE';
      NO_DIR_CHECK='TRUE';
      ALLOW_CONNECT='TRUE';
    'PETN10':
      PIN_NUMBER='(B50)';
      OUTPUT_LOAD='(1.0,-1.0)';
      PINUSE='OUT';
    'PETP10':
      PIN_NUMBER='(B51)';
      OUTPUT_LOAD='(1.0,-1.0)';
      PINUSE='OUT';
    'GND_B52':
      PIN_NUMBER='(B52)';
      PINUSE='POWER';
      NO_LOAD_CHECK='Both';
      NO_IO_CHECK='Both';
      NO_ASSERT_CHECK='TRUE';
      NO_DIR_CHECK='TRUE';
      ALLOW_CONNECT='TRUE';
    'PETN11':
      PIN_NUMBER='(B53)';
      OUTPUT_LOAD='(1.0,-1.0)';
      PINUSE='OUT';
    'PETP11':
      PIN_NUMBER='(B54)';
      OUTPUT_LOAD='(1.0,-1.0)';
      PINUSE='OUT';
    'GND_B55':
      PIN_NUMBER='(B55)';
      PINUSE='POWER';
      NO_LOAD_CHECK='Both';
      NO_IO_CHECK='Both';
      NO_ASSERT_CHECK='TRUE';
      NO_DIR_CHECK='TRUE';
      ALLOW_CONNECT='TRUE';
    'PETN12':
      PIN_NUMBER='(B56)';
      OUTPUT_LOAD='(1.0,-1.0)';
      PINUSE='OUT';
    'PERST2#':
      PIN_NUMBER='(OA1)';
      OUTPUT_LOAD='(1.0,-1.0)';
      PINUSE='OUT';
    'PERST3#':
      PIN_NUMBER='(OA2)';
      OUTPUT_LOAD='(1.0,-1.0)';
      PINUSE='OUT';
    'WAKE#':
      PIN_NUMBER='(OA3)';
      INPUT_LOAD='(-0.01,0.01)';
      PINUSE='IN';
    'RBT_ARB_IN':
      PIN_NUMBER='(OA4)';
      INPUT_LOAD='(-0.01,0.01)';
      PINUSE='IN';
    'RBT_ARB_OUT':
      PIN_NUMBER='(OA5)';
      OUTPUT_LOAD='(1.0,-1.0)';
      PINUSE='OUT';
    'SLOT_ID1':
      PIN_NUMBER='(OA6)';
      OUTPUT_LOAD='(1.0,-1.0)';
      PINUSE='OUT';
    'RBT_TX_EN':
      PIN_NUMBER='(OA7)';
      OUTPUT_LOAD='(1.0,-1.0)';
      PINUSE='OUT';
    'RBT_TXD1':
      PIN_NUMBER='(OA8)';
      OUTPUT_LOAD='(1.0,-1.0)';
      PINUSE='OUT';
    'RBT_TXD0':
      PIN_NUMBER='(OA9)';
      OUTPUT_LOAD='(1.0,-1.0)';
      PINUSE='OUT';
    'GND_OA10':
      PIN_NUMBER='(OA10)';
      PINUSE='POWER';
      NO_LOAD_CHECK='Both';
      NO_IO_CHECK='Both';
      NO_ASSERT_CHECK='TRUE';
      NO_DIR_CHECK='TRUE';
      ALLOW_CONNECT='TRUE';
    'REFCLKN3':
      PIN_NUMBER='(OA11)';
      OUTPUT_LOAD='(1.0,-1.0)';
      PINUSE='OUT';
    'REFCLKP3':
      PIN_NUMBER='(OA12)';
      OUTPUT_LOAD='(1.0,-1.0)';
      PINUSE='OUT';
    'GND_OA13':
      PIN_NUMBER='(OA13)';
      PINUSE='POWER';
      NO_LOAD_CHECK='Both';
      NO_IO_CHECK='Both';
      NO_ASSERT_CHECK='TRUE';
      NO_DIR_CHECK='TRUE';
      ALLOW_CONNECT='TRUE';
    'RBT_CLK_IN':
      PIN_NUMBER='(OA14)';
      OUTPUT_LOAD='(1.0,-1.0)';
      PINUSE='OUT';
    'GND_A1':
      PIN_NUMBER='(A1)';
      PINUSE='POWER';
      NO_LOAD_CHECK='Both';
      NO_IO_CHECK='Both';
      NO_ASSERT_CHECK='TRUE';
      NO_DIR_CHECK='TRUE';
      ALLOW_CONNECT='TRUE';
    'GND_A2':
      PIN_NUMBER='(A2)';
      PINUSE='POWER';
      NO_LOAD_CHECK='Both';
      NO_IO_CHECK='Both';
      NO_ASSERT_CHECK='TRUE';
      NO_DIR_CHECK='TRUE';
      ALLOW_CONNECT='TRUE';
    'GND_A3':
      PIN_NUMBER='(A3)';
      PINUSE='POWER';
      NO_LOAD_CHECK='Both';
      NO_IO_CHECK='Both';
      NO_ASSERT_CHECK='TRUE';
      NO_DIR_CHECK='TRUE';
      ALLOW_CONNECT='TRUE';
    'GND_A4':
      PIN_NUMBER='(A4)';
      PINUSE='POWER';
      NO_LOAD_CHECK='Both';
      NO_IO_CHECK='Both';
      NO_ASSERT_CHECK='TRUE';
      NO_DIR_CHECK='TRUE';
      ALLOW_CONNECT='TRUE';
    'GND_A5':
      PIN_NUMBER='(A5)';
      PINUSE='POWER';
      NO_LOAD_CHECK='Both';
      NO_IO_CHECK='Both';
      NO_ASSERT_CHECK='TRUE';
      NO_DIR_CHECK='TRUE';
      ALLOW_CONNECT='TRUE';
    'GND_A6':
      PIN_NUMBER='(A6)';
      PINUSE='POWER';
      NO_LOAD_CHECK='Both';
      NO_IO_CHECK='Both';
      NO_ASSERT_CHECK='TRUE';
      NO_DIR_CHECK='TRUE';
      ALLOW_CONNECT='TRUE';
    'SMCLK':
      PIN_NUMBER='(A7)';
      OUTPUT_LOAD='(1.0,-1.0)';
      PINUSE='OUT';
    'SMDAT':
      PIN_NUMBER='(A8)';
      BIDIRECTIONAL='TRUE';
      INPUT_LOAD='(-0.01,0.01)';
      OUTPUT_LOAD='(1.0,-1.0)';
      PINUSE='BI';
    'SMRST#':
      PIN_NUMBER='(A9)';
      OUTPUT_LOAD='(1.0,-1.0)';
      PINUSE='OUT';
    'PRSNTA#':
      PIN_NUMBER='(A10)';
      OUTPUT_LOAD='(1.0,-1.0)';
      PINUSE='OUT';
    'PERST1#':
      PIN_NUMBER='(A11)';
      OUTPUT_LOAD='(1.0,-1.0)';
      PINUSE='OUT';
    'PRSNTB2#':
      PIN_NUMBER='(A12)';
      INPUT_LOAD='(-0.01,0.01)';
      PINUSE='IN';
    'GND_A13':
      PIN_NUMBER='(A13)';
      PINUSE='POWER';
      NO_LOAD_CHECK='Both';
      NO_IO_CHECK='Both';
      NO_ASSERT_CHECK='TRUE';
      NO_DIR_CHECK='TRUE';
      ALLOW_CONNECT='TRUE';
    'REFCLKN1':
      PIN_NUMBER='(A14)';
      OUTPUT_LOAD='(1.0,-1.0)';
      PINUSE='OUT';
    'REFCLKP1':
      PIN_NUMBER='(A15)';
      OUTPUT_LOAD='(1.0,-1.0)';
      PINUSE='OUT';
    'GND_A16':
      PIN_NUMBER='(A16)';
      PINUSE='POWER';
      NO_LOAD_CHECK='Both';
      NO_IO_CHECK='Both';
      NO_ASSERT_CHECK='TRUE';
      NO_DIR_CHECK='TRUE';
      ALLOW_CONNECT='TRUE';
    'PERN0':
      PIN_NUMBER='(A17)';
      INPUT_LOAD='(-0.01,0.01)';
      PINUSE='IN';
    'PERP0':
      PIN_NUMBER='(A18)';
      INPUT_LOAD='(-0.01,0.01)';
      PINUSE='IN';
    'GND_A19':
      PIN_NUMBER='(A19)';
      PINUSE='POWER';
      NO_LOAD_CHECK='Both';
      NO_IO_CHECK='Both';
      NO_ASSERT_CHECK='TRUE';
      NO_DIR_CHECK='TRUE';
      ALLOW_CONNECT='TRUE';
    'PERN1':
      PIN_NUMBER='(A20)';
      INPUT_LOAD='(-0.01,0.01)';
      PINUSE='IN';
    'PERP1':
      PIN_NUMBER='(A21)';
      INPUT_LOAD='(-0.01,0.01)';
      PINUSE='IN';
    'GND_A22':
      PIN_NUMBER='(A22)';
      PINUSE='POWER';
      NO_LOAD_CHECK='Both';
      NO_IO_CHECK='Both';
      NO_ASSERT_CHECK='TRUE';
      NO_DIR_CHECK='TRUE';
      ALLOW_CONNECT='TRUE';
    'PERN2':
      PIN_NUMBER='(A23)';
      INPUT_LOAD='(-0.01,0.01)';
      PINUSE='IN';
    'PERP2':
      PIN_NUMBER='(A24)';
      INPUT_LOAD='(-0.01,0.01)';
      PINUSE='IN';
    'GND_A25':
      PIN_NUMBER='(A25)';
      PINUSE='POWER';
      NO_LOAD_CHECK='Both';
      NO_IO_CHECK='Both';
      NO_ASSERT_CHECK='TRUE';
      NO_DIR_CHECK='TRUE';
      ALLOW_CONNECT='TRUE';
    'PERN3':
      PIN_NUMBER='(A26)';
      INPUT_LOAD='(-0.01,0.01)';
      PINUSE='IN';
    'PERP3':
      PIN_NUMBER='(A27)';
      INPUT_LOAD='(-0.01,0.01)';
      PINUSE='IN';
    'GND_A28':
      PIN_NUMBER='(A28)';
      PINUSE='POWER';
      NO_LOAD_CHECK='Both';
      NO_IO_CHECK='Both';
      NO_ASSERT_CHECK='TRUE';
      NO_DIR_CHECK='TRUE';
      ALLOW_CONNECT='TRUE';
    'GND_A29':
      PIN_NUMBER='(A29)';
      PINUSE='POWER';
      NO_LOAD_CHECK='Both';
      NO_IO_CHECK='Both';
      NO_ASSERT_CHECK='TRUE';
      NO_DIR_CHECK='TRUE';
      ALLOW_CONNECT='TRUE';
    'PERN4':
      PIN_NUMBER='(A30)';
      INPUT_LOAD='(-0.01,0.01)';
      PINUSE='IN';
    'PERP4':
      PIN_NUMBER='(A31)';
      INPUT_LOAD='(-0.01,0.01)';
      PINUSE='IN';
    'GND_A32':
      PIN_NUMBER='(A32)';
      PINUSE='POWER';
      NO_LOAD_CHECK='Both';
      NO_IO_CHECK='Both';
      NO_ASSERT_CHECK='TRUE';
      NO_DIR_CHECK='TRUE';
      ALLOW_CONNECT='TRUE';
    'PERN5':
      PIN_NUMBER='(A33)';
      INPUT_LOAD='(-0.01,0.01)';
      PINUSE='IN';
    'PERP5':
      PIN_NUMBER='(A34)';
      INPUT_LOAD='(-0.01,0.01)';
      PINUSE='IN';
    'GND_A35':
      PIN_NUMBER='(A35)';
      PINUSE='POWER';
      NO_LOAD_CHECK='Both';
      NO_IO_CHECK='Both';
      NO_ASSERT_CHECK='TRUE';
      NO_DIR_CHECK='TRUE';
      ALLOW_CONNECT='TRUE';
    'PERN6':
      PIN_NUMBER='(A36)';
      INPUT_LOAD='(-0.01,0.01)';
      PINUSE='IN';
    'PERP6':
      PIN_NUMBER='(A37)';
      INPUT_LOAD='(-0.01,0.01)';
      PINUSE='IN';
    'GND_A38':
      PIN_NUMBER='(A38)';
      PINUSE='POWER';
      NO_LOAD_CHECK='Both';
      NO_IO_CHECK='Both';
      NO_ASSERT_CHECK='TRUE';
      NO_DIR_CHECK='TRUE';
      ALLOW_CONNECT='TRUE';
    'PERN7':
      PIN_NUMBER='(A39)';
      INPUT_LOAD='(-0.01,0.01)';
      PINUSE='IN';
    'PERP7':
      PIN_NUMBER='(A40)';
      INPUT_LOAD='(-0.01,0.01)';
      PINUSE='IN';
    'GND_A41':
      PIN_NUMBER='(A41)';
      PINUSE='POWER';
      NO_LOAD_CHECK='Both';
      NO_IO_CHECK='Both';
      NO_ASSERT_CHECK='TRUE';
      NO_DIR_CHECK='TRUE';
      ALLOW_CONNECT='TRUE';
    'PRSNTB1#':
      PIN_NUMBER='(A42)';
      INPUT_LOAD='(-0.01,0.01)';
      PINUSE='IN';
    'GND_A43':
      PIN_NUMBER='(A43)';
      PINUSE='POWER';
      NO_LOAD_CHECK='Both';
      NO_IO_CHECK='Both';
      NO_ASSERT_CHECK='TRUE';
      NO_DIR_CHECK='TRUE';
      ALLOW_CONNECT='TRUE';
    'PERN8':
      PIN_NUMBER='(A44)';
      INPUT_LOAD='(-0.01,0.01)';
      PINUSE='IN';
    'PERP8':
      PIN_NUMBER='(A45)';
      INPUT_LOAD='(-0.01,0.01)';
      PINUSE='IN';
    'GND_A46':
      PIN_NUMBER='(A46)';
      PINUSE='POWER';
      NO_LOAD_CHECK='Both';
      NO_IO_CHECK='Both';
      NO_ASSERT_CHECK='TRUE';
      NO_DIR_CHECK='TRUE';
      ALLOW_CONNECT='TRUE';
    'PERN9':
      PIN_NUMBER='(A47)';
      INPUT_LOAD='(-0.01,0.01)';
      PINUSE='IN';
    'PERP9':
      PIN_NUMBER='(A48)';
      INPUT_LOAD='(-0.01,0.01)';
      PINUSE='IN';
    'GND_A49':
      PIN_NUMBER='(A49)';
      PINUSE='POWER';
      NO_LOAD_CHECK='Both';
      NO_IO_CHECK='Both';
      NO_ASSERT_CHECK='TRUE';
      NO_DIR_CHECK='TRUE';
      ALLOW_CONNECT='TRUE';
    'PERN10':
      PIN_NUMBER='(A50)';
      INPUT_LOAD='(-0.01,0.01)';
      PINUSE='IN';
    'PERP10':
      PIN_NUMBER='(A51)';
      INPUT_LOAD='(-0.01,0.01)';
      PINUSE='IN';
    'GND_A52':
      PIN_NUMBER='(A52)';
      PINUSE='POWER';
      NO_LOAD_CHECK='Both';
      NO_IO_CHECK='Both';
      NO_ASSERT_CHECK='TRUE';
      NO_DIR_CHECK='TRUE';
      ALLOW_CONNECT='TRUE';
    'PERN11':
      PIN_NUMBER='(A53)';
      INPUT_LOAD='(-0.01,0.01)';
      PINUSE='IN';
    'PERP11':
      PIN_NUMBER='(A54)';
      INPUT_LOAD='(-0.01,0.01)';
      PINUSE='IN';
    'GND_A55':
      PIN_NUMBER='(A55)';
      PINUSE='POWER';
      NO_LOAD_CHECK='Both';
      NO_IO_CHECK='Both';
      NO_ASSERT_CHECK='TRUE';
      NO_DIR_CHECK='TRUE';
      ALLOW_CONNECT='TRUE';
    'PERN12':
      PIN_NUMBER='(A56)';
      INPUT_LOAD='(-0.01,0.01)';
      PINUSE='IN';
    'PERP12':
      PIN_NUMBER='(A57)';
      INPUT_LOAD='(-0.01,0.01)';
      PINUSE='IN';
    'GND_A58':
      PIN_NUMBER='(A58)';
      PINUSE='POWER';
      NO_LOAD_CHECK='Both';
      NO_IO_CHECK='Both';
      NO_ASSERT_CHECK='TRUE';
      NO_DIR_CHECK='TRUE';
      ALLOW_CONNECT='TRUE';
    'PERN13':
      PIN_NUMBER='(A59)';
      INPUT_LOAD='(-0.01,0.01)';
      PINUSE='IN';
    'PERP13':
      PIN_NUMBER='(A60)';
      INPUT_LOAD='(-0.01,0.01)';
      PINUSE='IN';
    'GND_A61':
      PIN_NUMBER='(A61)';
      PINUSE='POWER';
      NO_LOAD_CHECK='Both';
      NO_IO_CHECK='Both';
      NO_ASSERT_CHECK='TRUE';
      NO_DIR_CHECK='TRUE';
      ALLOW_CONNECT='TRUE';
    'PERN14':
      PIN_NUMBER='(A62)';
      INPUT_LOAD='(-0.01,0.01)';
      PINUSE='IN';
    'PERP14':
      PIN_NUMBER='(A63)';
      INPUT_LOAD='(-0.01,0.01)';
      PINUSE='IN';
    'GND_A64':
      PIN_NUMBER='(A64)';
      PINUSE='POWER';
      NO_LOAD_CHECK='Both';
      NO_IO_CHECK='Both';
      NO_ASSERT_CHECK='TRUE';
      NO_DIR_CHECK='TRUE';
      ALLOW_CONNECT='TRUE';
    'PERN15':
      PIN_NUMBER='(A65)';
      INPUT_LOAD='(-0.01,0.01)';
      PINUSE='IN';
    'PERP15':
      PIN_NUMBER='(A66)';
      INPUT_LOAD='(-0.01,0.01)';
      PINUSE='IN';
    'GND_A67':
      PIN_NUMBER='(A67)';
      PINUSE='POWER';
      NO_LOAD_CHECK='Both';
      NO_IO_CHECK='Both';
      NO_ASSERT_CHECK='TRUE';
      NO_DIR_CHECK='TRUE';
      ALLOW_CONNECT='TRUE';
    'USB_DATN':
      PIN_NUMBER='(A68)';
      BIDIRECTIONAL='TRUE';
      INPUT_LOAD='(-0.01,0.01)';
      OUTPUT_LOAD='(1.0,-1.0)';
      PINUSE='BI';
    'USB_DATP':
      PIN_NUMBER='(A69)';
      BIDIRECTIONAL='TRUE';
      INPUT_LOAD='(-0.01,0.01)';
      OUTPUT_LOAD='(1.0,-1.0)';
      PINUSE='BI';
    'PWRBRK0#':
      PIN_NUMBER='(A70)';
      BIDIRECTIONAL='TRUE';
      INPUT_LOAD='(-0.01,0.01)';
      OUTPUT_LOAD='(1.0,-1.0)';
      PINUSE='BI';
    'PETP12':
      PIN_NUMBER='(B57)';
      OUTPUT_LOAD='(1.0,-1.0)';
      PINUSE='OUT';
    'GND_B58':
      PIN_NUMBER='(B58)';
      PINUSE='POWER';
      NO_LOAD_CHECK='Both';
      NO_IO_CHECK='Both';
      NO_ASSERT_CHECK='TRUE';
      NO_DIR_CHECK='TRUE';
      ALLOW_CONNECT='TRUE';
    'PETN13':
      PIN_NUMBER='(B59)';
      OUTPUT_LOAD='(1.0,-1.0)';
      PINUSE='OUT';
    'PETP13':
      PIN_NUMBER='(B60)';
      OUTPUT_LOAD='(1.0,-1.0)';
      PINUSE='OUT';
    'GND_B61':
      PIN_NUMBER='(B61)';
      PINUSE='POWER';
      NO_LOAD_CHECK='Both';
      NO_IO_CHECK='Both';
      NO_ASSERT_CHECK='TRUE';
      NO_DIR_CHECK='TRUE';
      ALLOW_CONNECT='TRUE';
    'PETN14':
      PIN_NUMBER='(B62)';
      OUTPUT_LOAD='(1.0,-1.0)';
      PINUSE='OUT';
    'PETP14':
      PIN_NUMBER='(B63)';
      OUTPUT_LOAD='(1.0,-1.0)';
      PINUSE='OUT';
    'GND_B64':
      PIN_NUMBER='(B64)';
      PINUSE='POWER';
      NO_LOAD_CHECK='Both';
      NO_IO_CHECK='Both';
      NO_ASSERT_CHECK='TRUE';
      NO_DIR_CHECK='TRUE';
      ALLOW_CONNECT='TRUE';
    'PETN15':
      PIN_NUMBER='(B65)';
      OUTPUT_LOAD='(1.0,-1.0)';
      PINUSE='OUT';
    'PETP15':
      PIN_NUMBER='(B66)';
      OUTPUT_LOAD='(1.0,-1.0)';
      PINUSE='OUT';
    'GND_B67':
      PIN_NUMBER='(B67)';
      PINUSE='POWER';
      NO_LOAD_CHECK='Both';
      NO_IO_CHECK='Both';
      NO_ASSERT_CHECK='TRUE';
      NO_DIR_CHECK='TRUE';
      ALLOW_CONNECT='TRUE';
    'RFU1_NC_B68':
      PIN_NUMBER='(B68)';
      OUTPUT_TYPE='(TS,TS)';
      INPUT_LOAD='(-0.01,0.01)';
      OUTPUT_LOAD='(1.0,-1.0)';
      PINUSE='TRI';
    'RFU1_NC_B69':
      PIN_NUMBER='(B69)';
      OUTPUT_TYPE='(TS,TS)';
      INPUT_LOAD='(-0.01,0.01)';
      OUTPUT_LOAD='(1.0,-1.0)';
      PINUSE='TRI';
    'PRSNTB3#':
      PIN_NUMBER='(B70)';
      INPUT_LOAD='(-0.01,0.01)';
      PINUSE='IN';
    'G1':
      PIN_NUMBER='(G1)';
      PINUSE='POWER';
      NO_LOAD_CHECK='Both';
      NO_IO_CHECK='Both';
      NO_ASSERT_CHECK='TRUE';
      NO_DIR_CHECK='TRUE';
      ALLOW_CONNECT='TRUE';
    'G2':
      PIN_NUMBER='(G2)';
      PINUSE='POWER';
      NO_LOAD_CHECK='Both';
      NO_IO_CHECK='Both';
      NO_ASSERT_CHECK='TRUE';
      NO_DIR_CHECK='TRUE';
      ALLOW_CONNECT='TRUE';
    'G3':
      PIN_NUMBER='(G3)';
      PINUSE='POWER';
      NO_LOAD_CHECK='Both';
      NO_IO_CHECK='Both';
      NO_ASSERT_CHECK='TRUE';
      NO_DIR_CHECK='TRUE';
      ALLOW_CONNECT='TRUE';
    'G4':
      PIN_NUMBER='(G4)';
      PINUSE='POWER';
      NO_LOAD_CHECK='Both';
      NO_IO_CHECK='Both';
      NO_ASSERT_CHECK='TRUE';
      NO_DIR_CHECK='TRUE';
      ALLOW_CONNECT='TRUE';
    'G5':
      PIN_NUMBER='(G5)';
      PINUSE='POWER';
      NO_LOAD_CHECK='Both';
      NO_IO_CHECK='Both';
      NO_ASSERT_CHECK='TRUE';
      NO_DIR_CHECK='TRUE';
      ALLOW_CONNECT='TRUE';
  end_pin;
  body
      PART_NAME='SCONN168_ME1016810202011';
      BODY_NAME='SCONN168_ME1016810202011';
      PHYS_DES_PREFIX='J';
      CLASS='IO';
      NC_PINS='(H1,H2)';
      STANDARD='';
      LIFECYCLE='';
      PART_NUMBER='DFHSG8FR011';
      JEDEC_TYPE='CON_F168S2H7D_P0-6W2-95_LUH';
      DESCRIPTION='CONN SMD HOUSING 168P 2R FR(P0.6,H5.35)';
      MANUFTR='APL';
      MANUF_PN='ME1016810202011';
      RD_CMPLS_LVL='EP(V1)';
      CMPLS_LVL='';
      DIP_SMD='';
      FROM_PJ='F0C-BELL';
      DATA='APL_ME1016810202011.pdf';
      FP_ECN='ME1016810202011.msg';
      EE_CHECK_LIST='';
      CREATOR='';
      CREATEDAY='20200615';
      PSL='';
      STATUS='';
      ESD_CDM='NA';
      ESD_HBM='NA';
      ESD_MM='NA';
      MSD='NA';
      PIN_LENGTH_LONG_PIN='56 MILS';
      PIN_LENGTH_SHORT_PIN='36 MILS';
      PARENT_PART_TYPE='SCONN168_ME1016810202011';
      PARENT_PPT='SCONN168_ME1016810202011';
      PARENT_PPT_PART='SCONN168_ME1016810202011-SCONN168_ME1016810202011,SMLF,IO,DFHSG8FR011';
  end_body;
end_primitive;
primitive 'SCONN20_HSU2101L00007H-SCONN20_HSU2101-L0000-7H,SMA';
  pin
    '1':
      PIN_NUMBER='(1)';
      BIDIRECTIONAL='TRUE';
      INPUT_LOAD='(-0.01,0.01)';
      OUTPUT_LOAD='(1.0,-1.0)';
      PINUSE='BI';
    '2':
      PIN_NUMBER='(2)';
      BIDIRECTIONAL='TRUE';
      INPUT_LOAD='(-0.01,0.01)';
      OUTPUT_LOAD='(1.0,-1.0)';
      PINUSE='BI';
    '3':
      PIN_NUMBER='(3)';
      BIDIRECTIONAL='TRUE';
      INPUT_LOAD='(-0.01,0.01)';
      OUTPUT_LOAD='(1.0,-1.0)';
      PINUSE='BI';
    '4':
      PIN_NUMBER='(4)';
      BIDIRECTIONAL='TRUE';
      INPUT_LOAD='(-0.01,0.01)';
      OUTPUT_LOAD='(1.0,-1.0)';
      PINUSE='BI';
    '5':
      PIN_NUMBER='(5)';
      BIDIRECTIONAL='TRUE';
      INPUT_LOAD='(-0.01,0.01)';
      OUTPUT_LOAD='(1.0,-1.0)';
      PINUSE='BI';
    '6':
      PIN_NUMBER='(6)';
      BIDIRECTIONAL='TRUE';
      INPUT_LOAD='(-0.01,0.01)';
      OUTPUT_LOAD='(1.0,-1.0)';
      PINUSE='BI';
    '7':
      PIN_NUMBER='(7)';
      BIDIRECTIONAL='TRUE';
      INPUT_LOAD='(-0.01,0.01)';
      OUTPUT_LOAD='(1.0,-1.0)';
      PINUSE='BI';
    '8':
      PIN_NUMBER='(8)';
      BIDIRECTIONAL='TRUE';
      INPUT_LOAD='(-0.01,0.01)';
      OUTPUT_LOAD='(1.0,-1.0)';
      PINUSE='BI';
    '9':
      PIN_NUMBER='(9)';
      BIDIRECTIONAL='TRUE';
      INPUT_LOAD='(-0.01,0.01)';
      OUTPUT_LOAD='(1.0,-1.0)';
      PINUSE='BI';
    '10':
      PIN_NUMBER='(10)';
      BIDIRECTIONAL='TRUE';
      INPUT_LOAD='(-0.01,0.01)';
      OUTPUT_LOAD='(1.0,-1.0)';
      PINUSE='BI';
    '11':
      PIN_NUMBER='(11)';
      BIDIRECTIONAL='TRUE';
      INPUT_LOAD='(-0.01,0.01)';
      OUTPUT_LOAD='(1.0,-1.0)';
      PINUSE='BI';
    '12':
      PIN_NUMBER='(12)';
      BIDIRECTIONAL='TRUE';
      INPUT_LOAD='(-0.01,0.01)';
      OUTPUT_LOAD='(1.0,-1.0)';
      PINUSE='BI';
    '13':
      PIN_NUMBER='(13)';
      BIDIRECTIONAL='TRUE';
      INPUT_LOAD='(-0.01,0.01)';
      OUTPUT_LOAD='(1.0,-1.0)';
      PINUSE='BI';
    '14':
      PIN_NUMBER='(14)';
      BIDIRECTIONAL='TRUE';
      INPUT_LOAD='(-0.01,0.01)';
      OUTPUT_LOAD='(1.0,-1.0)';
      PINUSE='BI';
    '15':
      PIN_NUMBER='(15)';
      BIDIRECTIONAL='TRUE';
      INPUT_LOAD='(-0.01,0.01)';
      OUTPUT_LOAD='(1.0,-1.0)';
      PINUSE='BI';
    '16':
      PIN_NUMBER='(16)';
      BIDIRECTIONAL='TRUE';
      INPUT_LOAD='(-0.01,0.01)';
      OUTPUT_LOAD='(1.0,-1.0)';
      PINUSE='BI';
    '17':
      PIN_NUMBER='(17)';
      BIDIRECTIONAL='TRUE';
      INPUT_LOAD='(-0.01,0.01)';
      OUTPUT_LOAD='(1.0,-1.0)';
      PINUSE='BI';
    '18':
      PIN_NUMBER='(18)';
      BIDIRECTIONAL='TRUE';
      INPUT_LOAD='(-0.01,0.01)';
      OUTPUT_LOAD='(1.0,-1.0)';
      PINUSE='BI';
    '19':
      PIN_NUMBER='(19)';
      BIDIRECTIONAL='TRUE';
      INPUT_LOAD='(-0.01,0.01)';
      OUTPUT_LOAD='(1.0,-1.0)';
      PINUSE='BI';
    '20':
      PIN_NUMBER='(20)';
      BIDIRECTIONAL='TRUE';
      INPUT_LOAD='(-0.01,0.01)';
      OUTPUT_LOAD='(1.0,-1.0)';
      PINUSE='BI';
  end_pin;
  body
      PART_NAME='SCONN20_HSU2101L00007H';
      BODY_NAME='SCONN20_HSU2101L00007H';
      PHYS_DES_PREFIX='J';
      CLASS='IO';
      STANDARD='';
      LIFECYCLE='';
      PART_NUMBER='DFHD20MS153';
      JEDEC_TYPE='HEADER2X10SXK';
      DESCRIPTION='CONN SMD HEADER 20P 2R MS(P1.27,H6.14)';
      MANUFTR='FOX';
      MANUF_PN='HSU2101-L0000-7H';
      RD_CMPLS_LVL='EP(V1)';
      CMPLS_LVL='EP(V1)';
      DIP_SMD='';
      FROM_PJ='T6G-JAY';
      DATA='FOX_HSU2101-L0000-7H.pdf';
      FP_ECN='HSU2101-L0000-7H.msg';
      EE_CHECK_LIST='';
      CREATOR='';
      CREATEDAY='20210719';
      PSL='';
      STATUS='';
      ESD_CDM='';
      ESD_HBM='';
      ESD_MM='';
      MSD='';
      PIN_LENGTH_LONG_PIN='0 MILS';
      PIN_LENGTH_SHORT_PIN='0 MILS';
      PARENT_PART_TYPE='SCONN20_HSU2101L00007H';
      PARENT_PPT='SCONN20_HSU2101L00007H';
      PARENT_PPT_PART='SCONN20_HSU2101L00007H-SCONN20_HSU2101-L0000-7H,SMLF,IO,DFHD20MS153';
  end_body;
end_primitive;
primitive 'SCONN21_9193031121LF-SCONN21_91930-31121LF,SMLF,IOA';
  pin
    '1':
      PIN_NUMBER='(1)';
      BIDIRECTIONAL='TRUE';
      INPUT_LOAD='(-0.01,0.01)';
      OUTPUT_LOAD='(1.0,-1.0)';
      PINUSE='BI';
    '3':
      PIN_NUMBER='(3)';
      BIDIRECTIONAL='TRUE';
      INPUT_LOAD='(-0.01,0.01)';
      OUTPUT_LOAD='(1.0,-1.0)';
      PINUSE='BI';
    '4':
      PIN_NUMBER='(4)';
      BIDIRECTIONAL='TRUE';
      INPUT_LOAD='(-0.01,0.01)';
      OUTPUT_LOAD='(1.0,-1.0)';
      PINUSE='BI';
    '5':
      PIN_NUMBER='(5)';
      BIDIRECTIONAL='TRUE';
      INPUT_LOAD='(-0.01,0.01)';
      OUTPUT_LOAD='(1.0,-1.0)';
      PINUSE='BI';
    '2':
      PIN_NUMBER='(2)';
      BIDIRECTIONAL='TRUE';
      INPUT_LOAD='(-0.01,0.01)';
      OUTPUT_LOAD='(1.0,-1.0)';
      PINUSE='BI';
    'G1':
      PIN_NUMBER='(G1)';
      PINUSE='POWER';
      NO_LOAD_CHECK='Both';
      NO_IO_CHECK='Both';
      NO_ASSERT_CHECK='TRUE';
      NO_DIR_CHECK='TRUE';
      ALLOW_CONNECT='TRUE';
    'G2':
      PIN_NUMBER='(G2)';
      PINUSE='POWER';
      NO_LOAD_CHECK='Both';
      NO_IO_CHECK='Both';
      NO_ASSERT_CHECK='TRUE';
      NO_DIR_CHECK='TRUE';
      ALLOW_CONNECT='TRUE';
    '6':
      PIN_NUMBER='(6)';
      BIDIRECTIONAL='TRUE';
      INPUT_LOAD='(-0.01,0.01)';
      OUTPUT_LOAD='(1.0,-1.0)';
      PINUSE='BI';
    '7':
      PIN_NUMBER='(7)';
      BIDIRECTIONAL='TRUE';
      INPUT_LOAD='(-0.01,0.01)';
      OUTPUT_LOAD='(1.0,-1.0)';
      PINUSE='BI';
    '8':
      PIN_NUMBER='(8)';
      BIDIRECTIONAL='TRUE';
      INPUT_LOAD='(-0.01,0.01)';
      OUTPUT_LOAD='(1.0,-1.0)';
      PINUSE='BI';
    '9':
      PIN_NUMBER='(9)';
      BIDIRECTIONAL='TRUE';
      INPUT_LOAD='(-0.01,0.01)';
      OUTPUT_LOAD='(1.0,-1.0)';
      PINUSE='BI';
    '10':
      PIN_NUMBER='(10)';
      BIDIRECTIONAL='TRUE';
      INPUT_LOAD='(-0.01,0.01)';
      OUTPUT_LOAD='(1.0,-1.0)';
      PINUSE='BI';
    '11':
      PIN_NUMBER='(11)';
      BIDIRECTIONAL='TRUE';
      INPUT_LOAD='(-0.01,0.01)';
      OUTPUT_LOAD='(1.0,-1.0)';
      PINUSE='BI';
    '12':
      PIN_NUMBER='(12)';
      BIDIRECTIONAL='TRUE';
      INPUT_LOAD='(-0.01,0.01)';
      OUTPUT_LOAD='(1.0,-1.0)';
      PINUSE='BI';
    '13':
      PIN_NUMBER='(13)';
      BIDIRECTIONAL='TRUE';
      INPUT_LOAD='(-0.01,0.01)';
      OUTPUT_LOAD='(1.0,-1.0)';
      PINUSE='BI';
    '14':
      PIN_NUMBER='(14)';
      BIDIRECTIONAL='TRUE';
      INPUT_LOAD='(-0.01,0.01)';
      OUTPUT_LOAD='(1.0,-1.0)';
      PINUSE='BI';
    '15':
      PIN_NUMBER='(15)';
      BIDIRECTIONAL='TRUE';
      INPUT_LOAD='(-0.01,0.01)';
      OUTPUT_LOAD='(1.0,-1.0)';
      PINUSE='BI';
    '16':
      PIN_NUMBER='(16)';
      BIDIRECTIONAL='TRUE';
      INPUT_LOAD='(-0.01,0.01)';
      OUTPUT_LOAD='(1.0,-1.0)';
      PINUSE='BI';
    '17':
      PIN_NUMBER='(17)';
      BIDIRECTIONAL='TRUE';
      INPUT_LOAD='(-0.01,0.01)';
      OUTPUT_LOAD='(1.0,-1.0)';
      PINUSE='BI';
    '18':
      PIN_NUMBER='(18)';
      BIDIRECTIONAL='TRUE';
      INPUT_LOAD='(-0.01,0.01)';
      OUTPUT_LOAD='(1.0,-1.0)';
      PINUSE='BI';
    '19':
      PIN_NUMBER='(19)';
      BIDIRECTIONAL='TRUE';
      INPUT_LOAD='(-0.01,0.01)';
      OUTPUT_LOAD='(1.0,-1.0)';
      PINUSE='BI';
    '20':
      PIN_NUMBER='(20)';
      BIDIRECTIONAL='TRUE';
      INPUT_LOAD='(-0.01,0.01)';
      OUTPUT_LOAD='(1.0,-1.0)';
      PINUSE='BI';
    '21':
      PIN_NUMBER='(21)';
      BIDIRECTIONAL='TRUE';
      INPUT_LOAD='(-0.01,0.01)';
      OUTPUT_LOAD='(1.0,-1.0)';
      PINUSE='BI';
  end_pin;
  body
      PART_NAME='SCONN21_9193031121LF';
      BODY_NAME='SCONN21_9193031121LF';
      PHYS_DES_PREFIX='J';
      CLASS='IO';
      NC_PINS='(H1,H2)';
      STANDARD='';
      LIFECYCLE='';
      PART_NUMBER='DFHS21FS003';
      JEDEC_TYPE='CON_F21S2H2D2S_P1W4-22_LDH';
      DESCRIPTION='CONN SMD HOUSING 21P 2R FS(P1,H3.28)';
      MANUFTR='APL';
      MANUF_PN='91930-31121LF';
      RD_CMPLS_LVL='EP(V1)';
      CMPLS_LVL='';
      DIP_SMD='';
      FROM_PJ='F0T-IVES';
      DATA='APL_91930-31121LF.pdf';
      FP_ECN='91930-31121LF.msg';
      EE_CHECK_LIST='';
      CREATOR='';
      CREATEDAY='20220421';
      PSL='';
      STATUS='';
      ESD_CDM='';
      ESD_HBM='';
      ESD_MM='';
      MSD='';
      PIN_LENGTH_LONG_PIN='20 MILS';
      PIN_LENGTH_SHORT_PIN='20 MILS';
      PARENT_PART_TYPE='SCONN21_9193031121LF';
      PARENT_PPT='SCONN21_9193031121LF';
      PARENT_PPT_PART='SCONN21_9193031121LF-SCONN21_91930-31121LF,SMLF,IO,DFHS21FS003';
  end_body;
end_primitive;
primitive 'SCONN288_DDR506112002KQ-SCONN288_DDR506112002KQ,SMA';
  pin
    'VIN_MGMT':
      PIN_NUMBER='(3,0,0)';
      PINUSE='POWER';
      NO_LOAD_CHECK='Both';
      NO_IO_CHECK='Both';
      NO_ASSERT_CHECK='TRUE';
      NO_DIR_CHECK='TRUE';
      ALLOW_CONNECT='TRUE';
    'RFU0':
      PIN_NUMBER='(2,0,0)';
      OUTPUT_TYPE='(TS,TS)';
      INPUT_LOAD='(-0.01,0.01)';
      OUTPUT_LOAD='(1.0,-1.0)';
      PINUSE='TRI';
    'RFU1':
      PIN_NUMBER='(144,0,0)';
      OUTPUT_TYPE='(TS,TS)';
      INPUT_LOAD='(-0.01,0.01)';
      OUTPUT_LOAD='(1.0,-1.0)';
      PINUSE='TRI';
    'RFU2':
      PIN_NUMBER='(149,0,0)';
      OUTPUT_TYPE='(TS,TS)';
      INPUT_LOAD='(-0.01,0.01)';
      OUTPUT_LOAD='(1.0,-1.0)';
      PINUSE='TRI';
    'RFU3':
      PIN_NUMBER='(150,0,0)';
      OUTPUT_TYPE='(TS,TS)';
      INPUT_LOAD='(-0.01,0.01)';
      OUTPUT_LOAD='(1.0,-1.0)';
      PINUSE='TRI';
    'RFU4':
      PIN_NUMBER='(220,0,0)';
      OUTPUT_TYPE='(TS,TS)';
      INPUT_LOAD='(-0.01,0.01)';
      OUTPUT_LOAD='(1.0,-1.0)';
      PINUSE='TRI';
    'RFU5':
      PIN_NUMBER='(231,0,0)';
      OUTPUT_TYPE='(TS,TS)';
      INPUT_LOAD='(-0.01,0.01)';
      OUTPUT_LOAD='(1.0,-1.0)';
      PINUSE='TRI';
    'RFU6':
      PIN_NUMBER='(232,0,0)';
      OUTPUT_TYPE='(TS,TS)';
      INPUT_LOAD='(-0.01,0.01)';
      OUTPUT_LOAD='(1.0,-1.0)';
      PINUSE='TRI';
    'RESET_N':
      PIN_NUMBER='(207,0,0)';
      INPUT_LOAD='(-0.01,0.01)';
      PINUSE='IN';
    'PWR_GOOD||FAIL_N':
      PIN_NUMBER='(147,0,0)';
      BIDIRECTIONAL='TRUE';
      INPUT_LOAD='(-0.01,0.01)';
      OUTPUT_LOAD='(1.0,-1.0)';
      PINUSE='BI';
    'PAR_B':
      PIN_NUMBER='(227,0,0)';
      INPUT_LOAD='(-0.01,0.01)';
      PINUSE='IN';
    'PAR_A':
      PIN_NUMBER='(74,0,0)';
      INPUT_LOAD='(-0.01,0.01)';
      PINUSE='IN';
    'LBS||RSP_B_N':
      PIN_NUMBER='(87,0,0)';
      OUTPUT_LOAD='(1.0,-1.0)';
      PINUSE='OUT';
    'LBD||RSP_A_N':
      PIN_NUMBER='(86,0,0)';
      OUTPUT_LOAD='(1.0,-1.0)';
      PINUSE='OUT';
    'HSDA':
      PIN_NUMBER='(5,0,0)';
      BIDIRECTIONAL='TRUE';
      INPUT_LOAD='(-0.01,0.01)';
      OUTPUT_LOAD='(1.0,-1.0)';
      PINUSE='BI';
    'HSCL':
      PIN_NUMBER='(4,0,0)';
      INPUT_LOAD='(-0.01,0.01)';
      PINUSE='IN';
    'HAS':
      PIN_NUMBER='(148,0,0)';
      INPUT_LOAD='(-0.01,0.01)';
      PINUSE='IN';
    'DQ0_B':
      PIN_NUMBER='(100,0,0)';
      BIDIRECTIONAL='TRUE';
      INPUT_LOAD='(-0.01,0.01)';
      OUTPUT_LOAD='(1.0,-1.0)';
      PINUSE='BI';
    'DQ1_B':
      PIN_NUMBER='(102,0,0)';
      BIDIRECTIONAL='TRUE';
      INPUT_LOAD='(-0.01,0.01)';
      OUTPUT_LOAD='(1.0,-1.0)';
      PINUSE='BI';
    'DQ2_B':
      PIN_NUMBER='(245,0,0)';
      BIDIRECTIONAL='TRUE';
      INPUT_LOAD='(-0.01,0.01)';
      OUTPUT_LOAD='(1.0,-1.0)';
      PINUSE='BI';
    'DQ3_B':
      PIN_NUMBER='(247,0,0)';
      BIDIRECTIONAL='TRUE';
      INPUT_LOAD='(-0.01,0.01)';
      OUTPUT_LOAD='(1.0,-1.0)';
      PINUSE='BI';
    'DQ4_B':
      PIN_NUMBER='(107,0,0)';
      BIDIRECTIONAL='TRUE';
      INPUT_LOAD='(-0.01,0.01)';
      OUTPUT_LOAD='(1.0,-1.0)';
      PINUSE='BI';
    'DQ5_B':
      PIN_NUMBER='(109,0,0)';
      BIDIRECTIONAL='TRUE';
      INPUT_LOAD='(-0.01,0.01)';
      OUTPUT_LOAD='(1.0,-1.0)';
      PINUSE='BI';
    'DQ6_B':
      PIN_NUMBER='(252,0,0)';
      BIDIRECTIONAL='TRUE';
      INPUT_LOAD='(-0.01,0.01)';
      OUTPUT_LOAD='(1.0,-1.0)';
      PINUSE='BI';
    'DQ7_B':
      PIN_NUMBER='(254,0,0)';
      BIDIRECTIONAL='TRUE';
      INPUT_LOAD='(-0.01,0.01)';
      OUTPUT_LOAD='(1.0,-1.0)';
      PINUSE='BI';
    'DQ8_B':
      PIN_NUMBER='(111,0,0)';
      BIDIRECTIONAL='TRUE';
      INPUT_LOAD='(-0.01,0.01)';
      OUTPUT_LOAD='(1.0,-1.0)';
      PINUSE='BI';
    'DQ9_B':
      PIN_NUMBER='(113,0,0)';
      BIDIRECTIONAL='TRUE';
      INPUT_LOAD='(-0.01,0.01)';
      OUTPUT_LOAD='(1.0,-1.0)';
      PINUSE='BI';
    'DQ10_B':
      PIN_NUMBER='(256,0,0)';
      BIDIRECTIONAL='TRUE';
      INPUT_LOAD='(-0.01,0.01)';
      OUTPUT_LOAD='(1.0,-1.0)';
      PINUSE='BI';
    'DQ11_B':
      PIN_NUMBER='(258,0,0)';
      BIDIRECTIONAL='TRUE';
      INPUT_LOAD='(-0.01,0.01)';
      OUTPUT_LOAD='(1.0,-1.0)';
      PINUSE='BI';
    'DQ12_B':
      PIN_NUMBER='(118,0,0)';
      BIDIRECTIONAL='TRUE';
      INPUT_LOAD='(-0.01,0.01)';
      OUTPUT_LOAD='(1.0,-1.0)';
      PINUSE='BI';
    'DQ13_B':
      PIN_NUMBER='(120,0,0)';
      BIDIRECTIONAL='TRUE';
      INPUT_LOAD='(-0.01,0.01)';
      OUTPUT_LOAD='(1.0,-1.0)';
      PINUSE='BI';
    'DQ14_B':
      PIN_NUMBER='(263,0,0)';
      BIDIRECTIONAL='TRUE';
      INPUT_LOAD='(-0.01,0.01)';
      OUTPUT_LOAD='(1.0,-1.0)';
      PINUSE='BI';
    'DQ15_B':
      PIN_NUMBER='(265,0,0)';
      BIDIRECTIONAL='TRUE';
      INPUT_LOAD='(-0.01,0.01)';
      OUTPUT_LOAD='(1.0,-1.0)';
      PINUSE='BI';
    'DQ16_B':
      PIN_NUMBER='(122,0,0)';
      BIDIRECTIONAL='TRUE';
      INPUT_LOAD='(-0.01,0.01)';
      OUTPUT_LOAD='(1.0,-1.0)';
      PINUSE='BI';
    'DQ17_B':
      PIN_NUMBER='(124,0,0)';
      BIDIRECTIONAL='TRUE';
      INPUT_LOAD='(-0.01,0.01)';
      OUTPUT_LOAD='(1.0,-1.0)';
      PINUSE='BI';
    'DQ18_B':
      PIN_NUMBER='(267,0,0)';
      BIDIRECTIONAL='TRUE';
      INPUT_LOAD='(-0.01,0.01)';
      OUTPUT_LOAD='(1.0,-1.0)';
      PINUSE='BI';
    'DQ19_B':
      PIN_NUMBER='(269,0,0)';
      BIDIRECTIONAL='TRUE';
      INPUT_LOAD='(-0.01,0.01)';
      OUTPUT_LOAD='(1.0,-1.0)';
      PINUSE='BI';
    'DQ20_B':
      PIN_NUMBER='(129,0,0)';
      BIDIRECTIONAL='TRUE';
      INPUT_LOAD='(-0.01,0.01)';
      OUTPUT_LOAD='(1.0,-1.0)';
      PINUSE='BI';
    'DQ21_B':
      PIN_NUMBER='(131,0,0)';
      BIDIRECTIONAL='TRUE';
      INPUT_LOAD='(-0.01,0.01)';
      OUTPUT_LOAD='(1.0,-1.0)';
      PINUSE='BI';
    'DQ22_B':
      PIN_NUMBER='(274,0,0)';
      BIDIRECTIONAL='TRUE';
      INPUT_LOAD='(-0.01,0.01)';
      OUTPUT_LOAD='(1.0,-1.0)';
      PINUSE='BI';
    'DQ23_B':
      PIN_NUMBER='(276,0,0)';
      BIDIRECTIONAL='TRUE';
      INPUT_LOAD='(-0.01,0.01)';
      OUTPUT_LOAD='(1.0,-1.0)';
      PINUSE='BI';
    'DQ24_B':
      PIN_NUMBER='(133,0,0)';
      BIDIRECTIONAL='TRUE';
      INPUT_LOAD='(-0.01,0.01)';
      OUTPUT_LOAD='(1.0,-1.0)';
      PINUSE='BI';
    'DQ25_B':
      PIN_NUMBER='(135,0,0)';
      BIDIRECTIONAL='TRUE';
      INPUT_LOAD='(-0.01,0.01)';
      OUTPUT_LOAD='(1.0,-1.0)';
      PINUSE='BI';
    'DQ26_B':
      PIN_NUMBER='(278,0,0)';
      BIDIRECTIONAL='TRUE';
      INPUT_LOAD='(-0.01,0.01)';
      OUTPUT_LOAD='(1.0,-1.0)';
      PINUSE='BI';
    'DQ27_B':
      PIN_NUMBER='(280,0,0)';
      BIDIRECTIONAL='TRUE';
      INPUT_LOAD='(-0.01,0.01)';
      OUTPUT_LOAD='(1.0,-1.0)';
      PINUSE='BI';
    'DQ28_B':
      PIN_NUMBER='(140,0,0)';
      BIDIRECTIONAL='TRUE';
      INPUT_LOAD='(-0.01,0.01)';
      OUTPUT_LOAD='(1.0,-1.0)';
      PINUSE='BI';
    'DQ29_B':
      PIN_NUMBER='(142,0,0)';
      BIDIRECTIONAL='TRUE';
      INPUT_LOAD='(-0.01,0.01)';
      OUTPUT_LOAD='(1.0,-1.0)';
      PINUSE='BI';
    'DQ30_B':
      PIN_NUMBER='(285,0,0)';
      BIDIRECTIONAL='TRUE';
      INPUT_LOAD='(-0.01,0.01)';
      OUTPUT_LOAD='(1.0,-1.0)';
      PINUSE='BI';
    'DQ31_B':
      PIN_NUMBER='(287,0,0)';
      BIDIRECTIONAL='TRUE';
      INPUT_LOAD='(-0.01,0.01)';
      OUTPUT_LOAD='(1.0,-1.0)';
      PINUSE='BI';
    'DQ0_A':
      PIN_NUMBER='(7,0,0)';
      BIDIRECTIONAL='TRUE';
      INPUT_LOAD='(-0.01,0.01)';
      OUTPUT_LOAD='(1.0,-1.0)';
      PINUSE='BI';
    'DQ1_A':
      PIN_NUMBER='(9,0,0)';
      BIDIRECTIONAL='TRUE';
      INPUT_LOAD='(-0.01,0.01)';
      OUTPUT_LOAD='(1.0,-1.0)';
      PINUSE='BI';
    'DQ2_A':
      PIN_NUMBER='(152,0,0)';
      BIDIRECTIONAL='TRUE';
      INPUT_LOAD='(-0.01,0.01)';
      OUTPUT_LOAD='(1.0,-1.0)';
      PINUSE='BI';
    'DQ3_A':
      PIN_NUMBER='(154,0,0)';
      BIDIRECTIONAL='TRUE';
      INPUT_LOAD='(-0.01,0.01)';
      OUTPUT_LOAD='(1.0,-1.0)';
      PINUSE='BI';
    'DQ4_A':
      PIN_NUMBER='(14,0,0)';
      BIDIRECTIONAL='TRUE';
      INPUT_LOAD='(-0.01,0.01)';
      OUTPUT_LOAD='(1.0,-1.0)';
      PINUSE='BI';
    'DQ5_A':
      PIN_NUMBER='(16,0,0)';
      BIDIRECTIONAL='TRUE';
      INPUT_LOAD='(-0.01,0.01)';
      OUTPUT_LOAD='(1.0,-1.0)';
      PINUSE='BI';
    'DQ6_A':
      PIN_NUMBER='(159,0,0)';
      BIDIRECTIONAL='TRUE';
      INPUT_LOAD='(-0.01,0.01)';
      OUTPUT_LOAD='(1.0,-1.0)';
      PINUSE='BI';
    'DQ7_A':
      PIN_NUMBER='(161,0,0)';
      BIDIRECTIONAL='TRUE';
      INPUT_LOAD='(-0.01,0.01)';
      OUTPUT_LOAD='(1.0,-1.0)';
      PINUSE='BI';
    'DQ8_A':
      PIN_NUMBER='(18,0,0)';
      BIDIRECTIONAL='TRUE';
      INPUT_LOAD='(-0.01,0.01)';
      OUTPUT_LOAD='(1.0,-1.0)';
      PINUSE='BI';
    'DQ9_A':
      PIN_NUMBER='(20,0,0)';
      BIDIRECTIONAL='TRUE';
      INPUT_LOAD='(-0.01,0.01)';
      OUTPUT_LOAD='(1.0,-1.0)';
      PINUSE='BI';
    'DQ10_A':
      PIN_NUMBER='(163,0,0)';
      BIDIRECTIONAL='TRUE';
      INPUT_LOAD='(-0.01,0.01)';
      OUTPUT_LOAD='(1.0,-1.0)';
      PINUSE='BI';
    'DQ11_A':
      PIN_NUMBER='(165,0,0)';
      BIDIRECTIONAL='TRUE';
      INPUT_LOAD='(-0.01,0.01)';
      OUTPUT_LOAD='(1.0,-1.0)';
      PINUSE='BI';
    'DQ12_A':
      PIN_NUMBER='(25,0,0)';
      BIDIRECTIONAL='TRUE';
      INPUT_LOAD='(-0.01,0.01)';
      OUTPUT_LOAD='(1.0,-1.0)';
      PINUSE='BI';
    'DQ13_A':
      PIN_NUMBER='(27,0,0)';
      BIDIRECTIONAL='TRUE';
      INPUT_LOAD='(-0.01,0.01)';
      OUTPUT_LOAD='(1.0,-1.0)';
      PINUSE='BI';
    'DQ14_A':
      PIN_NUMBER='(170,0,0)';
      BIDIRECTIONAL='TRUE';
      INPUT_LOAD='(-0.01,0.01)';
      OUTPUT_LOAD='(1.0,-1.0)';
      PINUSE='BI';
    'DQ15_A':
      PIN_NUMBER='(172,0,0)';
      BIDIRECTIONAL='TRUE';
      INPUT_LOAD='(-0.01,0.01)';
      OUTPUT_LOAD='(1.0,-1.0)';
      PINUSE='BI';
    'DQ16_A':
      PIN_NUMBER='(29,0,0)';
      BIDIRECTIONAL='TRUE';
      INPUT_LOAD='(-0.01,0.01)';
      OUTPUT_LOAD='(1.0,-1.0)';
      PINUSE='BI';
    'DQ17_A':
      PIN_NUMBER='(31,0,0)';
      BIDIRECTIONAL='TRUE';
      INPUT_LOAD='(-0.01,0.01)';
      OUTPUT_LOAD='(1.0,-1.0)';
      PINUSE='BI';
    'DQ18_A':
      PIN_NUMBER='(174,0,0)';
      BIDIRECTIONAL='TRUE';
      INPUT_LOAD='(-0.01,0.01)';
      OUTPUT_LOAD='(1.0,-1.0)';
      PINUSE='BI';
    'DQ19_A':
      PIN_NUMBER='(176,0,0)';
      BIDIRECTIONAL='TRUE';
      INPUT_LOAD='(-0.01,0.01)';
      OUTPUT_LOAD='(1.0,-1.0)';
      PINUSE='BI';
    'DQ20_A':
      PIN_NUMBER='(36,0,0)';
      BIDIRECTIONAL='TRUE';
      INPUT_LOAD='(-0.01,0.01)';
      OUTPUT_LOAD='(1.0,-1.0)';
      PINUSE='BI';
    'DQ21_A':
      PIN_NUMBER='(38,0,0)';
      BIDIRECTIONAL='TRUE';
      INPUT_LOAD='(-0.01,0.01)';
      OUTPUT_LOAD='(1.0,-1.0)';
      PINUSE='BI';
    'DQ22_A':
      PIN_NUMBER='(181,0,0)';
      BIDIRECTIONAL='TRUE';
      INPUT_LOAD='(-0.01,0.01)';
      OUTPUT_LOAD='(1.0,-1.0)';
      PINUSE='BI';
    'DQ23_A':
      PIN_NUMBER='(183,0,0)';
      BIDIRECTIONAL='TRUE';
      INPUT_LOAD='(-0.01,0.01)';
      OUTPUT_LOAD='(1.0,-1.0)';
      PINUSE='BI';
    'DQ24_A':
      PIN_NUMBER='(40,0,0)';
      BIDIRECTIONAL='TRUE';
      INPUT_LOAD='(-0.01,0.01)';
      OUTPUT_LOAD='(1.0,-1.0)';
      PINUSE='BI';
    'DQ25_A':
      PIN_NUMBER='(42,0,0)';
      BIDIRECTIONAL='TRUE';
      INPUT_LOAD='(-0.01,0.01)';
      OUTPUT_LOAD='(1.0,-1.0)';
      PINUSE='BI';
    'DQ26_A':
      PIN_NUMBER='(185,0,0)';
      BIDIRECTIONAL='TRUE';
      INPUT_LOAD='(-0.01,0.01)';
      OUTPUT_LOAD='(1.0,-1.0)';
      PINUSE='BI';
    'DQ27_A':
      PIN_NUMBER='(187,0,0)';
      BIDIRECTIONAL='TRUE';
      INPUT_LOAD='(-0.01,0.01)';
      OUTPUT_LOAD='(1.0,-1.0)';
      PINUSE='BI';
    'DQ28_A':
      PIN_NUMBER='(47,0,0)';
      BIDIRECTIONAL='TRUE';
      INPUT_LOAD='(-0.01,0.01)';
      OUTPUT_LOAD='(1.0,-1.0)';
      PINUSE='BI';
    'DQ29_A':
      PIN_NUMBER='(49,0,0)';
      BIDIRECTIONAL='TRUE';
      INPUT_LOAD='(-0.01,0.01)';
      OUTPUT_LOAD='(1.0,-1.0)';
      PINUSE='BI';
    'DQ30_A':
      PIN_NUMBER='(192,0,0)';
      BIDIRECTIONAL='TRUE';
      INPUT_LOAD='(-0.01,0.01)';
      OUTPUT_LOAD='(1.0,-1.0)';
      PINUSE='BI';
    'CS1_B_N':
      PIN_NUMBER='(229,0,0)';
      INPUT_LOAD='(-0.01,0.01)';
      PINUSE='IN';
    'CS1_A_N':
      PIN_NUMBER='(209,0,0)';
      INPUT_LOAD='(-0.01,0.01)';
      PINUSE='IN';
    'CS0_B_N':
      PIN_NUMBER='(84,0,0)';
      INPUT_LOAD='(-0.01,0.01)';
      PINUSE='IN';
    'CS0_A_N':
      PIN_NUMBER='(64,0,0)';
      INPUT_LOAD='(-0.01,0.01)';
      PINUSE='IN';
    'CK_T':
      PIN_NUMBER='(217,0,0)';
      INPUT_LOAD='(-0.01,0.01)';
      PINUSE='IN';
    'CK_C':
      PIN_NUMBER='(218,0,0)';
      INPUT_LOAD='(-0.01,0.01)';
      PINUSE='IN';
    'CB0_B':
      PIN_NUMBER='(96,0,0)';
      BIDIRECTIONAL='TRUE';
      INPUT_LOAD='(-0.01,0.01)';
      OUTPUT_LOAD='(1.0,-1.0)';
      PINUSE='BI';
    'CB1_B':
      PIN_NUMBER='(98,0,0)';
      BIDIRECTIONAL='TRUE';
      INPUT_LOAD='(-0.01,0.01)';
      OUTPUT_LOAD='(1.0,-1.0)';
      PINUSE='BI';
    'CB2_B':
      PIN_NUMBER='(241,0,0)';
      BIDIRECTIONAL='TRUE';
      INPUT_LOAD='(-0.01,0.01)';
      OUTPUT_LOAD='(1.0,-1.0)';
      PINUSE='BI';
    'CB3_B':
      PIN_NUMBER='(243,0,0)';
      BIDIRECTIONAL='TRUE';
      INPUT_LOAD='(-0.01,0.01)';
      OUTPUT_LOAD='(1.0,-1.0)';
      PINUSE='BI';
    'CB4_B':
      PIN_NUMBER='(89,0,0)';
      BIDIRECTIONAL='TRUE';
      INPUT_LOAD='(-0.01,0.01)';
      OUTPUT_LOAD='(1.0,-1.0)';
      PINUSE='BI';
    'CB5_B':
      PIN_NUMBER='(91,0,0)';
      BIDIRECTIONAL='TRUE';
      INPUT_LOAD='(-0.01,0.01)';
      OUTPUT_LOAD='(1.0,-1.0)';
      PINUSE='BI';
    'CB6_B':
      PIN_NUMBER='(234,0,0)';
      BIDIRECTIONAL='TRUE';
      INPUT_LOAD='(-0.01,0.01)';
      OUTPUT_LOAD='(1.0,-1.0)';
      PINUSE='BI';
    'CB0_A':
      PIN_NUMBER='(51,0,0)';
      BIDIRECTIONAL='TRUE';
      INPUT_LOAD='(-0.01,0.01)';
      OUTPUT_LOAD='(1.0,-1.0)';
      PINUSE='BI';
    'CB2_A':
      PIN_NUMBER='(196,0,0)';
      BIDIRECTIONAL='TRUE';
      INPUT_LOAD='(-0.01,0.01)';
      OUTPUT_LOAD='(1.0,-1.0)';
      PINUSE='BI';
    'CB3_A':
      PIN_NUMBER='(198,0,0)';
      BIDIRECTIONAL='TRUE';
      INPUT_LOAD='(-0.01,0.01)';
      OUTPUT_LOAD='(1.0,-1.0)';
      PINUSE='BI';
    'CB5_A':
      PIN_NUMBER='(60,0,0)';
      BIDIRECTIONAL='TRUE';
      INPUT_LOAD='(-0.01,0.01)';
      OUTPUT_LOAD='(1.0,-1.0)';
      PINUSE='BI';
    'CB6_A':
      PIN_NUMBER='(203,0,0)';
      BIDIRECTIONAL='TRUE';
      INPUT_LOAD='(-0.01,0.01)';
      OUTPUT_LOAD='(1.0,-1.0)';
      PINUSE='BI';
    'CA6_B':
      PIN_NUMBER='(82,0,0)';
      INPUT_LOAD='(-0.01,0.01)';
      PINUSE='IN';
    'CA6_A':
      PIN_NUMBER='(72,0,0)';
      INPUT_LOAD='(-0.01,0.01)';
      PINUSE='IN';
    'CA5_B':
      PIN_NUMBER='(225,0,0)';
      INPUT_LOAD='(-0.01,0.01)';
      PINUSE='IN';
    'CA5_A':
      PIN_NUMBER='(215,0,0)';
      INPUT_LOAD='(-0.01,0.01)';
      PINUSE='IN';
    'CA4_B':
      PIN_NUMBER='(80,0,0)';
      INPUT_LOAD='(-0.01,0.01)';
      PINUSE='IN';
    'CA4_A':
      PIN_NUMBER='(70,0,0)';
      INPUT_LOAD='(-0.01,0.01)';
      PINUSE='IN';
    'CA3_B':
      PIN_NUMBER='(223,0,0)';
      INPUT_LOAD='(-0.01,0.01)';
      PINUSE='IN';
    'CA3_A':
      PIN_NUMBER='(213,0,0)';
      INPUT_LOAD='(-0.01,0.01)';
      PINUSE='IN';
    'CA2_B':
      PIN_NUMBER='(78,0,0)';
      INPUT_LOAD='(-0.01,0.01)';
      PINUSE='IN';
    'CA2_A':
      PIN_NUMBER='(68,0,0)';
      INPUT_LOAD='(-0.01,0.01)';
      PINUSE='IN';
    'CA1_B':
      PIN_NUMBER='(221,0,0)';
      INPUT_LOAD='(-0.01,0.01)';
      PINUSE='IN';
    'CA1_A':
      PIN_NUMBER='(211,0,0)';
      INPUT_LOAD='(-0.01,0.01)';
      PINUSE='IN';
    'CA0_B':
      PIN_NUMBER='(76,0,0)';
      INPUT_LOAD='(-0.01,0.01)';
      PINUSE='IN';
    'CA0_A':
      PIN_NUMBER='(66,0,0)';
      INPUT_LOAD='(-0.01,0.01)';
      PINUSE='IN';
    'ALERT_N':
      PIN_NUMBER='(62,0,0)';
      OUTPUT_LOAD='(1.0,-1.0)';
      PINUSE='OUT';
    'CB7_B':
      PIN_NUMBER='(236,0,0)';
      BIDIRECTIONAL='TRUE';
      INPUT_LOAD='(-0.01,0.01)';
      OUTPUT_LOAD='(1.0,-1.0)';
      PINUSE='BI';
    'CB1_A':
      PIN_NUMBER='(53,0,0)';
      BIDIRECTIONAL='TRUE';
      INPUT_LOAD='(-0.01,0.01)';
      OUTPUT_LOAD='(1.0,-1.0)';
      PINUSE='BI';
    'CB4_A':
      PIN_NUMBER='(58,0,0)';
      BIDIRECTIONAL='TRUE';
      INPUT_LOAD='(-0.01,0.01)';
      OUTPUT_LOAD='(1.0,-1.0)';
      PINUSE='BI';
    'CB7_A':
      PIN_NUMBER='(205,0,0)';
      BIDIRECTIONAL='TRUE';
      INPUT_LOAD='(-0.01,0.01)';
      OUTPUT_LOAD='(1.0,-1.0)';
      PINUSE='BI';
    'DQ31_A':
      PIN_NUMBER='(194,0,0)';
      BIDIRECTIONAL='TRUE';
      INPUT_LOAD='(-0.01,0.01)';
      OUTPUT_LOAD='(1.0,-1.0)';
      PINUSE='BI';
    'DQS9_B_T||TDQS9_B_T||DBI4_B_N':
      PIN_NUMBER='(0,93,0)';
      BIDIRECTIONAL='TRUE';
      INPUT_LOAD='(-0.01,0.01)';
      OUTPUT_LOAD='(1.0,-1.0)';
      PINUSE='BI';
    'DQS9_B_C||TDQS9_B_C':
      PIN_NUMBER='(0,94,0)';
      BIDIRECTIONAL='TRUE';
      INPUT_LOAD='(-0.01,0.01)';
      OUTPUT_LOAD='(1.0,-1.0)';
      PINUSE='BI';
    'DQS9_A_T||TDQS9_A_T':
      PIN_NUMBER='(0,201,0)';
      BIDIRECTIONAL='TRUE';
      INPUT_LOAD='(-0.01,0.01)';
      OUTPUT_LOAD='(1.0,-1.0)';
      PINUSE='BI';
    'DQS9_A_C||TDQS9_A_C':
      PIN_NUMBER='(0,200,0)';
      BIDIRECTIONAL='TRUE';
      INPUT_LOAD='(-0.01,0.01)';
      OUTPUT_LOAD='(1.0,-1.0)';
      PINUSE='BI';
    'DQS8_A_T||TDQS8_A_T':
      PIN_NUMBER='(0,190,0)';
      BIDIRECTIONAL='TRUE';
      INPUT_LOAD='(-0.01,0.01)';
      OUTPUT_LOAD='(1.0,-1.0)';
      PINUSE='BI';
    'DQS8_A_C||TDQS8_A_C':
      PIN_NUMBER='(0,189,0)';
      BIDIRECTIONAL='TRUE';
      INPUT_LOAD='(-0.01,0.01)';
      OUTPUT_LOAD='(1.0,-1.0)';
      PINUSE='BI';
    'DQS7_B_C||TDQS7_B_C':
      PIN_NUMBER='(0,271,0)';
      BIDIRECTIONAL='TRUE';
      INPUT_LOAD='(-0.01,0.01)';
      OUTPUT_LOAD='(1.0,-1.0)';
      PINUSE='BI';
    'DQS7_A_T||TDQS7_A_T':
      PIN_NUMBER='(0,179,0)';
      BIDIRECTIONAL='TRUE';
      INPUT_LOAD='(-0.01,0.01)';
      OUTPUT_LOAD='(1.0,-1.0)';
      PINUSE='BI';
    'DQS6_B_T||TDQS6_B_T':
      PIN_NUMBER='(0,261,0)';
      BIDIRECTIONAL='TRUE';
      INPUT_LOAD='(-0.01,0.01)';
      OUTPUT_LOAD='(1.0,-1.0)';
      PINUSE='BI';
    'DQS6_B_C||TDQS6_B_C':
      PIN_NUMBER='(0,260,0)';
      BIDIRECTIONAL='TRUE';
      INPUT_LOAD='(-0.01,0.01)';
      OUTPUT_LOAD='(1.0,-1.0)';
      PINUSE='BI';
    'DQS6_A_C||TDQS6_A_C||DQS6_A_T||TDQS6_A_T':
      PIN_NUMBER='(0,167,0)';
      BIDIRECTIONAL='TRUE';
      INPUT_LOAD='(-0.01,0.01)';
      OUTPUT_LOAD='(1.0,-1.0)';
      PINUSE='BI';
    'DQS5_B_T||TDQS5_B_T':
      PIN_NUMBER='(0,250,0)';
      BIDIRECTIONAL='TRUE';
      INPUT_LOAD='(-0.01,0.01)';
      OUTPUT_LOAD='(1.0,-1.0)';
      PINUSE='BI';
    'DQS5_B_C||TDQS5_B_C':
      PIN_NUMBER='(0,249,0)';
      BIDIRECTIONAL='TRUE';
      INPUT_LOAD='(-0.01,0.01)';
      OUTPUT_LOAD='(1.0,-1.0)';
      PINUSE='BI';
    'DQS5_A_T||TDQS5_A_T':
      PIN_NUMBER='(0,157,0)';
      BIDIRECTIONAL='TRUE';
      INPUT_LOAD='(-0.01,0.01)';
      OUTPUT_LOAD='(1.0,-1.0)';
      PINUSE='BI';
    'DQS5_A_C||TDQS5_A_C||DQS5_A_T||TDQS5_A_T':
      PIN_NUMBER='(0,156,0)';
      BIDIRECTIONAL='TRUE';
      INPUT_LOAD='(-0.01,0.01)';
      OUTPUT_LOAD='(1.0,-1.0)';
      PINUSE='BI';
    'DQS4_B_T':
      PIN_NUMBER='(0,239,0)';
      BIDIRECTIONAL='TRUE';
      INPUT_LOAD='(-0.01,0.01)';
      OUTPUT_LOAD='(1.0,-1.0)';
      PINUSE='BI';
    'DQS4_B_C':
      PIN_NUMBER='(0,238,0)';
      BIDIRECTIONAL='TRUE';
      INPUT_LOAD='(-0.01,0.01)';
      OUTPUT_LOAD='(1.0,-1.0)';
      PINUSE='BI';
    'DQS4_A_T':
      PIN_NUMBER='(0,55,0)';
      BIDIRECTIONAL='TRUE';
      INPUT_LOAD='(-0.01,0.01)';
      OUTPUT_LOAD='(1.0,-1.0)';
      PINUSE='BI';
    'DQS4_A_C':
      PIN_NUMBER='(0,56,0)';
      BIDIRECTIONAL='TRUE';
      INPUT_LOAD='(-0.01,0.01)';
      OUTPUT_LOAD='(1.0,-1.0)';
      PINUSE='BI';
    'DQS3_B_T':
      PIN_NUMBER='(0,137,0)';
      BIDIRECTIONAL='TRUE';
      INPUT_LOAD='(-0.01,0.01)';
      OUTPUT_LOAD='(1.0,-1.0)';
      PINUSE='BI';
    'DQS3_B_C':
      PIN_NUMBER='(0,138,0)';
      BIDIRECTIONAL='TRUE';
      INPUT_LOAD='(-0.01,0.01)';
      OUTPUT_LOAD='(1.0,-1.0)';
      PINUSE='BI';
    'DQS3_A_T':
      PIN_NUMBER='(0,44,0)';
      BIDIRECTIONAL='TRUE';
      INPUT_LOAD='(-0.01,0.01)';
      OUTPUT_LOAD='(1.0,-1.0)';
      PINUSE='BI';
    'DQS3_A_C':
      PIN_NUMBER='(0,45,0)';
      BIDIRECTIONAL='TRUE';
      INPUT_LOAD='(-0.01,0.01)';
      OUTPUT_LOAD='(1.0,-1.0)';
      PINUSE='BI';
    'DQS2_B_T':
      PIN_NUMBER='(0,126,0)';
      BIDIRECTIONAL='TRUE';
      INPUT_LOAD='(-0.01,0.01)';
      OUTPUT_LOAD='(1.0,-1.0)';
      PINUSE='BI';
    'DQS2_B_C':
      PIN_NUMBER='(0,127,0)';
      BIDIRECTIONAL='TRUE';
      INPUT_LOAD='(-0.01,0.01)';
      OUTPUT_LOAD='(1.0,-1.0)';
      PINUSE='BI';
    'DQS2_A_T':
      PIN_NUMBER='(0,33,0)';
      BIDIRECTIONAL='TRUE';
      INPUT_LOAD='(-0.01,0.01)';
      OUTPUT_LOAD='(1.0,-1.0)';
      PINUSE='BI';
    'DQS2_A_C':
      PIN_NUMBER='(0,34,0)';
      BIDIRECTIONAL='TRUE';
      INPUT_LOAD='(-0.01,0.01)';
      OUTPUT_LOAD='(1.0,-1.0)';
      PINUSE='BI';
    'DQS1_B_T':
      PIN_NUMBER='(0,115,0)';
      BIDIRECTIONAL='TRUE';
      INPUT_LOAD='(-0.01,0.01)';
      OUTPUT_LOAD='(1.0,-1.0)';
      PINUSE='BI';
    'DQS1_B_C':
      PIN_NUMBER='(0,116,0)';
      BIDIRECTIONAL='TRUE';
      INPUT_LOAD='(-0.01,0.01)';
      OUTPUT_LOAD='(1.0,-1.0)';
      PINUSE='BI';
    'DQS1_A_T':
      PIN_NUMBER='(0,22,0)';
      BIDIRECTIONAL='TRUE';
      INPUT_LOAD='(-0.01,0.01)';
      OUTPUT_LOAD='(1.0,-1.0)';
      PINUSE='BI';
    'DQS1_A_C':
      PIN_NUMBER='(0,23,0)';
      BIDIRECTIONAL='TRUE';
      INPUT_LOAD='(-0.01,0.01)';
      OUTPUT_LOAD='(1.0,-1.0)';
      PINUSE='BI';
    'DQS0_B_T':
      PIN_NUMBER='(0,104,0)';
      BIDIRECTIONAL='TRUE';
      INPUT_LOAD='(-0.01,0.01)';
      OUTPUT_LOAD='(1.0,-1.0)';
      PINUSE='BI';
    'DQS0_B_C':
      PIN_NUMBER='(0,105,0)';
      BIDIRECTIONAL='TRUE';
      INPUT_LOAD='(-0.01,0.01)';
      OUTPUT_LOAD='(1.0,-1.0)';
      PINUSE='BI';
    'DQS0_A_T':
      PIN_NUMBER='(0,11,0)';
      BIDIRECTIONAL='TRUE';
      INPUT_LOAD='(-0.01,0.01)';
      OUTPUT_LOAD='(1.0,-1.0)';
      PINUSE='BI';
    'DQS0_A_C':
      PIN_NUMBER='(0,12,0)';
      BIDIRECTIONAL='TRUE';
      INPUT_LOAD='(-0.01,0.01)';
      OUTPUT_LOAD='(1.0,-1.0)';
      PINUSE='BI';
    'DQS7_B_T||TDQS7_B_T':
      PIN_NUMBER='(0,272,0)';
      BIDIRECTIONAL='TRUE';
      INPUT_LOAD='(-0.01,0.01)';
      OUTPUT_LOAD='(1.0,-1.0)';
      PINUSE='BI';
    'DQS8_B_C||TDQS8_B_C':
      PIN_NUMBER='(0,282,0)';
      BIDIRECTIONAL='TRUE';
      INPUT_LOAD='(-0.01,0.01)';
      OUTPUT_LOAD='(1.0,-1.0)';
      PINUSE='BI';
    'DQS8_B_T||TDQS8_B_T':
      PIN_NUMBER='(0,283,0)';
      BIDIRECTIONAL='TRUE';
      INPUT_LOAD='(-0.01,0.01)';
      OUTPUT_LOAD='(1.0,-1.0)';
      PINUSE='BI';
    'DQS6_A_T||TDQS6_A_T':
      PIN_NUMBER='(0,168,0)';
      BIDIRECTIONAL='TRUE';
      INPUT_LOAD='(-0.01,0.01)';
      OUTPUT_LOAD='(1.0,-1.0)';
      PINUSE='BI';
    'DQS7_A_C||TDQS7_A_C':
      PIN_NUMBER='(0,178,0)';
      BIDIRECTIONAL='TRUE';
      INPUT_LOAD='(-0.01,0.01)';
      OUTPUT_LOAD='(1.0,-1.0)';
      PINUSE='BI';
    'VSS0':
      PIN_NUMBER='(0,0,6)';
      PINUSE='POWER';
      NO_LOAD_CHECK='Both';
      NO_IO_CHECK='Both';
      NO_ASSERT_CHECK='TRUE';
      NO_DIR_CHECK='TRUE';
      ALLOW_CONNECT='TRUE';
    'VSS1':
      PIN_NUMBER='(0,0,8)';
      PINUSE='POWER';
      NO_LOAD_CHECK='Both';
      NO_IO_CHECK='Both';
      NO_ASSERT_CHECK='TRUE';
      NO_DIR_CHECK='TRUE';
      ALLOW_CONNECT='TRUE';
    'VSS2':
      PIN_NUMBER='(0,0,10)';
      PINUSE='POWER';
      NO_LOAD_CHECK='Both';
      NO_IO_CHECK='Both';
      NO_ASSERT_CHECK='TRUE';
      NO_DIR_CHECK='TRUE';
      ALLOW_CONNECT='TRUE';
    'VSS3':
      PIN_NUMBER='(0,0,13)';
      PINUSE='POWER';
      NO_LOAD_CHECK='Both';
      NO_IO_CHECK='Both';
      NO_ASSERT_CHECK='TRUE';
      NO_DIR_CHECK='TRUE';
      ALLOW_CONNECT='TRUE';
    'VSS4':
      PIN_NUMBER='(0,0,15)';
      PINUSE='POWER';
      NO_LOAD_CHECK='Both';
      NO_IO_CHECK='Both';
      NO_ASSERT_CHECK='TRUE';
      NO_DIR_CHECK='TRUE';
      ALLOW_CONNECT='TRUE';
    'VSS5':
      PIN_NUMBER='(0,0,17)';
      PINUSE='POWER';
      NO_LOAD_CHECK='Both';
      NO_IO_CHECK='Both';
      NO_ASSERT_CHECK='TRUE';
      NO_DIR_CHECK='TRUE';
      ALLOW_CONNECT='TRUE';
    'VSS6':
      PIN_NUMBER='(0,0,19)';
      PINUSE='POWER';
      NO_LOAD_CHECK='Both';
      NO_IO_CHECK='Both';
      NO_ASSERT_CHECK='TRUE';
      NO_DIR_CHECK='TRUE';
      ALLOW_CONNECT='TRUE';
    'VSS7':
      PIN_NUMBER='(0,0,21)';
      PINUSE='POWER';
      NO_LOAD_CHECK='Both';
      NO_IO_CHECK='Both';
      NO_ASSERT_CHECK='TRUE';
      NO_DIR_CHECK='TRUE';
      ALLOW_CONNECT='TRUE';
    'VSS8':
      PIN_NUMBER='(0,0,24)';
      PINUSE='POWER';
      NO_LOAD_CHECK='Both';
      NO_IO_CHECK='Both';
      NO_ASSERT_CHECK='TRUE';
      NO_DIR_CHECK='TRUE';
      ALLOW_CONNECT='TRUE';
    'VSS9':
      PIN_NUMBER='(0,0,26)';
      PINUSE='POWER';
      NO_LOAD_CHECK='Both';
      NO_IO_CHECK='Both';
      NO_ASSERT_CHECK='TRUE';
      NO_DIR_CHECK='TRUE';
      ALLOW_CONNECT='TRUE';
    'VSS10':
      PIN_NUMBER='(0,0,28)';
      PINUSE='POWER';
      NO_LOAD_CHECK='Both';
      NO_IO_CHECK='Both';
      NO_ASSERT_CHECK='TRUE';
      NO_DIR_CHECK='TRUE';
      ALLOW_CONNECT='TRUE';
    'VSS11':
      PIN_NUMBER='(0,0,30)';
      PINUSE='POWER';
      NO_LOAD_CHECK='Both';
      NO_IO_CHECK='Both';
      NO_ASSERT_CHECK='TRUE';
      NO_DIR_CHECK='TRUE';
      ALLOW_CONNECT='TRUE';
    'VSS12':
      PIN_NUMBER='(0,0,32)';
      PINUSE='POWER';
      NO_LOAD_CHECK='Both';
      NO_IO_CHECK='Both';
      NO_ASSERT_CHECK='TRUE';
      NO_DIR_CHECK='TRUE';
      ALLOW_CONNECT='TRUE';
    'VSS13':
      PIN_NUMBER='(0,0,35)';
      PINUSE='POWER';
      NO_LOAD_CHECK='Both';
      NO_IO_CHECK='Both';
      NO_ASSERT_CHECK='TRUE';
      NO_DIR_CHECK='TRUE';
      ALLOW_CONNECT='TRUE';
    'VSS14':
      PIN_NUMBER='(0,0,37)';
      PINUSE='POWER';
      NO_LOAD_CHECK='Both';
      NO_IO_CHECK='Both';
      NO_ASSERT_CHECK='TRUE';
      NO_DIR_CHECK='TRUE';
      ALLOW_CONNECT='TRUE';
    'VSS15':
      PIN_NUMBER='(0,0,39)';
      PINUSE='POWER';
      NO_LOAD_CHECK='Both';
      NO_IO_CHECK='Both';
      NO_ASSERT_CHECK='TRUE';
      NO_DIR_CHECK='TRUE';
      ALLOW_CONNECT='TRUE';
    'VSS16':
      PIN_NUMBER='(0,0,41)';
      PINUSE='POWER';
      NO_LOAD_CHECK='Both';
      NO_IO_CHECK='Both';
      NO_ASSERT_CHECK='TRUE';
      NO_DIR_CHECK='TRUE';
      ALLOW_CONNECT='TRUE';
    'VSS17':
      PIN_NUMBER='(0,0,43)';
      PINUSE='POWER';
      NO_LOAD_CHECK='Both';
      NO_IO_CHECK='Both';
      NO_ASSERT_CHECK='TRUE';
      NO_DIR_CHECK='TRUE';
      ALLOW_CONNECT='TRUE';
    'VSS18':
      PIN_NUMBER='(0,0,46)';
      PINUSE='POWER';
      NO_LOAD_CHECK='Both';
      NO_IO_CHECK='Both';
      NO_ASSERT_CHECK='TRUE';
      NO_DIR_CHECK='TRUE';
      ALLOW_CONNECT='TRUE';
    'VSS19':
      PIN_NUMBER='(0,0,48)';
      PINUSE='POWER';
      NO_LOAD_CHECK='Both';
      NO_IO_CHECK='Both';
      NO_ASSERT_CHECK='TRUE';
      NO_DIR_CHECK='TRUE';
      ALLOW_CONNECT='TRUE';
    'VSS20':
      PIN_NUMBER='(0,0,50)';
      PINUSE='POWER';
      NO_LOAD_CHECK='Both';
      NO_IO_CHECK='Both';
      NO_ASSERT_CHECK='TRUE';
      NO_DIR_CHECK='TRUE';
      ALLOW_CONNECT='TRUE';
    'VSS21':
      PIN_NUMBER='(0,0,52)';
      PINUSE='POWER';
      NO_LOAD_CHECK='Both';
      NO_IO_CHECK='Both';
      NO_ASSERT_CHECK='TRUE';
      NO_DIR_CHECK='TRUE';
      ALLOW_CONNECT='TRUE';
    'VSS22':
      PIN_NUMBER='(0,0,54)';
      PINUSE='POWER';
      NO_LOAD_CHECK='Both';
      NO_IO_CHECK='Both';
      NO_ASSERT_CHECK='TRUE';
      NO_DIR_CHECK='TRUE';
      ALLOW_CONNECT='TRUE';
    'VSS23':
      PIN_NUMBER='(0,0,57)';
      PINUSE='POWER';
      NO_LOAD_CHECK='Both';
      NO_IO_CHECK='Both';
      NO_ASSERT_CHECK='TRUE';
      NO_DIR_CHECK='TRUE';
      ALLOW_CONNECT='TRUE';
    'VSS24':
      PIN_NUMBER='(0,0,59)';
      PINUSE='POWER';
      NO_LOAD_CHECK='Both';
      NO_IO_CHECK='Both';
      NO_ASSERT_CHECK='TRUE';
      NO_DIR_CHECK='TRUE';
      ALLOW_CONNECT='TRUE';
    'VSS25':
      PIN_NUMBER='(0,0,61)';
      PINUSE='POWER';
      NO_LOAD_CHECK='Both';
      NO_IO_CHECK='Both';
      NO_ASSERT_CHECK='TRUE';
      NO_DIR_CHECK='TRUE';
      ALLOW_CONNECT='TRUE';
    'VSS26':
      PIN_NUMBER='(0,0,63)';
      PINUSE='POWER';
      NO_LOAD_CHECK='Both';
      NO_IO_CHECK='Both';
      NO_ASSERT_CHECK='TRUE';
      NO_DIR_CHECK='TRUE';
      ALLOW_CONNECT='TRUE';
    'VSS27':
      PIN_NUMBER='(0,0,65)';
      PINUSE='POWER';
      NO_LOAD_CHECK='Both';
      NO_IO_CHECK='Both';
      NO_ASSERT_CHECK='TRUE';
      NO_DIR_CHECK='TRUE';
      ALLOW_CONNECT='TRUE';
    'VSS28':
      PIN_NUMBER='(0,0,67)';
      PINUSE='POWER';
      NO_LOAD_CHECK='Both';
      NO_IO_CHECK='Both';
      NO_ASSERT_CHECK='TRUE';
      NO_DIR_CHECK='TRUE';
      ALLOW_CONNECT='TRUE';
    'VSS29':
      PIN_NUMBER='(0,0,69)';
      PINUSE='POWER';
      NO_LOAD_CHECK='Both';
      NO_IO_CHECK='Both';
      NO_ASSERT_CHECK='TRUE';
      NO_DIR_CHECK='TRUE';
      ALLOW_CONNECT='TRUE';
    'VSS30':
      PIN_NUMBER='(0,0,71)';
      PINUSE='POWER';
      NO_LOAD_CHECK='Both';
      NO_IO_CHECK='Both';
      NO_ASSERT_CHECK='TRUE';
      NO_DIR_CHECK='TRUE';
      ALLOW_CONNECT='TRUE';
    'VSS31':
      PIN_NUMBER='(0,0,73)';
      PINUSE='POWER';
      NO_LOAD_CHECK='Both';
      NO_IO_CHECK='Both';
      NO_ASSERT_CHECK='TRUE';
      NO_DIR_CHECK='TRUE';
      ALLOW_CONNECT='TRUE';
    'VSS32':
      PIN_NUMBER='(0,0,75)';
      PINUSE='POWER';
      NO_LOAD_CHECK='Both';
      NO_IO_CHECK='Both';
      NO_ASSERT_CHECK='TRUE';
      NO_DIR_CHECK='TRUE';
      ALLOW_CONNECT='TRUE';
    'VSS33':
      PIN_NUMBER='(0,0,77)';
      PINUSE='POWER';
      NO_LOAD_CHECK='Both';
      NO_IO_CHECK='Both';
      NO_ASSERT_CHECK='TRUE';
      NO_DIR_CHECK='TRUE';
      ALLOW_CONNECT='TRUE';
    'VSS34':
      PIN_NUMBER='(0,0,79)';
      PINUSE='POWER';
      NO_LOAD_CHECK='Both';
      NO_IO_CHECK='Both';
      NO_ASSERT_CHECK='TRUE';
      NO_DIR_CHECK='TRUE';
      ALLOW_CONNECT='TRUE';
    'VSS35':
      PIN_NUMBER='(0,0,81)';
      PINUSE='POWER';
      NO_LOAD_CHECK='Both';
      NO_IO_CHECK='Both';
      NO_ASSERT_CHECK='TRUE';
      NO_DIR_CHECK='TRUE';
      ALLOW_CONNECT='TRUE';
    'VSS36':
      PIN_NUMBER='(0,0,83)';
      PINUSE='POWER';
      NO_LOAD_CHECK='Both';
      NO_IO_CHECK='Both';
      NO_ASSERT_CHECK='TRUE';
      NO_DIR_CHECK='TRUE';
      ALLOW_CONNECT='TRUE';
    'VSS37':
      PIN_NUMBER='(0,0,85)';
      PINUSE='POWER';
      NO_LOAD_CHECK='Both';
      NO_IO_CHECK='Both';
      NO_ASSERT_CHECK='TRUE';
      NO_DIR_CHECK='TRUE';
      ALLOW_CONNECT='TRUE';
    'VSS38':
      PIN_NUMBER='(0,0,88)';
      PINUSE='POWER';
      NO_LOAD_CHECK='Both';
      NO_IO_CHECK='Both';
      NO_ASSERT_CHECK='TRUE';
      NO_DIR_CHECK='TRUE';
      ALLOW_CONNECT='TRUE';
    'VSS39':
      PIN_NUMBER='(0,0,90)';
      PINUSE='POWER';
      NO_LOAD_CHECK='Both';
      NO_IO_CHECK='Both';
      NO_ASSERT_CHECK='TRUE';
      NO_DIR_CHECK='TRUE';
      ALLOW_CONNECT='TRUE';
    'VSS40':
      PIN_NUMBER='(0,0,92)';
      PINUSE='POWER';
      NO_LOAD_CHECK='Both';
      NO_IO_CHECK='Both';
      NO_ASSERT_CHECK='TRUE';
      NO_DIR_CHECK='TRUE';
      ALLOW_CONNECT='TRUE';
    'VSS41':
      PIN_NUMBER='(0,0,95)';
      PINUSE='POWER';
      NO_LOAD_CHECK='Both';
      NO_IO_CHECK='Both';
      NO_ASSERT_CHECK='TRUE';
      NO_DIR_CHECK='TRUE';
      ALLOW_CONNECT='TRUE';
    'VSS42':
      PIN_NUMBER='(0,0,97)';
      PINUSE='POWER';
      NO_LOAD_CHECK='Both';
      NO_IO_CHECK='Both';
      NO_ASSERT_CHECK='TRUE';
      NO_DIR_CHECK='TRUE';
      ALLOW_CONNECT='TRUE';
    'VSS43':
      PIN_NUMBER='(0,0,99)';
      PINUSE='POWER';
      NO_LOAD_CHECK='Both';
      NO_IO_CHECK='Both';
      NO_ASSERT_CHECK='TRUE';
      NO_DIR_CHECK='TRUE';
      ALLOW_CONNECT='TRUE';
    'VSS44':
      PIN_NUMBER='(0,0,101)';
      PINUSE='POWER';
      NO_LOAD_CHECK='Both';
      NO_IO_CHECK='Both';
      NO_ASSERT_CHECK='TRUE';
      NO_DIR_CHECK='TRUE';
      ALLOW_CONNECT='TRUE';
    'VSS45':
      PIN_NUMBER='(0,0,103)';
      PINUSE='POWER';
      NO_LOAD_CHECK='Both';
      NO_IO_CHECK='Both';
      NO_ASSERT_CHECK='TRUE';
      NO_DIR_CHECK='TRUE';
      ALLOW_CONNECT='TRUE';
    'VSS46':
      PIN_NUMBER='(0,0,106)';
      PINUSE='POWER';
      NO_LOAD_CHECK='Both';
      NO_IO_CHECK='Both';
      NO_ASSERT_CHECK='TRUE';
      NO_DIR_CHECK='TRUE';
      ALLOW_CONNECT='TRUE';
    'VSS47':
      PIN_NUMBER='(0,0,108)';
      PINUSE='POWER';
      NO_LOAD_CHECK='Both';
      NO_IO_CHECK='Both';
      NO_ASSERT_CHECK='TRUE';
      NO_DIR_CHECK='TRUE';
      ALLOW_CONNECT='TRUE';
    'VSS48':
      PIN_NUMBER='(0,0,110)';
      PINUSE='POWER';
      NO_LOAD_CHECK='Both';
      NO_IO_CHECK='Both';
      NO_ASSERT_CHECK='TRUE';
      NO_DIR_CHECK='TRUE';
      ALLOW_CONNECT='TRUE';
    'VSS49':
      PIN_NUMBER='(0,0,112)';
      PINUSE='POWER';
      NO_LOAD_CHECK='Both';
      NO_IO_CHECK='Both';
      NO_ASSERT_CHECK='TRUE';
      NO_DIR_CHECK='TRUE';
      ALLOW_CONNECT='TRUE';
    'VSS50':
      PIN_NUMBER='(0,0,114)';
      PINUSE='POWER';
      NO_LOAD_CHECK='Both';
      NO_IO_CHECK='Both';
      NO_ASSERT_CHECK='TRUE';
      NO_DIR_CHECK='TRUE';
      ALLOW_CONNECT='TRUE';
    'VSS51':
      PIN_NUMBER='(0,0,117)';
      PINUSE='POWER';
      NO_LOAD_CHECK='Both';
      NO_IO_CHECK='Both';
      NO_ASSERT_CHECK='TRUE';
      NO_DIR_CHECK='TRUE';
      ALLOW_CONNECT='TRUE';
    'VSS52':
      PIN_NUMBER='(0,0,119)';
      PINUSE='POWER';
      NO_LOAD_CHECK='Both';
      NO_IO_CHECK='Both';
      NO_ASSERT_CHECK='TRUE';
      NO_DIR_CHECK='TRUE';
      ALLOW_CONNECT='TRUE';
    'VSS53':
      PIN_NUMBER='(0,0,121)';
      PINUSE='POWER';
      NO_LOAD_CHECK='Both';
      NO_IO_CHECK='Both';
      NO_ASSERT_CHECK='TRUE';
      NO_DIR_CHECK='TRUE';
      ALLOW_CONNECT='TRUE';
    'VSS54':
      PIN_NUMBER='(0,0,123)';
      PINUSE='POWER';
      NO_LOAD_CHECK='Both';
      NO_IO_CHECK='Both';
      NO_ASSERT_CHECK='TRUE';
      NO_DIR_CHECK='TRUE';
      ALLOW_CONNECT='TRUE';
    'VSS55':
      PIN_NUMBER='(0,0,125)';
      PINUSE='POWER';
      NO_LOAD_CHECK='Both';
      NO_IO_CHECK='Both';
      NO_ASSERT_CHECK='TRUE';
      NO_DIR_CHECK='TRUE';
      ALLOW_CONNECT='TRUE';
    'VSS56':
      PIN_NUMBER='(0,0,128)';
      PINUSE='POWER';
      NO_LOAD_CHECK='Both';
      NO_IO_CHECK='Both';
      NO_ASSERT_CHECK='TRUE';
      NO_DIR_CHECK='TRUE';
      ALLOW_CONNECT='TRUE';
    'VSS57':
      PIN_NUMBER='(0,0,130)';
      PINUSE='POWER';
      NO_LOAD_CHECK='Both';
      NO_IO_CHECK='Both';
      NO_ASSERT_CHECK='TRUE';
      NO_DIR_CHECK='TRUE';
      ALLOW_CONNECT='TRUE';
    'VSS59':
      PIN_NUMBER='(0,0,134)';
      PINUSE='POWER';
      NO_LOAD_CHECK='Both';
      NO_IO_CHECK='Both';
      NO_ASSERT_CHECK='TRUE';
      NO_DIR_CHECK='TRUE';
      ALLOW_CONNECT='TRUE';
    'VSS63':
      PIN_NUMBER='(0,0,143)';
      PINUSE='POWER';
      NO_LOAD_CHECK='Both';
      NO_IO_CHECK='Both';
      NO_ASSERT_CHECK='TRUE';
      NO_DIR_CHECK='TRUE';
      ALLOW_CONNECT='TRUE';
    'VSS64':
      PIN_NUMBER='(0,0,151)';
      PINUSE='POWER';
      NO_LOAD_CHECK='Both';
      NO_IO_CHECK='Both';
      NO_ASSERT_CHECK='TRUE';
      NO_DIR_CHECK='TRUE';
      ALLOW_CONNECT='TRUE';
    'VSS65':
      PIN_NUMBER='(0,0,153)';
      PINUSE='POWER';
      NO_LOAD_CHECK='Both';
      NO_IO_CHECK='Both';
      NO_ASSERT_CHECK='TRUE';
      NO_DIR_CHECK='TRUE';
      ALLOW_CONNECT='TRUE';
    'VSS66':
      PIN_NUMBER='(0,0,155)';
      PINUSE='POWER';
      NO_LOAD_CHECK='Both';
      NO_IO_CHECK='Both';
      NO_ASSERT_CHECK='TRUE';
      NO_DIR_CHECK='TRUE';
      ALLOW_CONNECT='TRUE';
    'VSS67':
      PIN_NUMBER='(0,0,158)';
      PINUSE='POWER';
      NO_LOAD_CHECK='Both';
      NO_IO_CHECK='Both';
      NO_ASSERT_CHECK='TRUE';
      NO_DIR_CHECK='TRUE';
      ALLOW_CONNECT='TRUE';
    'VSS68':
      PIN_NUMBER='(0,0,160)';
      PINUSE='POWER';
      NO_LOAD_CHECK='Both';
      NO_IO_CHECK='Both';
      NO_ASSERT_CHECK='TRUE';
      NO_DIR_CHECK='TRUE';
      ALLOW_CONNECT='TRUE';
    'VSS69':
      PIN_NUMBER='(0,0,162)';
      PINUSE='POWER';
      NO_LOAD_CHECK='Both';
      NO_IO_CHECK='Both';
      NO_ASSERT_CHECK='TRUE';
      NO_DIR_CHECK='TRUE';
      ALLOW_CONNECT='TRUE';
    'VSS70':
      PIN_NUMBER='(0,0,164)';
      PINUSE='POWER';
      NO_LOAD_CHECK='Both';
      NO_IO_CHECK='Both';
      NO_ASSERT_CHECK='TRUE';
      NO_DIR_CHECK='TRUE';
      ALLOW_CONNECT='TRUE';
    'VSS71':
      PIN_NUMBER='(0,0,166)';
      PINUSE='POWER';
      NO_LOAD_CHECK='Both';
      NO_IO_CHECK='Both';
      NO_ASSERT_CHECK='TRUE';
      NO_DIR_CHECK='TRUE';
      ALLOW_CONNECT='TRUE';
    'VSS72':
      PIN_NUMBER='(0,0,169)';
      PINUSE='POWER';
      NO_LOAD_CHECK='Both';
      NO_IO_CHECK='Both';
      NO_ASSERT_CHECK='TRUE';
      NO_DIR_CHECK='TRUE';
      ALLOW_CONNECT='TRUE';
    'VSS73':
      PIN_NUMBER='(0,0,171)';
      PINUSE='POWER';
      NO_LOAD_CHECK='Both';
      NO_IO_CHECK='Both';
      NO_ASSERT_CHECK='TRUE';
      NO_DIR_CHECK='TRUE';
      ALLOW_CONNECT='TRUE';
    'VSS74':
      PIN_NUMBER='(0,0,173)';
      PINUSE='POWER';
      NO_LOAD_CHECK='Both';
      NO_IO_CHECK='Both';
      NO_ASSERT_CHECK='TRUE';
      NO_DIR_CHECK='TRUE';
      ALLOW_CONNECT='TRUE';
    'VSS75':
      PIN_NUMBER='(0,0,175)';
      PINUSE='POWER';
      NO_LOAD_CHECK='Both';
      NO_IO_CHECK='Both';
      NO_ASSERT_CHECK='TRUE';
      NO_DIR_CHECK='TRUE';
      ALLOW_CONNECT='TRUE';
    'VSS76':
      PIN_NUMBER='(0,0,177)';
      PINUSE='POWER';
      NO_LOAD_CHECK='Both';
      NO_IO_CHECK='Both';
      NO_ASSERT_CHECK='TRUE';
      NO_DIR_CHECK='TRUE';
      ALLOW_CONNECT='TRUE';
    'VSS77':
      PIN_NUMBER='(0,0,180)';
      PINUSE='POWER';
      NO_LOAD_CHECK='Both';
      NO_IO_CHECK='Both';
      NO_ASSERT_CHECK='TRUE';
      NO_DIR_CHECK='TRUE';
      ALLOW_CONNECT='TRUE';
    'VSS78':
      PIN_NUMBER='(0,0,182)';
      PINUSE='POWER';
      NO_LOAD_CHECK='Both';
      NO_IO_CHECK='Both';
      NO_ASSERT_CHECK='TRUE';
      NO_DIR_CHECK='TRUE';
      ALLOW_CONNECT='TRUE';
    'VSS79':
      PIN_NUMBER='(0,0,184)';
      PINUSE='POWER';
      NO_LOAD_CHECK='Both';
      NO_IO_CHECK='Both';
      NO_ASSERT_CHECK='TRUE';
      NO_DIR_CHECK='TRUE';
      ALLOW_CONNECT='TRUE';
    'VSS80':
      PIN_NUMBER='(0,0,186)';
      PINUSE='POWER';
      NO_LOAD_CHECK='Both';
      NO_IO_CHECK='Both';
      NO_ASSERT_CHECK='TRUE';
      NO_DIR_CHECK='TRUE';
      ALLOW_CONNECT='TRUE';
    'VSS81':
      PIN_NUMBER='(0,0,188)';
      PINUSE='POWER';
      NO_LOAD_CHECK='Both';
      NO_IO_CHECK='Both';
      NO_ASSERT_CHECK='TRUE';
      NO_DIR_CHECK='TRUE';
      ALLOW_CONNECT='TRUE';
    'VSS82':
      PIN_NUMBER='(0,0,191)';
      PINUSE='POWER';
      NO_LOAD_CHECK='Both';
      NO_IO_CHECK='Both';
      NO_ASSERT_CHECK='TRUE';
      NO_DIR_CHECK='TRUE';
      ALLOW_CONNECT='TRUE';
    'VSS83':
      PIN_NUMBER='(0,0,193)';
      PINUSE='POWER';
      NO_LOAD_CHECK='Both';
      NO_IO_CHECK='Both';
      NO_ASSERT_CHECK='TRUE';
      NO_DIR_CHECK='TRUE';
      ALLOW_CONNECT='TRUE';
    'VSS84':
      PIN_NUMBER='(0,0,195)';
      PINUSE='POWER';
      NO_LOAD_CHECK='Both';
      NO_IO_CHECK='Both';
      NO_ASSERT_CHECK='TRUE';
      NO_DIR_CHECK='TRUE';
      ALLOW_CONNECT='TRUE';
    'VSS85':
      PIN_NUMBER='(0,0,197)';
      PINUSE='POWER';
      NO_LOAD_CHECK='Both';
      NO_IO_CHECK='Both';
      NO_ASSERT_CHECK='TRUE';
      NO_DIR_CHECK='TRUE';
      ALLOW_CONNECT='TRUE';
    'VSS86':
      PIN_NUMBER='(0,0,199)';
      PINUSE='POWER';
      NO_LOAD_CHECK='Both';
      NO_IO_CHECK='Both';
      NO_ASSERT_CHECK='TRUE';
      NO_DIR_CHECK='TRUE';
      ALLOW_CONNECT='TRUE';
    'VSS87':
      PIN_NUMBER='(0,0,202)';
      PINUSE='POWER';
      NO_LOAD_CHECK='Both';
      NO_IO_CHECK='Both';
      NO_ASSERT_CHECK='TRUE';
      NO_DIR_CHECK='TRUE';
      ALLOW_CONNECT='TRUE';
    'VSS88':
      PIN_NUMBER='(0,0,204)';
      PINUSE='POWER';
      NO_LOAD_CHECK='Both';
      NO_IO_CHECK='Both';
      NO_ASSERT_CHECK='TRUE';
      NO_DIR_CHECK='TRUE';
      ALLOW_CONNECT='TRUE';
    'VSS89':
      PIN_NUMBER='(0,0,206)';
      PINUSE='POWER';
      NO_LOAD_CHECK='Both';
      NO_IO_CHECK='Both';
      NO_ASSERT_CHECK='TRUE';
      NO_DIR_CHECK='TRUE';
      ALLOW_CONNECT='TRUE';
    'VSS90':
      PIN_NUMBER='(0,0,208)';
      PINUSE='POWER';
      NO_LOAD_CHECK='Both';
      NO_IO_CHECK='Both';
      NO_ASSERT_CHECK='TRUE';
      NO_DIR_CHECK='TRUE';
      ALLOW_CONNECT='TRUE';
    'VSS91':
      PIN_NUMBER='(0,0,210)';
      PINUSE='POWER';
      NO_LOAD_CHECK='Both';
      NO_IO_CHECK='Both';
      NO_ASSERT_CHECK='TRUE';
      NO_DIR_CHECK='TRUE';
      ALLOW_CONNECT='TRUE';
    'VSS92':
      PIN_NUMBER='(0,0,212)';
      PINUSE='POWER';
      NO_LOAD_CHECK='Both';
      NO_IO_CHECK='Both';
      NO_ASSERT_CHECK='TRUE';
      NO_DIR_CHECK='TRUE';
      ALLOW_CONNECT='TRUE';
    'VSS93':
      PIN_NUMBER='(0,0,214)';
      PINUSE='POWER';
      NO_LOAD_CHECK='Both';
      NO_IO_CHECK='Both';
      NO_ASSERT_CHECK='TRUE';
      NO_DIR_CHECK='TRUE';
      ALLOW_CONNECT='TRUE';
    'VSS94':
      PIN_NUMBER='(0,0,216)';
      PINUSE='POWER';
      NO_LOAD_CHECK='Both';
      NO_IO_CHECK='Both';
      NO_ASSERT_CHECK='TRUE';
      NO_DIR_CHECK='TRUE';
      ALLOW_CONNECT='TRUE';
    'VSS95':
      PIN_NUMBER='(0,0,219)';
      PINUSE='POWER';
      NO_LOAD_CHECK='Both';
      NO_IO_CHECK='Both';
      NO_ASSERT_CHECK='TRUE';
      NO_DIR_CHECK='TRUE';
      ALLOW_CONNECT='TRUE';
    'VSS96':
      PIN_NUMBER='(0,0,222)';
      PINUSE='POWER';
      NO_LOAD_CHECK='Both';
      NO_IO_CHECK='Both';
      NO_ASSERT_CHECK='TRUE';
      NO_DIR_CHECK='TRUE';
      ALLOW_CONNECT='TRUE';
    'VSS97':
      PIN_NUMBER='(0,0,224)';
      PINUSE='POWER';
      NO_LOAD_CHECK='Both';
      NO_IO_CHECK='Both';
      NO_ASSERT_CHECK='TRUE';
      NO_DIR_CHECK='TRUE';
      ALLOW_CONNECT='TRUE';
    'VSS98':
      PIN_NUMBER='(0,0,226)';
      PINUSE='POWER';
      NO_LOAD_CHECK='Both';
      NO_IO_CHECK='Both';
      NO_ASSERT_CHECK='TRUE';
      NO_DIR_CHECK='TRUE';
      ALLOW_CONNECT='TRUE';
    'VSS99':
      PIN_NUMBER='(0,0,228)';
      PINUSE='POWER';
      NO_LOAD_CHECK='Both';
      NO_IO_CHECK='Both';
      NO_ASSERT_CHECK='TRUE';
      NO_DIR_CHECK='TRUE';
      ALLOW_CONNECT='TRUE';
    'VSS101':
      PIN_NUMBER='(0,0,233)';
      PINUSE='POWER';
      NO_LOAD_CHECK='Both';
      NO_IO_CHECK='Both';
      NO_ASSERT_CHECK='TRUE';
      NO_DIR_CHECK='TRUE';
      ALLOW_CONNECT='TRUE';
    'VSS103':
      PIN_NUMBER='(0,0,237)';
      PINUSE='POWER';
      NO_LOAD_CHECK='Both';
      NO_IO_CHECK='Both';
      NO_ASSERT_CHECK='TRUE';
      NO_DIR_CHECK='TRUE';
      ALLOW_CONNECT='TRUE';
    'VSS105':
      PIN_NUMBER='(0,0,242)';
      PINUSE='POWER';
      NO_LOAD_CHECK='Both';
      NO_IO_CHECK='Both';
      NO_ASSERT_CHECK='TRUE';
      NO_DIR_CHECK='TRUE';
      ALLOW_CONNECT='TRUE';
    'VSS106':
      PIN_NUMBER='(0,0,244)';
      PINUSE='POWER';
      NO_LOAD_CHECK='Both';
      NO_IO_CHECK='Both';
      NO_ASSERT_CHECK='TRUE';
      NO_DIR_CHECK='TRUE';
      ALLOW_CONNECT='TRUE';
    'VSS107':
      PIN_NUMBER='(0,0,246)';
      PINUSE='POWER';
      NO_LOAD_CHECK='Both';
      NO_IO_CHECK='Both';
      NO_ASSERT_CHECK='TRUE';
      NO_DIR_CHECK='TRUE';
      ALLOW_CONNECT='TRUE';
    'VSS108':
      PIN_NUMBER='(0,0,248)';
      PINUSE='POWER';
      NO_LOAD_CHECK='Both';
      NO_IO_CHECK='Both';
      NO_ASSERT_CHECK='TRUE';
      NO_DIR_CHECK='TRUE';
      ALLOW_CONNECT='TRUE';
    'VSS109':
      PIN_NUMBER='(0,0,251)';
      PINUSE='POWER';
      NO_LOAD_CHECK='Both';
      NO_IO_CHECK='Both';
      NO_ASSERT_CHECK='TRUE';
      NO_DIR_CHECK='TRUE';
      ALLOW_CONNECT='TRUE';
    'VSS110':
      PIN_NUMBER='(0,0,253)';
      PINUSE='POWER';
      NO_LOAD_CHECK='Both';
      NO_IO_CHECK='Both';
      NO_ASSERT_CHECK='TRUE';
      NO_DIR_CHECK='TRUE';
      ALLOW_CONNECT='TRUE';
    'VSS111':
      PIN_NUMBER='(0,0,255)';
      PINUSE='POWER';
      NO_LOAD_CHECK='Both';
      NO_IO_CHECK='Both';
      NO_ASSERT_CHECK='TRUE';
      NO_DIR_CHECK='TRUE';
      ALLOW_CONNECT='TRUE';
    'VSS112':
      PIN_NUMBER='(0,0,257)';
      PINUSE='POWER';
      NO_LOAD_CHECK='Both';
      NO_IO_CHECK='Both';
      NO_ASSERT_CHECK='TRUE';
      NO_DIR_CHECK='TRUE';
      ALLOW_CONNECT='TRUE';
    'VSS113':
      PIN_NUMBER='(0,0,259)';
      PINUSE='POWER';
      NO_LOAD_CHECK='Both';
      NO_IO_CHECK='Both';
      NO_ASSERT_CHECK='TRUE';
      NO_DIR_CHECK='TRUE';
      ALLOW_CONNECT='TRUE';
    'VSS114':
      PIN_NUMBER='(0,0,262)';
      PINUSE='POWER';
      NO_LOAD_CHECK='Both';
      NO_IO_CHECK='Both';
      NO_ASSERT_CHECK='TRUE';
      NO_DIR_CHECK='TRUE';
      ALLOW_CONNECT='TRUE';
    'VSS115':
      PIN_NUMBER='(0,0,264)';
      PINUSE='POWER';
      NO_LOAD_CHECK='Both';
      NO_IO_CHECK='Both';
      NO_ASSERT_CHECK='TRUE';
      NO_DIR_CHECK='TRUE';
      ALLOW_CONNECT='TRUE';
    'VSS116':
      PIN_NUMBER='(0,0,266)';
      PINUSE='POWER';
      NO_LOAD_CHECK='Both';
      NO_IO_CHECK='Both';
      NO_ASSERT_CHECK='TRUE';
      NO_DIR_CHECK='TRUE';
      ALLOW_CONNECT='TRUE';
    'VSS117':
      PIN_NUMBER='(0,0,268)';
      PINUSE='POWER';
      NO_LOAD_CHECK='Both';
      NO_IO_CHECK='Both';
      NO_ASSERT_CHECK='TRUE';
      NO_DIR_CHECK='TRUE';
      ALLOW_CONNECT='TRUE';
    'VSS118':
      PIN_NUMBER='(0,0,270)';
      PINUSE='POWER';
      NO_LOAD_CHECK='Both';
      NO_IO_CHECK='Both';
      NO_ASSERT_CHECK='TRUE';
      NO_DIR_CHECK='TRUE';
      ALLOW_CONNECT='TRUE';
    'VSS119':
      PIN_NUMBER='(0,0,273)';
      PINUSE='POWER';
      NO_LOAD_CHECK='Both';
      NO_IO_CHECK='Both';
      NO_ASSERT_CHECK='TRUE';
      NO_DIR_CHECK='TRUE';
      ALLOW_CONNECT='TRUE';
    'VSS120':
      PIN_NUMBER='(0,0,275)';
      PINUSE='POWER';
      NO_LOAD_CHECK='Both';
      NO_IO_CHECK='Both';
      NO_ASSERT_CHECK='TRUE';
      NO_DIR_CHECK='TRUE';
      ALLOW_CONNECT='TRUE';
    'VSS121':
      PIN_NUMBER='(0,0,277)';
      PINUSE='POWER';
      NO_LOAD_CHECK='Both';
      NO_IO_CHECK='Both';
      NO_ASSERT_CHECK='TRUE';
      NO_DIR_CHECK='TRUE';
      ALLOW_CONNECT='TRUE';
    'VSS122':
      PIN_NUMBER='(0,0,279)';
      PINUSE='POWER';
      NO_LOAD_CHECK='Both';
      NO_IO_CHECK='Both';
      NO_ASSERT_CHECK='TRUE';
      NO_DIR_CHECK='TRUE';
      ALLOW_CONNECT='TRUE';
    'VSS123':
      PIN_NUMBER='(0,0,281)';
      PINUSE='POWER';
      NO_LOAD_CHECK='Both';
      NO_IO_CHECK='Both';
      NO_ASSERT_CHECK='TRUE';
      NO_DIR_CHECK='TRUE';
      ALLOW_CONNECT='TRUE';
    'VSS124':
      PIN_NUMBER='(0,0,284)';
      PINUSE='POWER';
      NO_LOAD_CHECK='Both';
      NO_IO_CHECK='Both';
      NO_ASSERT_CHECK='TRUE';
      NO_DIR_CHECK='TRUE';
      ALLOW_CONNECT='TRUE';
    'VSS125':
      PIN_NUMBER='(0,0,286)';
      PINUSE='POWER';
      NO_LOAD_CHECK='Both';
      NO_IO_CHECK='Both';
      NO_ASSERT_CHECK='TRUE';
      NO_DIR_CHECK='TRUE';
      ALLOW_CONNECT='TRUE';
    'VSS126':
      PIN_NUMBER='(0,0,288)';
      PINUSE='POWER';
      NO_LOAD_CHECK='Both';
      NO_IO_CHECK='Both';
      NO_ASSERT_CHECK='TRUE';
      NO_DIR_CHECK='TRUE';
      ALLOW_CONNECT='TRUE';
    'VIN_BULK0':
      PIN_NUMBER='(0,0,1)';
      PINUSE='POWER';
      NO_LOAD_CHECK='Both';
      NO_IO_CHECK='Both';
      NO_ASSERT_CHECK='TRUE';
      NO_DIR_CHECK='TRUE';
      ALLOW_CONNECT='TRUE';
    'VIN_BULK1':
      PIN_NUMBER='(0,0,145)';
      PINUSE='POWER';
      NO_LOAD_CHECK='Both';
      NO_IO_CHECK='Both';
      NO_ASSERT_CHECK='TRUE';
      NO_DIR_CHECK='TRUE';
      ALLOW_CONNECT='TRUE';
    'VIN_BULK2':
      PIN_NUMBER='(0,0,146)';
      PINUSE='POWER';
      NO_LOAD_CHECK='Both';
      NO_IO_CHECK='Both';
      NO_ASSERT_CHECK='TRUE';
      NO_DIR_CHECK='TRUE';
      ALLOW_CONNECT='TRUE';
    'VSS100':
      PIN_NUMBER='(0,0,230)';
      PINUSE='POWER';
      NO_LOAD_CHECK='Both';
      NO_IO_CHECK='Both';
      NO_ASSERT_CHECK='TRUE';
      NO_DIR_CHECK='TRUE';
      ALLOW_CONNECT='TRUE';
    'VSS102':
      PIN_NUMBER='(0,0,235)';
      PINUSE='POWER';
      NO_LOAD_CHECK='Both';
      NO_IO_CHECK='Both';
      NO_ASSERT_CHECK='TRUE';
      NO_DIR_CHECK='TRUE';
      ALLOW_CONNECT='TRUE';
    'VSS104':
      PIN_NUMBER='(0,0,240)';
      PINUSE='POWER';
      NO_LOAD_CHECK='Both';
      NO_IO_CHECK='Both';
      NO_ASSERT_CHECK='TRUE';
      NO_DIR_CHECK='TRUE';
      ALLOW_CONNECT='TRUE';
    'VSS58':
      PIN_NUMBER='(0,0,132)';
      PINUSE='POWER';
      NO_LOAD_CHECK='Both';
      NO_IO_CHECK='Both';
      NO_ASSERT_CHECK='TRUE';
      NO_DIR_CHECK='TRUE';
      ALLOW_CONNECT='TRUE';
    'VSS60':
      PIN_NUMBER='(0,0,136)';
      PINUSE='POWER';
      NO_LOAD_CHECK='Both';
      NO_IO_CHECK='Both';
      NO_ASSERT_CHECK='TRUE';
      NO_DIR_CHECK='TRUE';
      ALLOW_CONNECT='TRUE';
    'VSS61':
      PIN_NUMBER='(0,0,139)';
      PINUSE='POWER';
      NO_LOAD_CHECK='Both';
      NO_IO_CHECK='Both';
      NO_ASSERT_CHECK='TRUE';
      NO_DIR_CHECK='TRUE';
      ALLOW_CONNECT='TRUE';
    'VSS62':
      PIN_NUMBER='(0,0,141)';
      PINUSE='POWER';
      NO_LOAD_CHECK='Both';
      NO_IO_CHECK='Both';
      NO_ASSERT_CHECK='TRUE';
      NO_DIR_CHECK='TRUE';
      ALLOW_CONNECT='TRUE';
    'G1':
      PIN_NUMBER='(0,0,G1)';
      PINUSE='POWER';
      NO_LOAD_CHECK='Both';
      NO_IO_CHECK='Both';
      NO_ASSERT_CHECK='TRUE';
      NO_DIR_CHECK='TRUE';
      ALLOW_CONNECT='TRUE';
    'G2':
      PIN_NUMBER='(0,0,G2)';
      PINUSE='POWER';
      NO_LOAD_CHECK='Both';
      NO_IO_CHECK='Both';
      NO_ASSERT_CHECK='TRUE';
      NO_DIR_CHECK='TRUE';
      ALLOW_CONNECT='TRUE';
    'G3':
      PIN_NUMBER='(0,0,G3)';
      PINUSE='POWER';
      NO_LOAD_CHECK='Both';
      NO_IO_CHECK='Both';
      NO_ASSERT_CHECK='TRUE';
      NO_DIR_CHECK='TRUE';
      ALLOW_CONNECT='TRUE';
  end_pin;
  body
      PART_NAME='SCONN288_DDR506112002KQ';
      BODY_NAME='SCONN288_DDR506112002KQ';
      PHYS_DES_PREFIX='J';
      CLASS='IO';
      STANDARD='';
      LIFECYCLE='';
      PART_NUMBER='DFHST8FS479';
      JEDEC_TYPE='DDR288S_1-1VXC';
      DESCRIPTION='CONN SMD HS DDR5 288P 2R FS(P0.85,H21.3)';
      MANUFTR='APL';
      MANUF_PN='DDR506112002KQ';
      RD_CMPLS_LVL='EP(V1)';
      CMPLS_LVL='';
      DIP_SMD='';
      FROM_PJ='T6G-JOHN';
      DATA='APL_DDR506112002KQ.pdf';
      FP_ECN='DDR506112002KQ.msg';
      EE_CHECK_LIST='';
      CREATOR='';
      CREATEDAY='20211001';
      PSL='';
      STATUS='';
      ESD_CDM='';
      ESD_HBM='';
      ESD_MM='';
      MSD='';
      PIN_LENGTH_LONG_PIN='105 MILS';
      PIN_LENGTH_SHORT_PIN='105 MILS';
      PARENT_PART_TYPE='SCONN288_DDR506112002KQ';
      PARENT_PPT='SCONN288_DDR506112002KQ';
      PARENT_PPT_PART='SCONN288_DDR506112002KQ-SCONN288_DDR506112002KQ,SMLF,IO,DFHST8FS479';
  end_body;
end_primitive;
primitive 'SCONN56_123276793-SCONN56_1-2327679-3,SMLF,IO,DFHSA';
  pin
    'P12V_B1':
      PIN_NUMBER='(B1)';
      PINUSE='POWER';
      NO_LOAD_CHECK='Both';
      NO_IO_CHECK='Both';
      NO_ASSERT_CHECK='TRUE';
      NO_DIR_CHECK='TRUE';
      ALLOW_CONNECT='TRUE';
    'P12V_B2':
      PIN_NUMBER='(B2)';
      PINUSE='POWER';
      NO_LOAD_CHECK='Both';
      NO_IO_CHECK='Both';
      NO_ASSERT_CHECK='TRUE';
      NO_DIR_CHECK='TRUE';
      ALLOW_CONNECT='TRUE';
    'P12V_B3':
      PIN_NUMBER='(B3)';
      PINUSE='POWER';
      NO_LOAD_CHECK='Both';
      NO_IO_CHECK='Both';
      NO_ASSERT_CHECK='TRUE';
      NO_DIR_CHECK='TRUE';
      ALLOW_CONNECT='TRUE';
    'P12V_B4':
      PIN_NUMBER='(B4)';
      PINUSE='POWER';
      NO_LOAD_CHECK='Both';
      NO_IO_CHECK='Both';
      NO_ASSERT_CHECK='TRUE';
      NO_DIR_CHECK='TRUE';
      ALLOW_CONNECT='TRUE';
    'P12V_B5':
      PIN_NUMBER='(B5)';
      PINUSE='POWER';
      NO_LOAD_CHECK='Both';
      NO_IO_CHECK='Both';
      NO_ASSERT_CHECK='TRUE';
      NO_DIR_CHECK='TRUE';
      ALLOW_CONNECT='TRUE';
    'P12V_B6':
      PIN_NUMBER='(B6)';
      PINUSE='POWER';
      NO_LOAD_CHECK='Both';
      NO_IO_CHECK='Both';
      NO_ASSERT_CHECK='TRUE';
      NO_DIR_CHECK='TRUE';
      ALLOW_CONNECT='TRUE';
    'GND_A1':
      PIN_NUMBER='(A1)';
      PINUSE='POWER';
      NO_LOAD_CHECK='Both';
      NO_IO_CHECK='Both';
      NO_ASSERT_CHECK='TRUE';
      NO_DIR_CHECK='TRUE';
      ALLOW_CONNECT='TRUE';
    'GND_A2':
      PIN_NUMBER='(A2)';
      PINUSE='POWER';
      NO_LOAD_CHECK='Both';
      NO_IO_CHECK='Both';
      NO_ASSERT_CHECK='TRUE';
      NO_DIR_CHECK='TRUE';
      ALLOW_CONNECT='TRUE';
    'GND_A3':
      PIN_NUMBER='(A3)';
      PINUSE='POWER';
      NO_LOAD_CHECK='Both';
      NO_IO_CHECK='Both';
      NO_ASSERT_CHECK='TRUE';
      NO_DIR_CHECK='TRUE';
      ALLOW_CONNECT='TRUE';
    'GND_A4':
      PIN_NUMBER='(A4)';
      PINUSE='POWER';
      NO_LOAD_CHECK='Both';
      NO_IO_CHECK='Both';
      NO_ASSERT_CHECK='TRUE';
      NO_DIR_CHECK='TRUE';
      ALLOW_CONNECT='TRUE';
    'GND_A5':
      PIN_NUMBER='(A5)';
      PINUSE='POWER';
      NO_LOAD_CHECK='Both';
      NO_IO_CHECK='Both';
      NO_ASSERT_CHECK='TRUE';
      NO_DIR_CHECK='TRUE';
      ALLOW_CONNECT='TRUE';
    'GND_A6':
      PIN_NUMBER='(A6)';
      PINUSE='POWER';
      NO_LOAD_CHECK='Both';
      NO_IO_CHECK='Both';
      NO_ASSERT_CHECK='TRUE';
      NO_DIR_CHECK='TRUE';
      ALLOW_CONNECT='TRUE';
    'MFG':
      PIN_NUMBER='(B7)';
      BIDIRECTIONAL='TRUE';
      INPUT_LOAD='(-0.01,0.01)';
      OUTPUT_LOAD='(1.0,-1.0)';
      PINUSE='BI';
    'RFU':
      PIN_NUMBER='(B8)';
      BIDIRECTIONAL='TRUE';
      INPUT_LOAD='(-0.01,0.01)';
      OUTPUT_LOAD='(1.0,-1.0)';
      PINUSE='BI';
    'DUALPORTEN#':
      PIN_NUMBER='(B9)';
      BIDIRECTIONAL='TRUE';
      INPUT_LOAD='(-0.01,0.01)';
      OUTPUT_LOAD='(1.0,-1.0)';
      PINUSE='BI';
    'P3V3_AUX':
      PIN_NUMBER='(B11)';
      PINUSE='POWER';
      NO_LOAD_CHECK='Both';
      NO_IO_CHECK='Both';
      NO_ASSERT_CHECK='TRUE';
      NO_DIR_CHECK='TRUE';
      ALLOW_CONNECT='TRUE';
    'PWRDIS':
      PIN_NUMBER='(B12)';
      BIDIRECTIONAL='TRUE';
      INPUT_LOAD='(-0.01,0.01)';
      OUTPUT_LOAD='(1.0,-1.0)';
      PINUSE='BI';
    'GND_B13':
      PIN_NUMBER='(B13)';
      PINUSE='POWER';
      NO_LOAD_CHECK='Both';
      NO_IO_CHECK='Both';
      NO_ASSERT_CHECK='TRUE';
      NO_DIR_CHECK='TRUE';
      ALLOW_CONNECT='TRUE';
    'GND_B16':
      PIN_NUMBER='(B16)';
      PINUSE='POWER';
      NO_LOAD_CHECK='Both';
      NO_IO_CHECK='Both';
      NO_ASSERT_CHECK='TRUE';
      NO_DIR_CHECK='TRUE';
      ALLOW_CONNECT='TRUE';
    'GND_B19':
      PIN_NUMBER='(B19)';
      PINUSE='POWER';
      NO_LOAD_CHECK='Both';
      NO_IO_CHECK='Both';
      NO_ASSERT_CHECK='TRUE';
      NO_DIR_CHECK='TRUE';
      ALLOW_CONNECT='TRUE';
    'GND_B22':
      PIN_NUMBER='(B22)';
      PINUSE='POWER';
      NO_LOAD_CHECK='Both';
      NO_IO_CHECK='Both';
      NO_ASSERT_CHECK='TRUE';
      NO_DIR_CHECK='TRUE';
      ALLOW_CONNECT='TRUE';
    'GND_B25':
      PIN_NUMBER='(B25)';
      PINUSE='POWER';
      NO_LOAD_CHECK='Both';
      NO_IO_CHECK='Both';
      NO_ASSERT_CHECK='TRUE';
      NO_DIR_CHECK='TRUE';
      ALLOW_CONNECT='TRUE';
    'GND_B28':
      PIN_NUMBER='(B28)';
      PINUSE='POWER';
      NO_LOAD_CHECK='Both';
      NO_IO_CHECK='Both';
      NO_ASSERT_CHECK='TRUE';
      NO_DIR_CHECK='TRUE';
      ALLOW_CONNECT='TRUE';
    'REFCLK_N0':
      PIN_NUMBER='(B14)';
      BIDIRECTIONAL='TRUE';
      INPUT_LOAD='(-0.01,0.01)';
      OUTPUT_LOAD='(1.0,-1.0)';
      PINUSE='BI';
    'REFCLK_P0':
      PIN_NUMBER='(B15)';
      BIDIRECTIONAL='TRUE';
      INPUT_LOAD='(-0.01,0.01)';
      OUTPUT_LOAD='(1.0,-1.0)';
      PINUSE='BI';
    'PET_N0':
      PIN_NUMBER='(B17)';
      BIDIRECTIONAL='TRUE';
      INPUT_LOAD='(-0.01,0.01)';
      OUTPUT_LOAD='(1.0,-1.0)';
      PINUSE='BI';
    'PET_P0':
      PIN_NUMBER='(B18)';
      BIDIRECTIONAL='TRUE';
      INPUT_LOAD='(-0.01,0.01)';
      OUTPUT_LOAD='(1.0,-1.0)';
      PINUSE='BI';
    'PET_N1':
      PIN_NUMBER='(B20)';
      BIDIRECTIONAL='TRUE';
      INPUT_LOAD='(-0.01,0.01)';
      OUTPUT_LOAD='(1.0,-1.0)';
      PINUSE='BI';
    'PET_P1':
      PIN_NUMBER='(B21)';
      BIDIRECTIONAL='TRUE';
      INPUT_LOAD='(-0.01,0.01)';
      OUTPUT_LOAD='(1.0,-1.0)';
      PINUSE='BI';
    'PET_N2':
      PIN_NUMBER='(B23)';
      BIDIRECTIONAL='TRUE';
      INPUT_LOAD='(-0.01,0.01)';
      OUTPUT_LOAD='(1.0,-1.0)';
      PINUSE='BI';
    'PET_P2':
      PIN_NUMBER='(B24)';
      BIDIRECTIONAL='TRUE';
      INPUT_LOAD='(-0.01,0.01)';
      OUTPUT_LOAD='(1.0,-1.0)';
      PINUSE='BI';
    'PET_N3':
      PIN_NUMBER='(B26)';
      BIDIRECTIONAL='TRUE';
      INPUT_LOAD='(-0.01,0.01)';
      OUTPUT_LOAD='(1.0,-1.0)';
      PINUSE='BI';
    'PET_P3':
      PIN_NUMBER='(B27)';
      BIDIRECTIONAL='TRUE';
      INPUT_LOAD='(-0.01,0.01)';
      OUTPUT_LOAD='(1.0,-1.0)';
      PINUSE='BI';
    'SMBCLK':
      PIN_NUMBER='(A7)';
      BIDIRECTIONAL='TRUE';
      INPUT_LOAD='(-0.01,0.01)';
      OUTPUT_LOAD='(1.0,-1.0)';
      PINUSE='BI';
    'SMBDAT':
      PIN_NUMBER='(A8)';
      BIDIRECTIONAL='TRUE';
      INPUT_LOAD='(-0.01,0.01)';
      OUTPUT_LOAD='(1.0,-1.0)';
      PINUSE='BI';
    'SMBRST#':
      PIN_NUMBER='(A9)';
      BIDIRECTIONAL='TRUE';
      INPUT_LOAD='(-0.01,0.01)';
      OUTPUT_LOAD='(1.0,-1.0)';
      PINUSE='BI';
    'LED#_ACTIVITY':
      PIN_NUMBER='(A10)';
      BIDIRECTIONAL='TRUE';
      INPUT_LOAD='(-0.01,0.01)';
      OUTPUT_LOAD='(1.0,-1.0)';
      PINUSE='BI';
    'PERST0#':
      PIN_NUMBER='(B10)';
      BIDIRECTIONAL='TRUE';
      INPUT_LOAD='(-0.01,0.01)';
      OUTPUT_LOAD='(1.0,-1.0)';
      PINUSE='BI';
    'PERST1#_CLKREQ#':
      PIN_NUMBER='(A11)';
      BIDIRECTIONAL='TRUE';
      INPUT_LOAD='(-0.01,0.01)';
      OUTPUT_LOAD='(1.0,-1.0)';
      PINUSE='BI';
    'PRSNT0#':
      PIN_NUMBER='(A12)';
      BIDIRECTIONAL='TRUE';
      INPUT_LOAD='(-0.01,0.01)';
      OUTPUT_LOAD='(1.0,-1.0)';
      PINUSE='BI';
    'GND_A13':
      PIN_NUMBER='(A13)';
      PINUSE='POWER';
      NO_LOAD_CHECK='Both';
      NO_IO_CHECK='Both';
      NO_ASSERT_CHECK='TRUE';
      NO_DIR_CHECK='TRUE';
      ALLOW_CONNECT='TRUE';
    'GND_A16':
      PIN_NUMBER='(A16)';
      PINUSE='POWER';
      NO_LOAD_CHECK='Both';
      NO_IO_CHECK='Both';
      NO_ASSERT_CHECK='TRUE';
      NO_DIR_CHECK='TRUE';
      ALLOW_CONNECT='TRUE';
    'GND_A19':
      PIN_NUMBER='(A19)';
      PINUSE='POWER';
      NO_LOAD_CHECK='Both';
      NO_IO_CHECK='Both';
      NO_ASSERT_CHECK='TRUE';
      NO_DIR_CHECK='TRUE';
      ALLOW_CONNECT='TRUE';
    'GND_A22':
      PIN_NUMBER='(A22)';
      PINUSE='POWER';
      NO_LOAD_CHECK='Both';
      NO_IO_CHECK='Both';
      NO_ASSERT_CHECK='TRUE';
      NO_DIR_CHECK='TRUE';
      ALLOW_CONNECT='TRUE';
    'GND_A25':
      PIN_NUMBER='(A25)';
      PINUSE='POWER';
      NO_LOAD_CHECK='Both';
      NO_IO_CHECK='Both';
      NO_ASSERT_CHECK='TRUE';
      NO_DIR_CHECK='TRUE';
      ALLOW_CONNECT='TRUE';
    'GND_A28':
      PIN_NUMBER='(A28)';
      PINUSE='POWER';
      NO_LOAD_CHECK='Both';
      NO_IO_CHECK='Both';
      NO_ASSERT_CHECK='TRUE';
      NO_DIR_CHECK='TRUE';
      ALLOW_CONNECT='TRUE';
    'REFCLK_N1':
      PIN_NUMBER='(A14)';
      BIDIRECTIONAL='TRUE';
      INPUT_LOAD='(-0.01,0.01)';
      OUTPUT_LOAD='(1.0,-1.0)';
      PINUSE='BI';
    'REFCLK_P1':
      PIN_NUMBER='(A15)';
      BIDIRECTIONAL='TRUE';
      INPUT_LOAD='(-0.01,0.01)';
      OUTPUT_LOAD='(1.0,-1.0)';
      PINUSE='BI';
    'PER_N0':
      PIN_NUMBER='(A17)';
      BIDIRECTIONAL='TRUE';
      INPUT_LOAD='(-0.01,0.01)';
      OUTPUT_LOAD='(1.0,-1.0)';
      PINUSE='BI';
    'PER_P0':
      PIN_NUMBER='(A18)';
      BIDIRECTIONAL='TRUE';
      INPUT_LOAD='(-0.01,0.01)';
      OUTPUT_LOAD='(1.0,-1.0)';
      PINUSE='BI';
    'PER_N1':
      PIN_NUMBER='(A20)';
      BIDIRECTIONAL='TRUE';
      INPUT_LOAD='(-0.01,0.01)';
      OUTPUT_LOAD='(1.0,-1.0)';
      PINUSE='BI';
    'PER_P1':
      PIN_NUMBER='(A21)';
      BIDIRECTIONAL='TRUE';
      INPUT_LOAD='(-0.01,0.01)';
      OUTPUT_LOAD='(1.0,-1.0)';
      PINUSE='BI';
    'PER_N2':
      PIN_NUMBER='(A23)';
      BIDIRECTIONAL='TRUE';
      INPUT_LOAD='(-0.01,0.01)';
      OUTPUT_LOAD='(1.0,-1.0)';
      PINUSE='BI';
    'PER_P2':
      PIN_NUMBER='(A24)';
      BIDIRECTIONAL='TRUE';
      INPUT_LOAD='(-0.01,0.01)';
      OUTPUT_LOAD='(1.0,-1.0)';
      PINUSE='BI';
    'PER_N3':
      PIN_NUMBER='(A26)';
      BIDIRECTIONAL='TRUE';
      INPUT_LOAD='(-0.01,0.01)';
      OUTPUT_LOAD='(1.0,-1.0)';
      PINUSE='BI';
    'PER_P3':
      PIN_NUMBER='(A27)';
      BIDIRECTIONAL='TRUE';
      INPUT_LOAD='(-0.01,0.01)';
      OUTPUT_LOAD='(1.0,-1.0)';
      PINUSE='BI';
    'G2':
      PIN_NUMBER='(G2)';
      PINUSE='POWER';
      NO_LOAD_CHECK='Both';
      NO_IO_CHECK='Both';
      NO_ASSERT_CHECK='TRUE';
      NO_DIR_CHECK='TRUE';
      ALLOW_CONNECT='TRUE';
    'G1':
      PIN_NUMBER='(G1)';
      PINUSE='POWER';
      NO_LOAD_CHECK='Both';
      NO_IO_CHECK='Both';
      NO_ASSERT_CHECK='TRUE';
      NO_DIR_CHECK='TRUE';
      ALLOW_CONNECT='TRUE';
  end_pin;
  body
      PART_NAME='SCONN56_123276793';
      BODY_NAME='SCONN56_123276793';
      PHYS_DES_PREFIX='J';
      CLASS='IO';
      NC_PINS='(H1,H2)';
      STANDARD='';
      LIFECYCLE='';
      PART_NUMBER='DFHS56FS022';
      JEDEC_TYPE='CON_F56S2H4D_P0-6W4-6_LUHXA';
      DESCRIPTION='CONN SMD HOUSING 56P 2R FS(P0.6, H9.25)';
      MANUFTR='TYC';
      MANUF_PN='1-2327679-3';
      RD_CMPLS_LVL='EP(V1)';
      CMPLS_LVL='';
      DIP_SMD='';
      FROM_PJ='S9NS-NICK';
      DATA='TYC_1-2327679-3.pdf';
      FP_ECN='';
      EE_CHECK_LIST='';
      CREATOR='';
      CREATEDAY='20190104';
      PSL='';
      STATUS='';
      ESD_CDM='NA';
      ESD_HBM='NA';
      ESD_MM='NA';
      MSD='NA';
      PIN_LENGTH_LONG_PIN='67 MILS';
      PIN_LENGTH_SHORT_PIN='56 MILS';
      PARENT_PART_TYPE='SCONN56_123276793';
      PARENT_PPT='SCONN56_123276793';
      PARENT_PPT_PART='SCONN56_123276793-SCONN56_1-2327679-3,SMLF,IO,DFHS56FS022';
  end_body;
end_primitive;
primitive 'SCONN75K_APCI0155P004A-SCONN75K_APCI0155-P004A,SMLA';
  pin
    '3.3V_1':
      PIN_NUMBER='(2)';
      PINUSE='POWER';
      NO_LOAD_CHECK='Both';
      NO_IO_CHECK='Both';
      NO_ASSERT_CHECK='TRUE';
      NO_DIR_CHECK='TRUE';
      ALLOW_CONNECT='TRUE';
    '3.3V_2':
      PIN_NUMBER='(4)';
      PINUSE='POWER';
      NO_LOAD_CHECK='Both';
      NO_IO_CHECK='Both';
      NO_ASSERT_CHECK='TRUE';
      NO_DIR_CHECK='TRUE';
      ALLOW_CONNECT='TRUE';
    'DAS_DSS#||LED1#':
      PIN_NUMBER='(10)';
      BIDIRECTIONAL='TRUE';
      INPUT_LOAD='(-0.01,0.01)';
      OUTPUT_LOAD='(1.0,-1.0)';
      PINUSE='BI';
    '3.3V_3':
      PIN_NUMBER='(12)';
      PINUSE='POWER';
      NO_LOAD_CHECK='Both';
      NO_IO_CHECK='Both';
      NO_ASSERT_CHECK='TRUE';
      NO_DIR_CHECK='TRUE';
      ALLOW_CONNECT='TRUE';
    '3.3V_4':
      PIN_NUMBER='(14)';
      PINUSE='POWER';
      NO_LOAD_CHECK='Both';
      NO_IO_CHECK='Both';
      NO_ASSERT_CHECK='TRUE';
      NO_DIR_CHECK='TRUE';
      ALLOW_CONNECT='TRUE';
    '3.3V_5':
      PIN_NUMBER='(16)';
      PINUSE='POWER';
      NO_LOAD_CHECK='Both';
      NO_IO_CHECK='Both';
      NO_ASSERT_CHECK='TRUE';
      NO_DIR_CHECK='TRUE';
      ALLOW_CONNECT='TRUE';
    '3.3V_6':
      PIN_NUMBER='(18)';
      PINUSE='POWER';
      NO_LOAD_CHECK='Both';
      NO_IO_CHECK='Both';
      NO_ASSERT_CHECK='TRUE';
      NO_DIR_CHECK='TRUE';
      ALLOW_CONNECT='TRUE';
    'DEVSLP':
      PIN_NUMBER='(38)';
      INPUT_LOAD='(-0.01,0.01)';
      PINUSE='IN';
    'PERST#':
      PIN_NUMBER='(50)';
      INPUT_LOAD='(-0.01,0.01)';
      PINUSE='IN';
    'CLKREQ#':
      PIN_NUMBER='(52)';
      BIDIRECTIONAL='TRUE';
      INPUT_LOAD='(-0.01,0.01)';
      OUTPUT_LOAD='(1.0,-1.0)';
      PINUSE='BI';
    'PEWAKE#':
      PIN_NUMBER='(54)';
      BIDIRECTIONAL='TRUE';
      INPUT_LOAD='(-0.01,0.01)';
      OUTPUT_LOAD='(1.0,-1.0)';
      PINUSE='BI';
    'NC18':
      PIN_NUMBER='(58)';
      OUTPUT_TYPE='(TS,TS)';
      INPUT_LOAD='(-0.01,0.01)';
      OUTPUT_LOAD='(1.0,-1.0)';
      PINUSE='TRI';
    'SUSCLK':
      PIN_NUMBER='(68)';
      INPUT_LOAD='(-0.01,0.01)';
      PINUSE='IN';
    '3.3V_7':
      PIN_NUMBER='(70)';
      PINUSE='POWER';
      NO_LOAD_CHECK='Both';
      NO_IO_CHECK='Both';
      NO_ASSERT_CHECK='TRUE';
      NO_DIR_CHECK='TRUE';
      ALLOW_CONNECT='TRUE';
    '3.3V_8':
      PIN_NUMBER='(72)';
      PINUSE='POWER';
      NO_LOAD_CHECK='Both';
      NO_IO_CHECK='Both';
      NO_ASSERT_CHECK='TRUE';
      NO_DIR_CHECK='TRUE';
      ALLOW_CONNECT='TRUE';
    '3.3V_9':
      PIN_NUMBER='(74)';
      PINUSE='POWER';
      NO_LOAD_CHECK='Both';
      NO_IO_CHECK='Both';
      NO_ASSERT_CHECK='TRUE';
      NO_DIR_CHECK='TRUE';
      ALLOW_CONNECT='TRUE';
    'PERN0||SATA-B+':
      PIN_NUMBER='(41)';
      BIDIRECTIONAL='TRUE';
      INPUT_LOAD='(-0.01,0.01)';
      OUTPUT_LOAD='(1.0,-1.0)';
      PINUSE='BI';
    'PERP0||SATA-B-':
      PIN_NUMBER='(43)';
      BIDIRECTIONAL='TRUE';
      INPUT_LOAD='(-0.01,0.01)';
      OUTPUT_LOAD='(1.0,-1.0)';
      PINUSE='BI';
    'PETN0||SATA-A-':
      PIN_NUMBER='(47)';
      BIDIRECTIONAL='TRUE';
      INPUT_LOAD='(-0.01,0.01)';
      OUTPUT_LOAD='(1.0,-1.0)';
      PINUSE='BI';
    'PETP0||SATA-A+':
      PIN_NUMBER='(49)';
      BIDIRECTIONAL='TRUE';
      INPUT_LOAD='(-0.01,0.01)';
      OUTPUT_LOAD='(1.0,-1.0)';
      PINUSE='BI';
    'GND11':
      PIN_NUMBER='(57)';
      PINUSE='POWER';
      NO_LOAD_CHECK='Both';
      NO_IO_CHECK='Both';
      NO_ASSERT_CHECK='TRUE';
      NO_DIR_CHECK='TRUE';
      ALLOW_CONNECT='TRUE';
    'NC19':
      PIN_NUMBER='(67)';
      OUTPUT_TYPE='(TS,TS)';
      INPUT_LOAD='(-0.01,0.01)';
      OUTPUT_LOAD='(1.0,-1.0)';
      PINUSE='TRI';
    'PEDET':
      PIN_NUMBER='(69)';
      OUTPUT_LOAD='(1.0,-1.0)';
      PINUSE='OUT';
    'GND12':
      PIN_NUMBER='(71)';
      PINUSE='POWER';
      NO_LOAD_CHECK='Both';
      NO_IO_CHECK='Both';
      NO_ASSERT_CHECK='TRUE';
      NO_DIR_CHECK='TRUE';
      ALLOW_CONNECT='TRUE';
    'GND13':
      PIN_NUMBER='(73)';
      PINUSE='POWER';
      NO_LOAD_CHECK='Both';
      NO_IO_CHECK='Both';
      NO_ASSERT_CHECK='TRUE';
      NO_DIR_CHECK='TRUE';
      ALLOW_CONNECT='TRUE';
    'GND14':
      PIN_NUMBER='(75)';
      PINUSE='POWER';
      NO_LOAD_CHECK='Both';
      NO_IO_CHECK='Both';
      NO_ASSERT_CHECK='TRUE';
      NO_DIR_CHECK='TRUE';
      ALLOW_CONNECT='TRUE';
    'G1':
      PIN_NUMBER='(G1)';
      PINUSE='POWER';
      NO_LOAD_CHECK='Both';
      NO_IO_CHECK='Both';
      NO_ASSERT_CHECK='TRUE';
      NO_DIR_CHECK='TRUE';
      ALLOW_CONNECT='TRUE';
    'G2':
      PIN_NUMBER='(G2)';
      PINUSE='POWER';
      NO_LOAD_CHECK='Both';
      NO_IO_CHECK='Both';
      NO_ASSERT_CHECK='TRUE';
      NO_DIR_CHECK='TRUE';
      ALLOW_CONNECT='TRUE';
    'NC1':
      PIN_NUMBER='(6)';
      OUTPUT_TYPE='(TS,TS)';
      INPUT_LOAD='(-0.01,0.01)';
      OUTPUT_LOAD='(1.0,-1.0)';
      PINUSE='TRI';
    'NC2':
      PIN_NUMBER='(8)';
      OUTPUT_TYPE='(TS,TS)';
      INPUT_LOAD='(-0.01,0.01)';
      OUTPUT_LOAD='(1.0,-1.0)';
      PINUSE='TRI';
    'NC3':
      PIN_NUMBER='(20)';
      OUTPUT_TYPE='(TS,TS)';
      INPUT_LOAD='(-0.01,0.01)';
      OUTPUT_LOAD='(1.0,-1.0)';
      PINUSE='TRI';
    'NC10':
      PIN_NUMBER='(34)';
      OUTPUT_TYPE='(TS,TS)';
      INPUT_LOAD='(-0.01,0.01)';
      OUTPUT_LOAD='(1.0,-1.0)';
      PINUSE='TRI';
    'NC17':
      PIN_NUMBER='(56)';
      OUTPUT_TYPE='(TS,TS)';
      INPUT_LOAD='(-0.01,0.01)';
      OUTPUT_LOAD='(1.0,-1.0)';
      PINUSE='TRI';
    'NC16':
      PIN_NUMBER='(48)';
      OUTPUT_TYPE='(TS,TS)';
      INPUT_LOAD='(-0.01,0.01)';
      OUTPUT_LOAD='(1.0,-1.0)';
      PINUSE='TRI';
    'NC15':
      PIN_NUMBER='(46)';
      OUTPUT_TYPE='(TS,TS)';
      INPUT_LOAD='(-0.01,0.01)';
      OUTPUT_LOAD='(1.0,-1.0)';
      PINUSE='TRI';
    'NC14':
      PIN_NUMBER='(44)';
      OUTPUT_TYPE='(TS,TS)';
      INPUT_LOAD='(-0.01,0.01)';
      OUTPUT_LOAD='(1.0,-1.0)';
      PINUSE='TRI';
    'NC13':
      PIN_NUMBER='(42)';
      OUTPUT_TYPE='(TS,TS)';
      INPUT_LOAD='(-0.01,0.01)';
      OUTPUT_LOAD='(1.0,-1.0)';
      PINUSE='TRI';
    'NC12':
      PIN_NUMBER='(40)';
      OUTPUT_TYPE='(TS,TS)';
      INPUT_LOAD='(-0.01,0.01)';
      OUTPUT_LOAD='(1.0,-1.0)';
      PINUSE='TRI';
    'NC11':
      PIN_NUMBER='(36)';
      OUTPUT_TYPE='(TS,TS)';
      INPUT_LOAD='(-0.01,0.01)';
      OUTPUT_LOAD='(1.0,-1.0)';
      PINUSE='TRI';
    'NC9':
      PIN_NUMBER='(32)';
      OUTPUT_TYPE='(TS,TS)';
      INPUT_LOAD='(-0.01,0.01)';
      OUTPUT_LOAD='(1.0,-1.0)';
      PINUSE='TRI';
    'NC8':
      PIN_NUMBER='(30)';
      OUTPUT_TYPE='(TS,TS)';
      INPUT_LOAD='(-0.01,0.01)';
      OUTPUT_LOAD='(1.0,-1.0)';
      PINUSE='TRI';
    'NC7':
      PIN_NUMBER='(28)';
      OUTPUT_TYPE='(TS,TS)';
      INPUT_LOAD='(-0.01,0.01)';
      OUTPUT_LOAD='(1.0,-1.0)';
      PINUSE='TRI';
    'NC6':
      PIN_NUMBER='(26)';
      OUTPUT_TYPE='(TS,TS)';
      INPUT_LOAD='(-0.01,0.01)';
      OUTPUT_LOAD='(1.0,-1.0)';
      PINUSE='TRI';
    'NC5':
      PIN_NUMBER='(24)';
      OUTPUT_TYPE='(TS,TS)';
      INPUT_LOAD='(-0.01,0.01)';
      OUTPUT_LOAD='(1.0,-1.0)';
      PINUSE='TRI';
    'NC4':
      PIN_NUMBER='(22)';
      OUTPUT_TYPE='(TS,TS)';
      INPUT_LOAD='(-0.01,0.01)';
      OUTPUT_LOAD='(1.0,-1.0)';
      PINUSE='TRI';
    'GND1':
      PIN_NUMBER='(1)';
      PINUSE='POWER';
      NO_LOAD_CHECK='Both';
      NO_IO_CHECK='Both';
      NO_ASSERT_CHECK='TRUE';
      NO_DIR_CHECK='TRUE';
      ALLOW_CONNECT='TRUE';
    'GND2':
      PIN_NUMBER='(3)';
      PINUSE='POWER';
      NO_LOAD_CHECK='Both';
      NO_IO_CHECK='Both';
      NO_ASSERT_CHECK='TRUE';
      NO_DIR_CHECK='TRUE';
      ALLOW_CONNECT='TRUE';
    'GND3':
      PIN_NUMBER='(9)';
      PINUSE='POWER';
      NO_LOAD_CHECK='Both';
      NO_IO_CHECK='Both';
      NO_ASSERT_CHECK='TRUE';
      NO_DIR_CHECK='TRUE';
      ALLOW_CONNECT='TRUE';
    'GND4':
      PIN_NUMBER='(15)';
      PINUSE='POWER';
      NO_LOAD_CHECK='Both';
      NO_IO_CHECK='Both';
      NO_ASSERT_CHECK='TRUE';
      NO_DIR_CHECK='TRUE';
      ALLOW_CONNECT='TRUE';
    'GND5':
      PIN_NUMBER='(21)';
      PINUSE='POWER';
      NO_LOAD_CHECK='Both';
      NO_IO_CHECK='Both';
      NO_ASSERT_CHECK='TRUE';
      NO_DIR_CHECK='TRUE';
      ALLOW_CONNECT='TRUE';
    'GND6':
      PIN_NUMBER='(27)';
      PINUSE='POWER';
      NO_LOAD_CHECK='Both';
      NO_IO_CHECK='Both';
      NO_ASSERT_CHECK='TRUE';
      NO_DIR_CHECK='TRUE';
      ALLOW_CONNECT='TRUE';
    'GND7':
      PIN_NUMBER='(33)';
      PINUSE='POWER';
      NO_LOAD_CHECK='Both';
      NO_IO_CHECK='Both';
      NO_ASSERT_CHECK='TRUE';
      NO_DIR_CHECK='TRUE';
      ALLOW_CONNECT='TRUE';
    'GND8':
      PIN_NUMBER='(39)';
      PINUSE='POWER';
      NO_LOAD_CHECK='Both';
      NO_IO_CHECK='Both';
      NO_ASSERT_CHECK='TRUE';
      NO_DIR_CHECK='TRUE';
      ALLOW_CONNECT='TRUE';
    'GND9':
      PIN_NUMBER='(45)';
      PINUSE='POWER';
      NO_LOAD_CHECK='Both';
      NO_IO_CHECK='Both';
      NO_ASSERT_CHECK='TRUE';
      NO_DIR_CHECK='TRUE';
      ALLOW_CONNECT='TRUE';
    'GND10':
      PIN_NUMBER='(51)';
      PINUSE='POWER';
      NO_LOAD_CHECK='Both';
      NO_IO_CHECK='Both';
      NO_ASSERT_CHECK='TRUE';
      NO_DIR_CHECK='TRUE';
      ALLOW_CONNECT='TRUE';
    'PERN3':
      PIN_NUMBER='(5)';
      BIDIRECTIONAL='TRUE';
      INPUT_LOAD='(-0.01,0.01)';
      OUTPUT_LOAD='(1.0,-1.0)';
      PINUSE='BI';
    'PERP3':
      PIN_NUMBER='(7)';
      BIDIRECTIONAL='TRUE';
      INPUT_LOAD='(-0.01,0.01)';
      OUTPUT_LOAD='(1.0,-1.0)';
      PINUSE='BI';
    'PETN3':
      PIN_NUMBER='(11)';
      BIDIRECTIONAL='TRUE';
      INPUT_LOAD='(-0.01,0.01)';
      OUTPUT_LOAD='(1.0,-1.0)';
      PINUSE='BI';
    'PETP3':
      PIN_NUMBER='(13)';
      BIDIRECTIONAL='TRUE';
      INPUT_LOAD='(-0.01,0.01)';
      OUTPUT_LOAD='(1.0,-1.0)';
      PINUSE='BI';
    'PERN2':
      PIN_NUMBER='(17)';
      BIDIRECTIONAL='TRUE';
      INPUT_LOAD='(-0.01,0.01)';
      OUTPUT_LOAD='(1.0,-1.0)';
      PINUSE='BI';
    'PERP2':
      PIN_NUMBER='(19)';
      BIDIRECTIONAL='TRUE';
      INPUT_LOAD='(-0.01,0.01)';
      OUTPUT_LOAD='(1.0,-1.0)';
      PINUSE='BI';
    'PETN2':
      PIN_NUMBER='(23)';
      BIDIRECTIONAL='TRUE';
      INPUT_LOAD='(-0.01,0.01)';
      OUTPUT_LOAD='(1.0,-1.0)';
      PINUSE='BI';
    'PETP2':
      PIN_NUMBER='(25)';
      BIDIRECTIONAL='TRUE';
      INPUT_LOAD='(-0.01,0.01)';
      OUTPUT_LOAD='(1.0,-1.0)';
      PINUSE='BI';
    'PERN1':
      PIN_NUMBER='(29)';
      BIDIRECTIONAL='TRUE';
      INPUT_LOAD='(-0.01,0.01)';
      OUTPUT_LOAD='(1.0,-1.0)';
      PINUSE='BI';
    'PERP1':
      PIN_NUMBER='(31)';
      BIDIRECTIONAL='TRUE';
      INPUT_LOAD='(-0.01,0.01)';
      OUTPUT_LOAD='(1.0,-1.0)';
      PINUSE='BI';
    'PETN1':
      PIN_NUMBER='(35)';
      BIDIRECTIONAL='TRUE';
      INPUT_LOAD='(-0.01,0.01)';
      OUTPUT_LOAD='(1.0,-1.0)';
      PINUSE='BI';
    'PETP1':
      PIN_NUMBER='(37)';
      BIDIRECTIONAL='TRUE';
      INPUT_LOAD='(-0.01,0.01)';
      OUTPUT_LOAD='(1.0,-1.0)';
      PINUSE='BI';
    'REFCLKN':
      PIN_NUMBER='(53)';
      INPUT_LOAD='(-0.01,0.01)';
      PINUSE='IN';
    'REFCLKP':
      PIN_NUMBER='(55)';
      INPUT_LOAD='(-0.01,0.01)';
      PINUSE='IN';
  end_pin;
  body
      PART_NAME='SCONN75K_APCI0155P004A';
      BODY_NAME='SCONN75K_APCI0155P004A';
      PHYS_DES_PREFIX='J';
      CLASS='IO';
      NC_PINS='(H1,H2)';
      STANDARD='';
      LIFECYCLE='';
      PART_NUMBER='DFHS75FR313';
      JEDEC_TYPE='CON_F67S2H2D2S_P0-5W7-55_LUVXB_H270';
      DESCRIPTION='CONN SMD HOUSING 75P 2R FR(P0.5,H6.7)';
      MANUFTR='LTS';
      MANUF_PN='APCI0155-P004A';
      RD_CMPLS_LVL='EP(V1)';
      CMPLS_LVL='';
      DIP_SMD='';
      FROM_PJ='F08-MARK';
      DATA='LTS_APCI0155-P004A.pdf';
      FP_ECN='';
      EE_CHECK_LIST='';
      CREATOR='';
      CREATEDAY='20160104';
      PSL='';
      STATUS='';
      PARENT_PART_TYPE='SCONN75K_APCI0155P004A';
      PARENT_PPT='SCONN75K_APCI0155P004A';
      PARENT_PPT_PART='SCONN75K_APCI0155P004A-SCONN75K_APCI0155-P004A,SMLF,EMPTY,DFHS75FR313';
  end_body;
end_primitive;
primitive 'SCONN8_G802M0083150RD3HR-SCONN8_G802M0083150RD3HR,A';
  pin
    '1':
      PIN_NUMBER='(1)';
      BIDIRECTIONAL='TRUE';
      INPUT_LOAD='(-0.01,0.01)';
      OUTPUT_LOAD='(1.0,-1.0)';
      PINUSE='BI';
    '2':
      PIN_NUMBER='(2)';
      BIDIRECTIONAL='TRUE';
      INPUT_LOAD='(-0.01,0.01)';
      OUTPUT_LOAD='(1.0,-1.0)';
      PINUSE='BI';
    '3':
      PIN_NUMBER='(3)';
      BIDIRECTIONAL='TRUE';
      INPUT_LOAD='(-0.01,0.01)';
      OUTPUT_LOAD='(1.0,-1.0)';
      PINUSE='BI';
    '4':
      PIN_NUMBER='(4)';
      BIDIRECTIONAL='TRUE';
      INPUT_LOAD='(-0.01,0.01)';
      OUTPUT_LOAD='(1.0,-1.0)';
      PINUSE='BI';
    '5':
      PIN_NUMBER='(5)';
      BIDIRECTIONAL='TRUE';
      INPUT_LOAD='(-0.01,0.01)';
      OUTPUT_LOAD='(1.0,-1.0)';
      PINUSE='BI';
    '6':
      PIN_NUMBER='(6)';
      BIDIRECTIONAL='TRUE';
      INPUT_LOAD='(-0.01,0.01)';
      OUTPUT_LOAD='(1.0,-1.0)';
      PINUSE='BI';
    '7':
      PIN_NUMBER='(7)';
      BIDIRECTIONAL='TRUE';
      INPUT_LOAD='(-0.01,0.01)';
      OUTPUT_LOAD='(1.0,-1.0)';
      PINUSE='BI';
    '8':
      PIN_NUMBER='(8)';
      BIDIRECTIONAL='TRUE';
      INPUT_LOAD='(-0.01,0.01)';
      OUTPUT_LOAD='(1.0,-1.0)';
      PINUSE='BI';
  end_pin;
  body
      PART_NAME='SCONN8_G802M0083150RD3HR';
      BODY_NAME='SCONN8_G802M0083150RD3HR';
      PHYS_DES_PREFIX='J';
      CLASS='IO';
      STANDARD='';
      LIFECYCLE='';
      PART_NUMBER='DFHD08MS385';
      JEDEC_TYPE='HEADER2X4SXN';
      DESCRIPTION='CONN SMD HEADER 8P 2R MS(P1.27,H5.5)';
      MANUFTR='APL';
      MANUF_PN='G802M0083150RD3HR';
      RD_CMPLS_LVL='EP(V1)';
      CMPLS_LVL='';
      DIP_SMD='';
      FROM_PJ='F0TG-CART';
      DATA='APL_G802M0083150RD3HR.pdf';
      FP_ECN='G802M0083150RD3HR.msg';
      EE_CHECK_LIST='';
      CREATOR='';
      CREATEDAY='20220616';
      PSL='';
      STATUS='';
      ESD_CDM='';
      ESD_HBM='';
      ESD_MM='';
      MSD='';
      PIN_LENGTH_LONG_PIN='0 MILS';
      PIN_LENGTH_SHORT_PIN='0 MILS';
      PARENT_PART_TYPE='SCONN8_G802M0083150RD3HR';
      PARENT_PPT='SCONN8_G802M0083150RD3HR';
      PARENT_PPT_PART='SCONN8_G802M0083150RD3HR-SCONN8_G802M0083150RD3HR,SMLF,IO,DFHD08MS385';
  end_body;
end_primitive;
primitive 'SN74AUC2G66DCTR-SN74AUC2G66DCTR,SMLF,IC,AL2G0066C00';
  pin
    '1A':
      PIN_NUMBER='(1)';
      BIDIRECTIONAL='TRUE';
      INPUT_LOAD='(-0.01,0.01)';
      OUTPUT_LOAD='(1.0,-1.0)';
      PINUSE='BI';
    '1C':
      PIN_NUMBER='(7)';
      BIDIRECTIONAL='TRUE';
      INPUT_LOAD='(-0.01,0.01)';
      OUTPUT_LOAD='(1.0,-1.0)';
      PINUSE='BI';
    '2A':
      PIN_NUMBER='(5)';
      BIDIRECTIONAL='TRUE';
      INPUT_LOAD='(-0.01,0.01)';
      OUTPUT_LOAD='(1.0,-1.0)';
      PINUSE='BI';
    '2C':
      PIN_NUMBER='(3)';
      BIDIRECTIONAL='TRUE';
      INPUT_LOAD='(-0.01,0.01)';
      OUTPUT_LOAD='(1.0,-1.0)';
      PINUSE='BI';
    'VCC':
      PIN_NUMBER='(8)';
      PINUSE='POWER';
      NO_LOAD_CHECK='Both';
      NO_IO_CHECK='Both';
      NO_ASSERT_CHECK='TRUE';
      NO_DIR_CHECK='TRUE';
      ALLOW_CONNECT='TRUE';
    'GND':
      PIN_NUMBER='(4)';
      PINUSE='POWER';
      NO_LOAD_CHECK='Both';
      NO_IO_CHECK='Both';
      NO_ASSERT_CHECK='TRUE';
      NO_DIR_CHECK='TRUE';
      ALLOW_CONNECT='TRUE';
    '1B':
      PIN_NUMBER='(2)';
      BIDIRECTIONAL='TRUE';
      INPUT_LOAD='(-0.01,0.01)';
      OUTPUT_LOAD='(1.0,-1.0)';
      PINUSE='BI';
    '2B':
      PIN_NUMBER='(6)';
      BIDIRECTIONAL='TRUE';
      INPUT_LOAD='(-0.01,0.01)';
      OUTPUT_LOAD='(1.0,-1.0)';
      PINUSE='BI';
  end_pin;
  body
      PART_NAME='SN74AUC2G66DCTR';
      BODY_NAME='SN74AUC2G66DCTR';
      PHYS_DES_PREFIX='U';
      CLASS='IC';
      STANDARD='';
      LIFECYCLE='';
      PART_NUMBER='AL2G0066C00';
      JEDEC_TYPE='SSOP8';
      DESCRIPTION='IC OTHER(8P) SN74AUC2G66DCTR (SSOP)';
      MANUFTR='TIC';
      MANUF_PN='SN74AUC2G66DCTR';
      RD_CMPLS_LVL='EP(V1)';
      CMPLS_LVL='EP(V1)';
      FROM_PJ='S2C-WEITING';
      DIP_SMD='';
      DATA='TIC_SN74AUC2G66.pdf';
      EE_CHECK_LIST='';
      FP_ECN='';
      PSL='';
      CREATOR='';
      STATUS='';
      MSD='';
      ESD_CDM='';
      ESD_HBM='';
      ESD_MM='';
      PIN_LENGTH_SHORT_PIN='';
      PIN_LENGTH_LONG_PIN='';
      CREATEDAY='20100429';
      PARENT_PART_TYPE='SN74AUC2G66DCTR';
      PARENT_PPT='SN74AUC2G66DCTR';
      PARENT_PPT_PART='SN74AUC2G66DCTR-SN74AUC2G66DCTR,SMLF,IC,AL2G0066C00';
  end_body;
end_primitive;
primitive 'SN74AVC2T245RSWR-SN74AVC2T245RSWR,SMLF,IC,AL02T245A';
  pin
    'DIR2':
      PIN_NUMBER='(1)';
      INPUT_LOAD='(-0.01,0.01)';
      PINUSE='IN';
    'OE_#':
      PIN_NUMBER='(2)';
      INPUT_LOAD='(-0.01,0.01)';
      PINUSE='IN';
    'GND':
      PIN_NUMBER='(3)';
      PINUSE='POWER';
      NO_LOAD_CHECK='Both';
      NO_IO_CHECK='Both';
      NO_ASSERT_CHECK='TRUE';
      NO_DIR_CHECK='TRUE';
      ALLOW_CONNECT='TRUE';
    'B2':
      PIN_NUMBER='(4)';
      OUTPUT_LOAD='(1.0,-1.0)';
      PINUSE='OUT';
    'B1':
      PIN_NUMBER='(5)';
      OUTPUT_LOAD='(1.0,-1.0)';
      PINUSE='OUT';
    'VCCB':
      PIN_NUMBER='(6)';
      PINUSE='POWER';
      NO_LOAD_CHECK='Both';
      NO_IO_CHECK='Both';
      NO_ASSERT_CHECK='TRUE';
      NO_DIR_CHECK='TRUE';
      ALLOW_CONNECT='TRUE';
    'VCCA':
      PIN_NUMBER='(7)';
      PINUSE='POWER';
      NO_LOAD_CHECK='Both';
      NO_IO_CHECK='Both';
      NO_ASSERT_CHECK='TRUE';
      NO_DIR_CHECK='TRUE';
      ALLOW_CONNECT='TRUE';
    'A1':
      PIN_NUMBER='(8)';
      INPUT_LOAD='(-0.01,0.01)';
      PINUSE='IN';
    'A2':
      PIN_NUMBER='(9)';
      INPUT_LOAD='(-0.01,0.01)';
      PINUSE='IN';
    'DIR1':
      PIN_NUMBER='(10)';
      INPUT_LOAD='(-0.01,0.01)';
      PINUSE='IN';
  end_pin;
  body
      PART_NAME='SN74AVC2T245RSWR';
      BODY_NAME='SN74AVC2T245RSWR';
      PHYS_DES_PREFIX='U';
      CLASS='IC';
      STANDARD='End of Design';
      LIFECYCLE='Comp-Approve';
      PART_NUMBER='AL02T245000';
      JEDEC_TYPE='UQFN10_0-4_1-8X1-4';
      DESCRIPTION='IC OTHER (10P) SN74AVC2T245RSWR(UQFN)';
      MANUFTR='TIC';
      MANUF_PN='SN74AVC2T245RSWR';
      RD_CMPLS_LVL='EP(V1)';
      CMPLS_LVL='EP(V1)';
      FROM_PJ='T6MB-JOSEPH';
      DIP_SMD='';
      DATA='TIC_SN74AVC2T245RSWR.pdf';
      EE_CHECK_LIST='';
      FP_ECN='';
      PSL='';
      CREATOR='';
      STATUS='';
      MSD='';
      ESD_CDM='';
      ESD_HBM='';
      ESD_MM='';
      PIN_LENGTH_SHORT_PIN='';
      PIN_LENGTH_LONG_PIN='';
      CREATEDAY='20160729';
      PARENT_PART_TYPE='SN74AVC2T245RSWR';
      PARENT_PPT='SN74AVC2T245RSWR';
      PARENT_PPT_PART='SN74AVC2T245RSWR-SN74AVC2T245RSWR,SMLF,IC,AL02T245000';
  end_body;
end_primitive;
primitive 'SN74AVC4T774PWR-SN74AVC4T774PWR,SMLF,IC,AL04T774K00';
  pin
    'DIR1':
      PIN_NUMBER='(1)';
      INPUT_LOAD='(-0.01,0.01)';
      PINUSE='IN';
    'DIR2':
      PIN_NUMBER='(2)';
      INPUT_LOAD='(-0.01,0.01)';
      PINUSE='IN';
    'A1':
      PIN_NUMBER='(3)';
      BIDIRECTIONAL='TRUE';
      INPUT_LOAD='(-0.01,0.01)';
      OUTPUT_LOAD='(1.0,-1.0)';
      PINUSE='BI';
    'A2':
      PIN_NUMBER='(4)';
      BIDIRECTIONAL='TRUE';
      INPUT_LOAD='(-0.01,0.01)';
      OUTPUT_LOAD='(1.0,-1.0)';
      PINUSE='BI';
    'A3':
      PIN_NUMBER='(5)';
      BIDIRECTIONAL='TRUE';
      INPUT_LOAD='(-0.01,0.01)';
      OUTPUT_LOAD='(1.0,-1.0)';
      PINUSE='BI';
    'A4':
      PIN_NUMBER='(6)';
      BIDIRECTIONAL='TRUE';
      INPUT_LOAD='(-0.01,0.01)';
      OUTPUT_LOAD='(1.0,-1.0)';
      PINUSE='BI';
    'DIR3':
      PIN_NUMBER='(7)';
      INPUT_LOAD='(-0.01,0.01)';
      PINUSE='IN';
    'DIR4':
      PIN_NUMBER='(8)';
      INPUT_LOAD='(-0.01,0.01)';
      PINUSE='IN';
    'OE':
      PIN_NUMBER='(9)';
      INPUT_LOAD='(-0.01,0.01)';
      PINUSE='IN';
    'GND':
      PIN_NUMBER='(10)';
      PINUSE='POWER';
      NO_LOAD_CHECK='Both';
      NO_IO_CHECK='Both';
      NO_ASSERT_CHECK='TRUE';
      NO_DIR_CHECK='TRUE';
      ALLOW_CONNECT='TRUE';
    'B4':
      PIN_NUMBER='(11)';
      BIDIRECTIONAL='TRUE';
      INPUT_LOAD='(-0.01,0.01)';
      OUTPUT_LOAD='(1.0,-1.0)';
      PINUSE='BI';
    'B3':
      PIN_NUMBER='(12)';
      BIDIRECTIONAL='TRUE';
      INPUT_LOAD='(-0.01,0.01)';
      OUTPUT_LOAD='(1.0,-1.0)';
      PINUSE='BI';
    'B2':
      PIN_NUMBER='(13)';
      BIDIRECTIONAL='TRUE';
      INPUT_LOAD='(-0.01,0.01)';
      OUTPUT_LOAD='(1.0,-1.0)';
      PINUSE='BI';
    'B1':
      PIN_NUMBER='(14)';
      BIDIRECTIONAL='TRUE';
      INPUT_LOAD='(-0.01,0.01)';
      OUTPUT_LOAD='(1.0,-1.0)';
      PINUSE='BI';
    'VCCB':
      PIN_NUMBER='(15)';
      PINUSE='POWER';
      NO_LOAD_CHECK='Both';
      NO_IO_CHECK='Both';
      NO_ASSERT_CHECK='TRUE';
      NO_DIR_CHECK='TRUE';
      ALLOW_CONNECT='TRUE';
    'VCCA':
      PIN_NUMBER='(16)';
      PINUSE='POWER';
      NO_LOAD_CHECK='Both';
      NO_IO_CHECK='Both';
      NO_ASSERT_CHECK='TRUE';
      NO_DIR_CHECK='TRUE';
      ALLOW_CONNECT='TRUE';
  end_pin;
  body
      PART_NAME='SN74AVC4T774PWR';
      BODY_NAME='SN74AVC4T774PWR';
      PHYS_DES_PREFIX='U';
      CLASS='IC';
      STANDARD='';
      LIFECYCLE='';
      PART_NUMBER='AL04T774K00';
      JEDEC_TYPE='TSSOP16XC';
      DESCRIPTION='IC OTHER(16P) SN74AVC4T774PWR(TSSOP)';
      MANUFTR='TIC';
      MANUF_PN='SN74AVC4T774PWR';
      RD_CMPLS_LVL='EP(V1)';
      CMPLS_LVL='EP(V1)';
      FROM_PJ='T6MB-JOSEPH';
      DIP_SMD='';
      DATA='TIC_SN74AVC4T774PWR.pdf';
      EE_CHECK_LIST='';
      FP_ECN='';
      PSL='';
      CREATOR='';
      STATUS='';
      MSD='';
      ESD_CDM='';
      ESD_HBM='';
      ESD_MM='';
      PIN_LENGTH_SHORT_PIN='';
      PIN_LENGTH_LONG_PIN='';
      CREATEDAY='20160810';
      PARENT_PART_TYPE='SN74AVC4T774PWR';
      PARENT_PPT='SN74AVC4T774PWR';
      PARENT_PPT_PART='SN74AVC4T774PWR-SN74AVC4T774PWR,SMLF,IC,AL04T774K00';
  end_body;
end_primitive;
primitive 'SN74LVC1G07DBVR_SMLF-SN74LVC1G07DBVR,EMPTY,AL1G000A';
  pin
    'A':
      PIN_NUMBER='(2)';
      INPUT_LOAD='(-0.01,0.01)';
      PINUSE='IN';
    'Y':
      PIN_NUMBER='(4)';
      OUTPUT_LOAD='(1.0,*)';
      OUTPUT_TYPE='(OC,AND)';
      PINUSE='OCA';
    'NC':
      PIN_NUMBER='(1)';
      INPUT_LOAD='(-0.01,0.01)';
      OUTPUT_LOAD='(1.0,-1.0)';
      OUTPUT_TYPE='(TS,TS)';
      PINUSE='TRI';
    'VCC':
      PIN_NUMBER='(5)';
      PINUSE='POWER';
    'GND':
      PIN_NUMBER='(3)';
      PINUSE='POWER';
  end_pin;
  body
      CLASS='IO';
      PART_NAME='SN74LVC1G07DBVR';
      PHYS_DES_PREFIX='U';
      STANDARD='';
      LIFECYCLE='';
      ENVCOMP='YES';
      PART_NUMBER='AL1G0007024';
      JEDEC_TYPE='SOT23-5';
      DESCRIPTION='IC(5P) SN74LVC1G07DCKR(SOP)';
      HEIGHT='.058IN';
      COMPONENT_TYPE='SMALLSMT';
      LEAD_LENGTH='';
      LPID='';
      DAY='20100819';
      PARENT_PART_TYPE='SN74LVC1G07DBVR';
      PARENT_PPT='SN74LVC1G07DBVR';
      PARENT_PPT_PART='SN74LVC1G07DBVR_SMLF-SN74LVC1G07DBVR,EMPTY,AL1G0007024';
  end_body;
end_primitive;
primitive 'SN74LVC1G07DBVR_SMLF-SN74LVC1G07DBVR,IC,AL1G0007024';
  pin
    'A':
      PIN_NUMBER='(2)';
      INPUT_LOAD='(-0.01,0.01)';
      PINUSE='IN';
    'Y':
      PIN_NUMBER='(4)';
      OUTPUT_LOAD='(1.0,*)';
      OUTPUT_TYPE='(OC,AND)';
      PINUSE='OCA';
    'NC':
      PIN_NUMBER='(1)';
      INPUT_LOAD='(-0.01,0.01)';
      OUTPUT_LOAD='(1.0,-1.0)';
      OUTPUT_TYPE='(TS,TS)';
      PINUSE='TRI';
    'VCC':
      PIN_NUMBER='(5)';
      PINUSE='POWER';
    'GND':
      PIN_NUMBER='(3)';
      PINUSE='POWER';
  end_pin;
  body
      CLASS='IC';
      PART_NAME='SN74LVC1G07DBVR';
      PHYS_DES_PREFIX='U';
      STANDARD='';
      LIFECYCLE='';
      ENVCOMP='YES';
      PART_NUMBER='AL1G0007024';
      JEDEC_TYPE='SOT23-5';
      DESCRIPTION='IC(5P) SN74LVC1G07DCKR(SOP)';
      HEIGHT='.058IN';
      COMPONENT_TYPE='SMALLSMT';
      LEAD_LENGTH='';
      LPID='';
      DAY='20100819';
      PARENT_PART_TYPE='SN74LVC1G07DBVR';
      PARENT_PPT='SN74LVC1G07DBVR';
      PARENT_PPT_PART='SN74LVC1G07DBVR_SMLF-SN74LVC1G07DBVR,IC,AL1G0007024';
  end_body;
end_primitive;
primitive 'SN74LVC1G11DCKR-SN74LVC1G11DCKR,SMLF,IC,ALLVC1G1000';
  pin
    'A':
      PIN_NUMBER='(1)';
      INPUT_LOAD='(-0.01,0.01)';
      PINUSE='IN';
    'B':
      PIN_NUMBER='(3)';
      INPUT_LOAD='(-0.01,0.01)';
      PINUSE='IN';
    'C':
      PIN_NUMBER='(6)';
      INPUT_LOAD='(-0.01,0.01)';
      PINUSE='IN';
    'VCC':
      PIN_NUMBER='(5)';
      PINUSE='POWER';
      NO_LOAD_CHECK='Both';
      NO_IO_CHECK='Both';
      NO_ASSERT_CHECK='TRUE';
      NO_DIR_CHECK='TRUE';
      ALLOW_CONNECT='TRUE';
    'Y':
      PIN_NUMBER='(4)';
      OUTPUT_LOAD='(1.0,-1.0)';
      PINUSE='OUT';
    'GND':
      PIN_NUMBER='(2)';
      PINUSE='POWER';
      NO_LOAD_CHECK='Both';
      NO_IO_CHECK='Both';
      NO_ASSERT_CHECK='TRUE';
      NO_DIR_CHECK='TRUE';
      ALLOW_CONNECT='TRUE';
  end_pin;
  body
      PART_NAME='SN74LVC1G11DCKR';
      BODY_NAME='SN74LVC1G11DCKR';
      PHYS_DES_PREFIX='U';
      CLASS='IC';
      STANDARD='End of Design';
      LIFECYCLE='Comp-Approve';
      PART_NUMBER='ALLVC1G1000';
      JEDEC_TYPE='SC70-6_0-65_2X1-25';
      DESCRIPTION='IC OTHER(6P)SN74LVC1G11DCKR(SC70)';
      MANUFTR='TIC';
      MANUF_PN='SN74LVC1G11DCKR';
      RD_CMPLS_LVL='EP(V1)';
      CMPLS_LVL='EP(V1)';
      FROM_PJ='ALVIN TEMP-OWEN';
      DIP_SMD='';
      DATA='TIC_SN74LVC1G11DCKR.pdf';
      EE_CHECK_LIST='';
      FP_ECN='';
      PSL='';
      CREATOR='';
      STATUS='';
      MSD='NA';
      ESD_CDM='1000V';
      ESD_HBM='2000V';
      ESD_MM='NA';
      PIN_LENGTH_SHORT_PIN='0 MILS';
      PIN_LENGTH_LONG_PIN='0 MILS';
      CREATEDAY='20201022';
      PARENT_PART_TYPE='SN74LVC1G11DCKR';
      PARENT_PPT='SN74LVC1G11DCKR';
      PARENT_PPT_PART='SN74LVC1G11DCKR-SN74LVC1G11DCKR,SMLF,IC,ALLVC1G1000';
  end_body;
end_primitive;
primitive 'SN74LVC2G07DCKR_SMLF-SN74LVC2G07DCKR,IC,AL002G07006';
  pin
    '1A':
      PIN_NUMBER='(1)';
      INPUT_LOAD='(-0.01,0.01)';
      PINUSE='IN';
    '2A':
      PIN_NUMBER='(3)';
      INPUT_LOAD='(-0.01,0.01)';
      PINUSE='IN';
    '1Y':
      PIN_NUMBER='(6)';
      OUTPUT_LOAD='(1.0,-1.0)';
      PINUSE='OUT';
    '2Y':
      PIN_NUMBER='(4)';
      OUTPUT_LOAD='(1.0,-1.0)';
      PINUSE='OUT';
    'GND':
      PIN_NUMBER='(2)';
      PINUSE='POWER';
    'VCC':
      PIN_NUMBER='(5)';
      PINUSE='POWER';
  end_pin;
  body
      CLASS='IC';
      PART_NAME='SN74LVC2G07DCKR';
      PHYS_DES_PREFIX='U';
      STANDARD='End of Design';
      LIFECYCLE='Comp-Approve';
      ENVCOMP='NO';
      PART_NUMBER='AL002G07006';
      JEDEC_TYPE='SC70-6';
      DESCRIPTION='IC(6P) SN74LVC2G07DCKR(SC70-6)';
      HEIGHT='.044IN';
      COMPONENT_TYPE='';
      LEAD_LENGTH='';
      LPID='';
      STATUS='';
      RPL='';
      AML='';
      MANUF_PN='SN74LVC2G07DCKR';
      DAY='20101228';
      PARENT_PART_TYPE='SN74LVC2G07DCKR';
      PARENT_PPT='SN74LVC2G07DCKR';
      PARENT_PPT_PART='SN74LVC2G07DCKR_SMLF-SN74LVC2G07DCKR,IC,AL002G07006';
  end_body;
end_primitive;
primitive 'SS15P3SM386A-SS15P3S-M3/86A,SMLF,IC,BC015P3SZ00';
  pin
    'ANODE_1':
      PIN_NUMBER='(1)';
      INPUT_LOAD='(-0.01,0.01)';
      PINUSE='IN';
    'CATHODE':
      PIN_NUMBER='(K)';
      OUTPUT_LOAD='(1.0,-1.0)';
      PINUSE='OUT';
    'ANODE_2':
      PIN_NUMBER='(2)';
      INPUT_LOAD='(-0.01,0.01)';
      PINUSE='IN';
  end_pin;
  body
      PART_NAME='SS15P3SM386A';
      BODY_NAME='SS15P3SM386A';
      PHYS_DES_PREFIX='D';
      CLASS='IC';
      STANDARD='';
      LIFECYCLE='';
      PART_NUMBER='BC015P3SZ00';
      JEDEC_TYPE='TO277A_4-3X6-1';
      DESCRIPTION='DIODE SMD SS15P3S-M3/86A(30V,15A)';
      MANUFTR='SIL';
      MANUF_PN='SS15P3S-M3/86A';
      RD_CMPLS_LVL='EP(V1)';
      CMPLS_LVL='';
      DIP_SMD='';
      FP_ECN='SS15P3S-M386A.msg';
      FROM_PJ='S9T-YC';
      DATA='SIL_SS15P3S-M386A.pdf';
      EE_CHECK_LIST='';
      STATUS='';
      PSL='';
      PREFERENCE='';
      CREATOR='';
      CREATEDAY='20210421';
      ESD_CDM='';
      ESD_HBM='';
      ESD_MM='';
      MSD='';
      PIN_LENGTH_LONG_PIN='0 MILS';
      PIN_LENGTH_SHORT_PIN='0 MILS';
      PARENT_PART_TYPE='SS15P3SM386A';
      PARENT_PPT='SS15P3SM386A';
      PARENT_PPT_PART='SS15P3SM386A-SS15P3S-M3/86A,SMLF,IC,BC015P3SZ00';
  end_body;
end_primitive;
primitive 'SW20S_DHNF10FQTR-SW20S_DHNF-10F-Q-T/R,SMLF,MECH,DHA';
  pin
    '1':
      PIN_NUMBER='(1)';
      BIDIRECTIONAL='TRUE';
      INPUT_LOAD='(-0.01,0.01)';
      OUTPUT_LOAD='(1.0,-1.0)';
      PINUSE='BI';
    '2':
      PIN_NUMBER='(2)';
      BIDIRECTIONAL='TRUE';
      INPUT_LOAD='(-0.01,0.01)';
      OUTPUT_LOAD='(1.0,-1.0)';
      PINUSE='BI';
    '3':
      PIN_NUMBER='(3)';
      BIDIRECTIONAL='TRUE';
      INPUT_LOAD='(-0.01,0.01)';
      OUTPUT_LOAD='(1.0,-1.0)';
      PINUSE='BI';
    '4':
      PIN_NUMBER='(4)';
      BIDIRECTIONAL='TRUE';
      INPUT_LOAD='(-0.01,0.01)';
      OUTPUT_LOAD='(1.0,-1.0)';
      PINUSE='BI';
    '11':
      PIN_NUMBER='(11)';
      BIDIRECTIONAL='TRUE';
      INPUT_LOAD='(-0.01,0.01)';
      OUTPUT_LOAD='(1.0,-1.0)';
      PINUSE='BI';
    '12':
      PIN_NUMBER='(12)';
      BIDIRECTIONAL='TRUE';
      INPUT_LOAD='(-0.01,0.01)';
      OUTPUT_LOAD='(1.0,-1.0)';
      PINUSE='BI';
    '13':
      PIN_NUMBER='(13)';
      BIDIRECTIONAL='TRUE';
      INPUT_LOAD='(-0.01,0.01)';
      OUTPUT_LOAD='(1.0,-1.0)';
      PINUSE='BI';
    '14':
      PIN_NUMBER='(14)';
      BIDIRECTIONAL='TRUE';
      INPUT_LOAD='(-0.01,0.01)';
      OUTPUT_LOAD='(1.0,-1.0)';
      PINUSE='BI';
    '5':
      PIN_NUMBER='(5)';
      BIDIRECTIONAL='TRUE';
      INPUT_LOAD='(-0.01,0.01)';
      OUTPUT_LOAD='(1.0,-1.0)';
      PINUSE='BI';
    '6':
      PIN_NUMBER='(6)';
      BIDIRECTIONAL='TRUE';
      INPUT_LOAD='(-0.01,0.01)';
      OUTPUT_LOAD='(1.0,-1.0)';
      PINUSE='BI';
    '7':
      PIN_NUMBER='(7)';
      BIDIRECTIONAL='TRUE';
      INPUT_LOAD='(-0.01,0.01)';
      OUTPUT_LOAD='(1.0,-1.0)';
      PINUSE='BI';
    '8':
      PIN_NUMBER='(8)';
      BIDIRECTIONAL='TRUE';
      INPUT_LOAD='(-0.01,0.01)';
      OUTPUT_LOAD='(1.0,-1.0)';
      PINUSE='BI';
    '15':
      PIN_NUMBER='(15)';
      BIDIRECTIONAL='TRUE';
      INPUT_LOAD='(-0.01,0.01)';
      OUTPUT_LOAD='(1.0,-1.0)';
      PINUSE='BI';
    '16':
      PIN_NUMBER='(16)';
      BIDIRECTIONAL='TRUE';
      INPUT_LOAD='(-0.01,0.01)';
      OUTPUT_LOAD='(1.0,-1.0)';
      PINUSE='BI';
    '17':
      PIN_NUMBER='(17)';
      BIDIRECTIONAL='TRUE';
      INPUT_LOAD='(-0.01,0.01)';
      OUTPUT_LOAD='(1.0,-1.0)';
      PINUSE='BI';
    '18':
      PIN_NUMBER='(18)';
      BIDIRECTIONAL='TRUE';
      INPUT_LOAD='(-0.01,0.01)';
      OUTPUT_LOAD='(1.0,-1.0)';
      PINUSE='BI';
    '19':
      PIN_NUMBER='(19)';
      BIDIRECTIONAL='TRUE';
      INPUT_LOAD='(-0.01,0.01)';
      OUTPUT_LOAD='(1.0,-1.0)';
      PINUSE='BI';
    '20':
      PIN_NUMBER='(20)';
      BIDIRECTIONAL='TRUE';
      INPUT_LOAD='(-0.01,0.01)';
      OUTPUT_LOAD='(1.0,-1.0)';
      PINUSE='BI';
    '9':
      PIN_NUMBER='(9)';
      BIDIRECTIONAL='TRUE';
      INPUT_LOAD='(-0.01,0.01)';
      OUTPUT_LOAD='(1.0,-1.0)';
      PINUSE='BI';
    '10':
      PIN_NUMBER='(10)';
      BIDIRECTIONAL='TRUE';
      INPUT_LOAD='(-0.01,0.01)';
      OUTPUT_LOAD='(1.0,-1.0)';
      PINUSE='BI';
  end_pin;
  body
      PART_NAME='SW20S_DHNF10FQTR';
      BODY_NAME='SW20S_DHNF10FQTR';
      PHYS_DES_PREFIX='SW';
      CLASS='IO';
      STANDARD='';
      LIFECYCLE='';
      PART_NUMBER='DHD00010F01';
      JEDEC_TYPE='SW20S_DHNF10FTVTR';
      DESCRIPTION='SWITCH SMD DIP(DHNF-10F-Q-T/R)';
      MANUFTR='DIP';
      MANUF_PN='DHNF-10F-Q-T/R';
      RD_CMPLS_LVL='EP(V1)';
      CMPLS_LVL='';
      DIP_SMD='';
      FROM_PJ='F0C-IVES';
      DATA='DIP_DHNF-10F-Q-TR.pdf';
      FP_ECN='DHNF-10F-Q-TR.msg';
      EE_CHECK_LIST='';
      PSL='';
      PREFERENCE='';
      CREATOR='';
      CREATEDAY='20210119';
      STATUS='';
      ESD_CDM='0';
      ESD_HBM='0';
      ESD_MM='0';
      MSD='NA';
      PIN_LENGTH_LONG_PIN='0 MILS';
      PIN_LENGTH_SHORT_PIN='0 MILS';
      PARENT_PART_TYPE='SW20S_DHNF10FQTR';
      PARENT_PPT='SW20S_DHNF10FQTR';
      PARENT_PPT_PART='SW20S_DHNF10FQTR-SW20S_DHNF-10F-Q-T/R,SMLF,MECH,DHD00010F01';
  end_body;
end_primitive;
primitive 'TCA9548APWR-TCA9548APWR,SMLF,IC,AL009548K02';
  pin
    'A0':
      PIN_NUMBER='(1)';
      INPUT_LOAD='(-0.01,0.01)';
      PINUSE='IN';
    'A1':
      PIN_NUMBER='(2)';
      INPUT_LOAD='(-0.01,0.01)';
      PINUSE='IN';
    'RESET#':
      PIN_NUMBER='(3)';
      INPUT_LOAD='(-0.01,0.01)';
      PINUSE='IN';
    'SD0':
      PIN_NUMBER='(4)';
      BIDIRECTIONAL='TRUE';
      INPUT_LOAD='(-0.01,0.01)';
      OUTPUT_LOAD='(1.0,-1.0)';
      PINUSE='BI';
    'SC0':
      PIN_NUMBER='(5)';
      BIDIRECTIONAL='TRUE';
      INPUT_LOAD='(-0.01,0.01)';
      OUTPUT_LOAD='(1.0,-1.0)';
      PINUSE='BI';
    'SD1':
      PIN_NUMBER='(6)';
      BIDIRECTIONAL='TRUE';
      INPUT_LOAD='(-0.01,0.01)';
      OUTPUT_LOAD='(1.0,-1.0)';
      PINUSE='BI';
    'SC1':
      PIN_NUMBER='(7)';
      BIDIRECTIONAL='TRUE';
      INPUT_LOAD='(-0.01,0.01)';
      OUTPUT_LOAD='(1.0,-1.0)';
      PINUSE='BI';
    'SD2':
      PIN_NUMBER='(8)';
      BIDIRECTIONAL='TRUE';
      INPUT_LOAD='(-0.01,0.01)';
      OUTPUT_LOAD='(1.0,-1.0)';
      PINUSE='BI';
    'SC2':
      PIN_NUMBER='(9)';
      BIDIRECTIONAL='TRUE';
      INPUT_LOAD='(-0.01,0.01)';
      OUTPUT_LOAD='(1.0,-1.0)';
      PINUSE='BI';
    'SD3':
      PIN_NUMBER='(10)';
      BIDIRECTIONAL='TRUE';
      INPUT_LOAD='(-0.01,0.01)';
      OUTPUT_LOAD='(1.0,-1.0)';
      PINUSE='BI';
    'SC3':
      PIN_NUMBER='(11)';
      BIDIRECTIONAL='TRUE';
      INPUT_LOAD='(-0.01,0.01)';
      OUTPUT_LOAD='(1.0,-1.0)';
      PINUSE='BI';
    'GND':
      PIN_NUMBER='(12)';
      PINUSE='POWER';
      NO_LOAD_CHECK='Both';
      NO_IO_CHECK='Both';
      NO_ASSERT_CHECK='TRUE';
      NO_DIR_CHECK='TRUE';
      ALLOW_CONNECT='TRUE';
    'VCC':
      PIN_NUMBER='(24)';
      PINUSE='POWER';
      NO_LOAD_CHECK='Both';
      NO_IO_CHECK='Both';
      NO_ASSERT_CHECK='TRUE';
      NO_DIR_CHECK='TRUE';
      ALLOW_CONNECT='TRUE';
    'SDA':
      PIN_NUMBER='(23)';
      BIDIRECTIONAL='TRUE';
      INPUT_LOAD='(-0.01,0.01)';
      OUTPUT_LOAD='(1.0,-1.0)';
      PINUSE='BI';
    'SCL':
      PIN_NUMBER='(22)';
      BIDIRECTIONAL='TRUE';
      INPUT_LOAD='(-0.01,0.01)';
      OUTPUT_LOAD='(1.0,-1.0)';
      PINUSE='BI';
    'A2':
      PIN_NUMBER='(21)';
      INPUT_LOAD='(-0.01,0.01)';
      PINUSE='IN';
    'SC7':
      PIN_NUMBER='(20)';
      BIDIRECTIONAL='TRUE';
      INPUT_LOAD='(-0.01,0.01)';
      OUTPUT_LOAD='(1.0,-1.0)';
      PINUSE='BI';
    'SD7':
      PIN_NUMBER='(19)';
      BIDIRECTIONAL='TRUE';
      INPUT_LOAD='(-0.01,0.01)';
      OUTPUT_LOAD='(1.0,-1.0)';
      PINUSE='BI';
    'SC6':
      PIN_NUMBER='(18)';
      BIDIRECTIONAL='TRUE';
      INPUT_LOAD='(-0.01,0.01)';
      OUTPUT_LOAD='(1.0,-1.0)';
      PINUSE='BI';
    'SD6':
      PIN_NUMBER='(17)';
      BIDIRECTIONAL='TRUE';
      INPUT_LOAD='(-0.01,0.01)';
      OUTPUT_LOAD='(1.0,-1.0)';
      PINUSE='BI';
    'SC5':
      PIN_NUMBER='(16)';
      BIDIRECTIONAL='TRUE';
      INPUT_LOAD='(-0.01,0.01)';
      OUTPUT_LOAD='(1.0,-1.0)';
      PINUSE='BI';
    'SD5':
      PIN_NUMBER='(15)';
      BIDIRECTIONAL='TRUE';
      INPUT_LOAD='(-0.01,0.01)';
      OUTPUT_LOAD='(1.0,-1.0)';
      PINUSE='BI';
    'SC4':
      PIN_NUMBER='(14)';
      BIDIRECTIONAL='TRUE';
      INPUT_LOAD='(-0.01,0.01)';
      OUTPUT_LOAD='(1.0,-1.0)';
      PINUSE='BI';
    'SD4':
      PIN_NUMBER='(13)';
      BIDIRECTIONAL='TRUE';
      INPUT_LOAD='(-0.01,0.01)';
      OUTPUT_LOAD='(1.0,-1.0)';
      PINUSE='BI';
  end_pin;
  body
      PART_NAME='TCA9548APWR';
      BODY_NAME='TCA9548APWR';
      PHYS_DES_PREFIX='U';
      CLASS='IC';
      STANDARD='';
      LIFECYCLE='';
      PART_NUMBER='AL009548K02';
      JEDEC_TYPE='TSSOP24XA';
      DESCRIPTION='IC OTHER(24P) TCA9548APWR(TSSOP)';
      MANUFTR='TIC';
      MANUF_PN='TCA9548APWR';
      RD_CMPLS_LVL='EP(V1)';
      CMPLS_LVL='EP(V1)';
      FROM_PJ='T6MB-WILLIAM';
      DIP_SMD='';
      DATA='TIC_TCA9548APWR.pdf';
      EE_CHECK_LIST='';
      FP_ECN='';
      PSL='';
      CREATOR='';
      STATUS='';
      MSD='';
      ESD_CDM='';
      ESD_HBM='';
      ESD_MM='';
      PIN_LENGTH_SHORT_PIN='';
      PIN_LENGTH_LONG_PIN='';
      CREATEDAY='20160812';
      PARENT_PART_TYPE='TCA9548APWR';
      PARENT_PPT='TCA9548APWR';
      PARENT_PPT_PART='TCA9548APWR-TCA9548APWR,SMLF,IC,AL009548K02';
  end_body;
end_primitive;
primitive 'TDR_3P_TH2-EMPTY,N_A';
  pin
    'GND':
      PIN_NUMBER='(1)';
      PINUSE='UNSPEC';
      NO_LOAD_CHECK='BOTH';
      NO_IO_CHECK='BOTH';
      ALLOW_CONNECT='TRUE';
    'IO1':
      PIN_NUMBER='(2)';
      PINUSE='UNSPEC';
      NO_LOAD_CHECK='BOTH';
      NO_IO_CHECK='BOTH';
      ALLOW_CONNECT='TRUE';
    'IO2':
      PIN_NUMBER='(3)';
      PINUSE='UNSPEC';
      NO_LOAD_CHECK='BOTH';
      NO_IO_CHECK='BOTH';
      ALLOW_CONNECT='TRUE';
  end_pin;
  body
      PART_NAME='TDR_3P';
      BODY_NAME='TDR_3P';
      PHYS_DES_PREFIX='DB';
      CLASS='IO';
      STANDARD='';
      LIFECYCLE='';
      PART_NUMBER='N_A';
      JEDEC_TYPE='TDR_3P_C85P67_141_100M_Q';
      ALT_SYMBOLS='(TDR_3P_C85P67_141_100M)';
      DESCRIPTION='(USE SYM_2)TDR 3PIN,2X141MIL 1X100MIL P2P';
      HEIGHT='0.00001 IN';
      COMPONENT_TYPE='PSEUDO';
      LPID='';
      SPEED_URL='';
      PARENT_PART_TYPE='TDR_3P_TH2';
      PARENT_PPT='TDR_3P';
      PARENT_PPT_PART='TDR_3P_TH2-EMPTY,N_A';
  end_body;
end_primitive;
primitive 'TPS71715DCKR-TPS71715DCKR,SMLF,EMPTY,AL071715001';
  pin
    'GND':
      PIN_NUMBER='(2)';
      PINUSE='POWER';
      NO_LOAD_CHECK='Both';
      NO_IO_CHECK='Both';
      NO_ASSERT_CHECK='TRUE';
      NO_DIR_CHECK='TRUE';
      ALLOW_CONNECT='TRUE';
    'EN':
      PIN_NUMBER='(3)';
      INPUT_LOAD='(-0.01,0.01)';
      PINUSE='IN';
    'IN':
      PIN_NUMBER='(1)';
      INPUT_LOAD='(-0.01,0.01)';
      PINUSE='IN';
    'NR||FB':
      PIN_NUMBER='(4)';
      OUTPUT_LOAD='(1.0,-1.0)';
      PINUSE='OUT';
    'OUT':
      PIN_NUMBER='(5)';
      OUTPUT_LOAD='(1.0,-1.0)';
      PINUSE='OUT';
  end_pin;
  body
      PART_NAME='TPS71715DCKR';
      BODY_NAME='TPS71715DCKR';
      PHYS_DES_PREFIX='U';
      CLASS='IC';
      STANDARD='';
      LIFECYCLE='';
      PART_NUMBER='AL071715001';
      JEDEC_TYPE='SC70-5XB';
      DESCRIPTION='IC(5P)TPS71715DCKR(SC70)';
      MANUFTR='TIC';
      MANUF_PN='TPS71715DCKR';
      RD_CMPLS_LVL='EP(V1)';
      CMPLS_LVL='SEA';
      FROM_PJ='F0TG-KUO-JU';
      DIP_SMD='';
      DATA='TIC_TPS71715DCKR.pdf';
      EE_CHECK_LIST='';
      FP_ECN='';
      PSL='';
      CREATOR='';
      STATUS='';
      MSD='';
      ESD_CDM='';
      ESD_HBM='';
      ESD_MM='';
      PIN_LENGTH_SHORT_PIN='0 MILS';
      PIN_LENGTH_LONG_PIN='0 MILS';
      CREATEDAY='20220517';
      PARENT_PART_TYPE='TPS71715DCKR';
      PARENT_PPT='TPS71715DCKR';
      PARENT_PPT_PART='TPS71715DCKR-TPS71715DCKR,SMLF,EMPTY,AL071715001';
  end_body;
end_primitive;
primitive 'TP_TDR_4P_FTS_TH-TP_TDR_4P_DIP,EMPTY,TP15';
  pin
    'P1':
      PIN_NUMBER='(2)';
      INPUT_LOAD='(-0.01,0.01)';
      OUTPUT_LOAD='(1.0,-1.0)';
      BIDIRECTIONAL='TRUE';
      PINUSE='BI';
    'P2':
      PIN_NUMBER='(3)';
      INPUT_LOAD='(-0.01,0.01)';
      OUTPUT_LOAD='(1.0,-1.0)';
      BIDIRECTIONAL='TRUE';
      PINUSE='BI';
    'S1':
      PIN_NUMBER='(1)';
      INPUT_LOAD='(-0.01,0.01)';
      OUTPUT_LOAD='(1.0,-1.0)';
      BIDIRECTIONAL='TRUE';
      PINUSE='BI';
    'S2':
      PIN_NUMBER='(4)';
      INPUT_LOAD='(-0.01,0.01)';
      OUTPUT_LOAD='(1.0,-1.0)';
      BIDIRECTIONAL='TRUE';
      PINUSE='BI';
  end_pin;
  body
      CLASS='IO';
      PART_NAME='TP_TDR_4P_FTS';
      PHYS_DES_PREFIX='X';
      STANDARD='';
      LIFECYCLE='';
      ENVCOMP='(Error)';
      PART_NUMBER='N_A';
      JEDEC_TYPE='MPKT4_H025P0200';
      DESCRIPTION='DIFF_TEST_PAD DIP FOR FTS ONLY';
      HEIGHT='0.00001 IN';
      COMPONENT_TYPE='PSEUDO';
      LPID='';
      STATUS='???';
      RPL='???';
      AML='???';
      DAYS='20110210';
      PARENT_PART_TYPE='TP_TDR_4P_FTS';
      PARENT_PPT='TP_TDR_4P_FTS';
      PARENT_PPT_PART='TP_TDR_4P_FTS_TH-TP_TDR_4P_DIP,EMPTY,TP15';
  end_body;
end_primitive;
primitive 'TP_TP-NA,TP26';
  pin
    'TP':
      PIN_NUMBER='(1)';
      PINUSE='UNSPEC';
  end_pin;
  body
      PART_NAME='TP';
      BODY_NAME='TP';
      PHYS_DES_PREFIX='TP';
      CLASS='IO';
      STANDARD='';
      LIFECYCLE='';
      PART_NUMBER='TP26';
      JEDEC_TYPE='TP26';
      HEIGHT='';
      COMPONENT_TYPE='PSEUDO';
      LEAD_LENGTH='';
      PARENT_PART_TYPE='TP';
      PARENT_PPT='TP';
      PARENT_PPT_PART='TP_TP-NA,TP26';
  end_body;
end_primitive;
primitive 'TP_TP-NA,TP30';
  pin
    'TP':
      PIN_NUMBER='(1)';
      PINUSE='UNSPEC';
  end_pin;
  body
      PART_NAME='TP';
      BODY_NAME='TP';
      PHYS_DES_PREFIX='TP';
      CLASS='IO';
      STANDARD='';
      LIFECYCLE='';
      PART_NUMBER='TP30';
      JEDEC_TYPE='TP30';
      HEIGHT='';
      COMPONENT_TYPE='PSEUDO';
      LEAD_LENGTH='';
      PARENT_PART_TYPE='TP';
      PARENT_PPT='TP';
      PARENT_PPT_PART='TP_TP-NA,TP30';
  end_body;
end_primitive;
primitive 'TUSB211IRWBR-TUSB211IRWBR,SMLF,EMPTY,AL000211007';
  pin
    'RSTN':
      PIN_NUMBER='(5)';
      INPUT_LOAD='(-0.01,0.01)';
      PINUSE='IN';
    'D2M':
      PIN_NUMBER='(8)';
      BIDIRECTIONAL='TRUE';
      INPUT_LOAD='(-0.01,0.01)';
      OUTPUT_LOAD='(1.0,-1.0)';
      PINUSE='BI';
    'VREG':
      PIN_NUMBER='(11)';
      OUTPUT_LOAD='(1.0,-1.0)';
      PINUSE='OUT';
    'TEST':
      PIN_NUMBER='(3)';
      INPUT_LOAD='(-0.01,0.01)';
      PINUSE='IN';
    'VCC':
      PIN_NUMBER='(12)';
      PINUSE='POWER';
      NO_LOAD_CHECK='Both';
      NO_IO_CHECK='Both';
      NO_ASSERT_CHECK='TRUE';
      NO_DIR_CHECK='TRUE';
      ALLOW_CONNECT='TRUE';
    'ENA_HS':
      PIN_NUMBER='(9)';
      OUTPUT_LOAD='(1.0,-1.0)';
      PINUSE='OUT';
    'CD':
      PIN_NUMBER='(4)';
      OUTPUT_LOAD='(1.0,-1.0)';
      PINUSE='OUT';
    'D1M':
      PIN_NUMBER='(1)';
      BIDIRECTIONAL='TRUE';
      INPUT_LOAD='(-0.01,0.01)';
      OUTPUT_LOAD='(1.0,-1.0)';
      PINUSE='BI';
    'D1P':
      PIN_NUMBER='(2)';
      BIDIRECTIONAL='TRUE';
      INPUT_LOAD='(-0.01,0.01)';
      OUTPUT_LOAD='(1.0,-1.0)';
      PINUSE='BI';
    'D2P':
      PIN_NUMBER='(7)';
      BIDIRECTIONAL='TRUE';
      INPUT_LOAD='(-0.01,0.01)';
      OUTPUT_LOAD='(1.0,-1.0)';
      PINUSE='BI';
    'EQ':
      PIN_NUMBER='(6)';
      INPUT_LOAD='(-0.01,0.01)';
      PINUSE='IN';
    'GND':
      PIN_NUMBER='(10)';
      PINUSE='POWER';
      NO_LOAD_CHECK='Both';
      NO_IO_CHECK='Both';
      NO_ASSERT_CHECK='TRUE';
      NO_DIR_CHECK='TRUE';
      ALLOW_CONNECT='TRUE';
  end_pin;
  body
      PART_NAME='TUSB211IRWBR';
      BODY_NAME='TUSB211IRWBR';
      PHYS_DES_PREFIX='U';
      CLASS='IC';
      STANDARD='';
      LIFECYCLE='';
      PART_NUMBER='AL000211007';
      JEDEC_TYPE='X2QFN12_0-4_1-6X1-6';
      DESCRIPTION='IC OTHER(12P) TUSB211IRWBR(QFN)';
      MANUFTR='TIC';
      MANUF_PN='TUSB211IRWBR';
      RD_CMPLS_LVL='EP(V1)';
      CMPLS_LVL='';
      FROM_PJ='S5A-ROGER';
      DIP_SMD='';
      DATA='TIC_TUSB211IRWBR.pdf';
      EE_CHECK_LIST='';
      FP_ECN='';
      PSL='';
      CREATOR='';
      STATUS='';
      CREATEDAY='20150203';
      PARENT_PART_TYPE='TUSB211IRWBR';
      PARENT_PPT='TUSB211IRWBR';
      PARENT_PPT_PART='TUSB211IRWBR-TUSB211IRWBR,SMLF,EMPTY,AL000211007';
  end_body;
end_primitive;
primitive 'TUSB8042AIRGCR-TUSB8042AIRGCR,SMLF,IC,AL008042000';
  pin
    'USB_SSRXM_UP':
      PIN_NUMBER='(59,0)';
      INPUT_LOAD='(-0.01,0.01)';
      PINUSE='IN';
    'USB_SSRXM_DN2':
      PIN_NUMBER='(15,0)';
      INPUT_LOAD='(-0.01,0.01)';
      PINUSE='IN';
    'USB_SSRXP_DN2':
      PIN_NUMBER='(14,0)';
      INPUT_LOAD='(-0.01,0.01)';
      PINUSE='IN';
    'USB_SSTXP_DN2':
      PIN_NUMBER='(11,0)';
      OUTPUT_LOAD='(1.0,-1.0)';
      PINUSE='OUT';
    'USB_SSTXM_DN2':
      PIN_NUMBER='(12,0)';
      OUTPUT_LOAD='(1.0,-1.0)';
      PINUSE='OUT';
    'USB_DM_DN3':
      PIN_NUMBER='(18,0)';
      BIDIRECTIONAL='TRUE';
      INPUT_LOAD='(-0.01,0.01)';
      OUTPUT_LOAD='(1.0,-1.0)';
      PINUSE='BI';
    'USB_SSTXM_DN3':
      PIN_NUMBER='(20,0)';
      OUTPUT_LOAD='(1.0,-1.0)';
      PINUSE='OUT';
    'USB_SSTXP_UP':
      PIN_NUMBER='(55,0)';
      OUTPUT_LOAD='(1.0,-1.0)';
      PINUSE='OUT';
    'USB_DM_UP':
      PIN_NUMBER='(54,0)';
      BIDIRECTIONAL='TRUE';
      INPUT_LOAD='(-0.01,0.01)';
      OUTPUT_LOAD='(1.0,-1.0)';
      PINUSE='BI';
    'USB_SSRXM_DN3':
      PIN_NUMBER='(23,0)';
      INPUT_LOAD='(-0.01,0.01)';
      PINUSE='IN';
    'USB_DP_DN4':
      PIN_NUMBER='(24,0)';
      BIDIRECTIONAL='TRUE';
      INPUT_LOAD='(-0.01,0.01)';
      OUTPUT_LOAD='(1.0,-1.0)';
      PINUSE='BI';
    'USB_DP_DN3':
      PIN_NUMBER='(17,0)';
      BIDIRECTIONAL='TRUE';
      INPUT_LOAD='(-0.01,0.01)';
      OUTPUT_LOAD='(1.0,-1.0)';
      PINUSE='BI';
    'USB_SSRXP_UP':
      PIN_NUMBER='(58,0)';
      INPUT_LOAD='(-0.01,0.01)';
      PINUSE='IN';
    'USB_DP_DN2':
      PIN_NUMBER='(9,0)';
      BIDIRECTIONAL='TRUE';
      INPUT_LOAD='(-0.01,0.01)';
      OUTPUT_LOAD='(1.0,-1.0)';
      PINUSE='BI';
    'USB_SSRXP_DN1':
      PIN_NUMBER='(6,0)';
      INPUT_LOAD='(-0.01,0.01)';
      PINUSE='IN';
    'USB_SSTXP_DN4':
      PIN_NUMBER='(26,0)';
      OUTPUT_LOAD='(1.0,-1.0)';
      PINUSE='OUT';
    'USB_DM_DN1':
      PIN_NUMBER='(2,0)';
      BIDIRECTIONAL='TRUE';
      INPUT_LOAD='(-0.01,0.01)';
      OUTPUT_LOAD='(1.0,-1.0)';
      PINUSE='BI';
    'USB_DM_DN4':
      PIN_NUMBER='(25,0)';
      BIDIRECTIONAL='TRUE';
      INPUT_LOAD='(-0.01,0.01)';
      OUTPUT_LOAD='(1.0,-1.0)';
      PINUSE='BI';
    'USB_SSRXP_DN4':
      PIN_NUMBER='(29,0)';
      INPUT_LOAD='(-0.01,0.01)';
      PINUSE='IN';
    'USB_SSRXM_DN4':
      PIN_NUMBER='(30,0)';
      INPUT_LOAD='(-0.01,0.01)';
      PINUSE='IN';
    'USB_SSRXP_DN3':
      PIN_NUMBER='(22,0)';
      INPUT_LOAD='(-0.01,0.01)';
      PINUSE='IN';
    'TH_VSS':
      PIN_NUMBER='(TH,0)';
      PINUSE='POWER';
      NO_LOAD_CHECK='Both';
      NO_IO_CHECK='Both';
      NO_ASSERT_CHECK='TRUE';
      NO_DIR_CHECK='TRUE';
      ALLOW_CONNECT='TRUE';
    'USB_DP_UP':
      PIN_NUMBER='(53,0)';
      BIDIRECTIONAL='TRUE';
      INPUT_LOAD='(-0.01,0.01)';
      OUTPUT_LOAD='(1.0,-1.0)';
      PINUSE='BI';
    'USB_SSTXM_UP':
      PIN_NUMBER='(56,0)';
      OUTPUT_LOAD='(1.0,-1.0)';
      PINUSE='OUT';
    'USB_DP_DN1':
      PIN_NUMBER='(1,0)';
      BIDIRECTIONAL='TRUE';
      INPUT_LOAD='(-0.01,0.01)';
      OUTPUT_LOAD='(1.0,-1.0)';
      PINUSE='BI';
    'USB_SSRXM_DN1':
      PIN_NUMBER='(7,0)';
      INPUT_LOAD='(-0.01,0.01)';
      PINUSE='IN';
    'USB_SSTXP_DN1':
      PIN_NUMBER='(3,0)';
      OUTPUT_LOAD='(1.0,-1.0)';
      PINUSE='OUT';
    'USB_SSTXM_DN1':
      PIN_NUMBER='(4,0)';
      OUTPUT_LOAD='(1.0,-1.0)';
      PINUSE='OUT';
    'USB_DM_DN2':
      PIN_NUMBER='(10,0)';
      BIDIRECTIONAL='TRUE';
      INPUT_LOAD='(-0.01,0.01)';
      OUTPUT_LOAD='(1.0,-1.0)';
      PINUSE='BI';
    'USB_SSTXP_DN3':
      PIN_NUMBER='(19,0)';
      OUTPUT_LOAD='(1.0,-1.0)';
      PINUSE='OUT';
    'USB_SSTXM_DN4':
      PIN_NUMBER='(27,0)';
      OUTPUT_LOAD='(1.0,-1.0)';
      PINUSE='OUT';
    'USB_VBUS':
      PIN_NUMBER='(48,0)';
      INPUT_LOAD='(-0.01,0.01)';
      PINUSE='IN';
    'PWRCTL1||BATEN1':
      PIN_NUMBER='(36,0)';
      BIDIRECTIONAL='TRUE';
      INPUT_LOAD='(-0.01,0.01)';
      OUTPUT_LOAD='(1.0,-1.0)';
      PINUSE='BI';
    'PWRCTL2||BATEN2':
      PIN_NUMBER='(35,0)';
      BIDIRECTIONAL='TRUE';
      INPUT_LOAD='(-0.01,0.01)';
      OUTPUT_LOAD='(1.0,-1.0)';
      PINUSE='BI';
    'PWRCTL3||BATEN3':
      PIN_NUMBER='(33,0)';
      BIDIRECTIONAL='TRUE';
      INPUT_LOAD='(-0.01,0.01)';
      OUTPUT_LOAD='(1.0,-1.0)';
      PINUSE='BI';
    'PWRCTL4||BATEN4':
      PIN_NUMBER='(32,0)';
      BIDIRECTIONAL='TRUE';
      INPUT_LOAD='(-0.01,0.01)';
      OUTPUT_LOAD='(1.0,-1.0)';
      PINUSE='BI';
    'PWRCTL_POL':
      PIN_NUMBER='(41,0)';
      BIDIRECTIONAL='TRUE';
      INPUT_LOAD='(-0.01,0.01)';
      OUTPUT_LOAD='(1.0,-1.0)';
      PINUSE='BI';
    'GRSTZ':
      PIN_NUMBER='(50,0)';
      INPUT_LOAD='(-0.01,0.01)';
      PINUSE='IN';
    'OVERCUR1Z':
      PIN_NUMBER='(46,0)';
      INPUT_LOAD='(-0.01,0.01)';
      PINUSE='IN';
    'OVERCUR2Z':
      PIN_NUMBER='(47,0)';
      INPUT_LOAD='(-0.01,0.01)';
      PINUSE='IN';
    'OVERCUR3Z':
      PIN_NUMBER='(44,0)';
      INPUT_LOAD='(-0.01,0.01)';
      PINUSE='IN';
    'OVERCUR4Z':
      PIN_NUMBER='(43,0)';
      INPUT_LOAD='(-0.01,0.01)';
      PINUSE='IN';
    'TEST':
      PIN_NUMBER='(49,0)';
      INPUT_LOAD='(-0.01,0.01)';
      PINUSE='IN';
    'USB_R1':
      PIN_NUMBER='(64,0)';
      INPUT_LOAD='(-0.01,0.01)';
      PINUSE='IN';
    'NC_1':
      PIN_NUMBER='(60,0)';
      OUTPUT_TYPE='(TS,TS)';
      INPUT_LOAD='(-0.01,0.01)';
      OUTPUT_LOAD='(1.0,-1.0)';
      PINUSE='TRI';
    'VDD_13':
      PIN_NUMBER='(0,13)';
      PINUSE='POWER';
      NO_LOAD_CHECK='Both';
      NO_IO_CHECK='Both';
      NO_ASSERT_CHECK='TRUE';
      NO_DIR_CHECK='TRUE';
      ALLOW_CONNECT='TRUE';
    'SDA||SMBDAT':
      PIN_NUMBER='(0,37)';
      BIDIRECTIONAL='TRUE';
      INPUT_LOAD='(-0.01,0.01)';
      OUTPUT_LOAD='(1.0,-1.0)';
      PINUSE='BI';
    'VDD_28':
      PIN_NUMBER='(0,28)';
      PINUSE='POWER';
      NO_LOAD_CHECK='Both';
      NO_IO_CHECK='Both';
      NO_ASSERT_CHECK='TRUE';
      NO_DIR_CHECK='TRUE';
      ALLOW_CONNECT='TRUE';
    'VDD33_16':
      PIN_NUMBER='(0,16)';
      PINUSE='POWER';
      NO_LOAD_CHECK='Both';
      NO_IO_CHECK='Both';
      NO_ASSERT_CHECK='TRUE';
      NO_DIR_CHECK='TRUE';
      ALLOW_CONNECT='TRUE';
    'VDD33_34':
      PIN_NUMBER='(0,34)';
      PINUSE='POWER';
      NO_LOAD_CHECK='Both';
      NO_IO_CHECK='Both';
      NO_ASSERT_CHECK='TRUE';
      NO_DIR_CHECK='TRUE';
      ALLOW_CONNECT='TRUE';
    'VDD33_52':
      PIN_NUMBER='(0,52)';
      PINUSE='POWER';
      NO_LOAD_CHECK='Both';
      NO_IO_CHECK='Both';
      NO_ASSERT_CHECK='TRUE';
      NO_DIR_CHECK='TRUE';
      ALLOW_CONNECT='TRUE';
    'FULLPWRMGMTZ||FULLAUTOZ||SMBA1||SS_UP':
      PIN_NUMBER='(0,40)';
      BIDIRECTIONAL='TRUE';
      INPUT_LOAD='(-0.01,0.01)';
      OUTPUT_LOAD='(1.0,-1.0)';
      PINUSE='BI';
    'GANGED||SMBA2||HS_UP':
      PIN_NUMBER='(0,42)';
      BIDIRECTIONAL='TRUE';
      INPUT_LOAD='(-0.01,0.01)';
      OUTPUT_LOAD='(1.0,-1.0)';
      PINUSE='BI';
    'SCL||SMBCLK':
      PIN_NUMBER='(0,38)';
      BIDIRECTIONAL='TRUE';
      INPUT_LOAD='(-0.01,0.01)';
      OUTPUT_LOAD='(1.0,-1.0)';
      PINUSE='BI';
    'SMBUSZ||SS_SUSPEND':
      PIN_NUMBER='(0,39)';
      BIDIRECTIONAL='TRUE';
      INPUT_LOAD='(-0.01,0.01)';
      OUTPUT_LOAD='(1.0,-1.0)';
      PINUSE='BI';
    'VDD33_63':
      PIN_NUMBER='(0,63)';
      PINUSE='POWER';
      NO_LOAD_CHECK='Both';
      NO_IO_CHECK='Both';
      NO_ASSERT_CHECK='TRUE';
      NO_DIR_CHECK='TRUE';
      ALLOW_CONNECT='TRUE';
    'VDD_51':
      PIN_NUMBER='(0,51)';
      PINUSE='POWER';
      NO_LOAD_CHECK='Both';
      NO_IO_CHECK='Both';
      NO_ASSERT_CHECK='TRUE';
      NO_DIR_CHECK='TRUE';
      ALLOW_CONNECT='TRUE';
    'AUTOENZ||HS_SUSPEND':
      PIN_NUMBER='(0,45)';
      BIDIRECTIONAL='TRUE';
      INPUT_LOAD='(-0.01,0.01)';
      OUTPUT_LOAD='(1.0,-1.0)';
      PINUSE='BI';
    'VDD_8':
      PIN_NUMBER='(0,8)';
      PINUSE='POWER';
      NO_LOAD_CHECK='Both';
      NO_IO_CHECK='Both';
      NO_ASSERT_CHECK='TRUE';
      NO_DIR_CHECK='TRUE';
      ALLOW_CONNECT='TRUE';
    'VDD_5':
      PIN_NUMBER='(0,5)';
      PINUSE='POWER';
      NO_LOAD_CHECK='Both';
      NO_IO_CHECK='Both';
      NO_ASSERT_CHECK='TRUE';
      NO_DIR_CHECK='TRUE';
      ALLOW_CONNECT='TRUE';
    'VDD_57':
      PIN_NUMBER='(0,57)';
      PINUSE='POWER';
      NO_LOAD_CHECK='Both';
      NO_IO_CHECK='Both';
      NO_ASSERT_CHECK='TRUE';
      NO_DIR_CHECK='TRUE';
      ALLOW_CONNECT='TRUE';
    'VDD_21':
      PIN_NUMBER='(0,21)';
      PINUSE='POWER';
      NO_LOAD_CHECK='Both';
      NO_IO_CHECK='Both';
      NO_ASSERT_CHECK='TRUE';
      NO_DIR_CHECK='TRUE';
      ALLOW_CONNECT='TRUE';
    'VDD_31':
      PIN_NUMBER='(0,31)';
      PINUSE='POWER';
      NO_LOAD_CHECK='Both';
      NO_IO_CHECK='Both';
      NO_ASSERT_CHECK='TRUE';
      NO_DIR_CHECK='TRUE';
      ALLOW_CONNECT='TRUE';
    'XO':
      PIN_NUMBER='(0,61)';
      OUTPUT_LOAD='(1.0,-1.0)';
      PINUSE='OUT';
    'XI':
      PIN_NUMBER='(0,62)';
      INPUT_LOAD='(-0.01,0.01)';
      PINUSE='IN';
  end_pin;
  body
      PART_NAME='TUSB8042AIRGCR';
      BODY_NAME='TUSB8042AIRGCR';
      PHYS_DES_PREFIX='U';
      CLASS='IC';
      STANDARD='';
      LIFECYCLE='';
      PART_NUMBER='AL008042000';
      JEDEC_TYPE='VQFN64_TH_0-5_9X9XC';
      DESCRIPTION='IC OTHER(64P) TUSB8042AIRGCR(VQFN)';
      MANUFTR='TIC';
      MANUF_PN='TUSB8042AIRGCR';
      RD_CMPLS_LVL='EP(V1)';
      CMPLS_LVL='EP(V1)';
      FROM_PJ='F0TG-KUO-JU';
      DIP_SMD='';
      DATA='TIC_TUSB8042AIRGCR.pdf';
      EE_CHECK_LIST='';
      FP_ECN='';
      PSL='';
      CREATOR='';
      STATUS='';
      MSD='';
      ESD_CDM='';
      ESD_HBM='';
      ESD_MM='';
      PIN_LENGTH_SHORT_PIN='0 MILS';
      PIN_LENGTH_LONG_PIN='0 MILS';
      CREATEDAY='20220518';
      PARENT_PART_TYPE='TUSB8042AIRGCR';
      PARENT_PPT='TUSB8042AIRGCR';
      PARENT_PPT_PART='TUSB8042AIRGCR-TUSB8042AIRGCR,SMLF,IC,AL008042000';
  end_body;
end_primitive;
primitive 'ZENER_AC-5.0SMDJ14A,SMLF,IC,BC0MDJ14000';
  pin
    'A':
      PIN_NUMBER='(A)';
      BIDIRECTIONAL='TRUE';
      INPUT_LOAD='(-0.01,0.01)';
      OUTPUT_LOAD='(1.0,-1.0)';
      PINUSE='BI';
    'C':
      PIN_NUMBER='(C)';
      BIDIRECTIONAL='TRUE';
      INPUT_LOAD='(-0.01,0.01)';
      OUTPUT_LOAD='(1.0,-1.0)';
      PINUSE='BI';
  end_pin;
  body
      PART_NAME='ZENER_AC';
      BODY_NAME='ZENER_AC';
      PHYS_DES_PREFIX='D';
      CLASS='IC';
      STANDARD='';
      LIFECYCLE='';
      PART_NUMBER='BC0MDJ14000';
      JEDEC_TYPE='D2723_SMCXC';
      DESCRIPTION='DIODE SMD 5.0SMDJ14A(14V,216A,5000W)';
      MANUFTR='LFI';
      MANUF_PN='5.0SMDJ14A';
      RD_CMPLS_LVL='EP(V1)';
      CMPLS_LVL='';
      DIP_SMD='';
      FP_ECN='';
      FROM_PJ='T2HV-JOHN';
      DATA='LFI_5.0SMDJ14A.pdf';
      EE_CHECK_LIST='';
      STATUS='';
      PSL='';
      PREFERENCE='';
      CREATOR='';
      CREATEDAY='20151225';
      PARENT_PART_TYPE='ZENER_AC';
      PARENT_PPT='ZENER_AC';
      PARENT_PPT_PART='ZENER_AC-5.0SMDJ14A,SMLF,IC,BC0MDJ14000';
  end_body;
end_primitive;
END.
